G04 ================== begin FILE IDENTIFICATION RECORD ==================*
G04 Layout Name:  12432-1.brd*
G04 Film Name:    L1*
G04 File Format:  Gerber RS274X*
G04 File Origin:  Cadence Allegro 16.2-S037*
G04 Origin Date:  Wed Oct 17 10:59:58 2012*
G04 *
G04 Layer:  VIA CLASS/TOP*
G04 Layer:  PIN/TOP*
G04 Layer:  ETCH/TOP*
G04 Layer:  DRAWING FORMAT/LAYER_PCB_STORY*
G04 Layer:  DRAWING FORMAT/LAYER_L1*
G04 *
G04 Offset:    (0.00 0.00)*
G04 Mirror:    No*
G04 Mode:      Positive*
G04 Rotation:  0*
G04 FullContactRelief:  No*
G04 UndefLineWidth:     6.00*
G04 ================== end FILE IDENTIFICATION RECORD ====================*
%FSLAX35Y35*MOIN*%
%IR0*IPPOS*OFA0.00000B0.00000*MIA0B0*SFA1.00000B1.00000*%
%AMMACRO74*
4,1,40,.013,.017,
-.013,.017,
-.013695,.016939,
-.014368,.016759,
-.015,.016464,
-.015571,.016064,
-.016064,.015571,
-.016464,.015,
-.016759,.014368,
-.016939,.013695,
-.017,.013,
-.017,-.013,
-.016939,-.013695,
-.016759,-.014368,
-.016464,-.015,
-.016064,-.015571,
-.015571,-.016064,
-.015,-.016464,
-.014368,-.016759,
-.013695,-.016939,
-.013,-.017,
.013,-.017,
.013695,-.016939,
.014368,-.016759,
.015,-.016464,
.015571,-.016064,
.016064,-.015571,
.016464,-.015,
.016759,-.014368,
.016939,-.013695,
.017,-.013,
.017,.013,
.016939,.013695,
.016759,.014368,
.016464,.015,
.016064,.015571,
.015571,.016064,
.015,.016464,
.014368,.016759,
.013695,.016939,
.013,.017,
0.0*
%
%ADD74MACRO74*%
%AMMACRO42*
4,1,40,.017,-.013,
.017,.013,
.016939,.013695,
.016759,.014368,
.016464,.015,
.016064,.015571,
.015571,.016064,
.015,.016464,
.014368,.016759,
.013695,.016939,
.013,.017,
-.013,.017,
-.013695,.016939,
-.014368,.016759,
-.015,.016464,
-.015571,.016064,
-.016064,.015571,
-.016464,.015,
-.016759,.014368,
-.016939,.013695,
-.017,.013,
-.017,-.013,
-.016939,-.013695,
-.016759,-.014368,
-.016464,-.015,
-.016064,-.015571,
-.015571,-.016064,
-.015,-.016464,
-.014368,-.016759,
-.013695,-.016939,
-.013,-.017,
.013,-.017,
.013695,-.016939,
.014368,-.016759,
.015,-.016464,
.015571,-.016064,
.016064,-.015571,
.016464,-.015,
.016759,-.014368,
.016939,-.013695,
.017,-.013,
0.0*
%
%ADD42MACRO42*%
%ADD43O,.103X.06*%
%ADD94R,.23X.032*%
%ADD57R,.045X.11*%
%AMMACRO90*
4,1,40,-.023,-.013,
-.023,.013,
-.022939,.013695,
-.022759,.014368,
-.022464,.015,
-.022064,.015571,
-.021571,.016064,
-.021,.016464,
-.020368,.016759,
-.019695,.016939,
-.019,.017,
.019,.017,
.019695,.016939,
.020368,.016759,
.021,.016464,
.021571,.016064,
.022064,.015571,
.022464,.015,
.022759,.014368,
.022939,.013695,
.023,.013,
.023,-.013,
.022939,-.013695,
.022759,-.014368,
.022464,-.015,
.022064,-.015571,
.021571,-.016064,
.021,-.016464,
.020368,-.016759,
.019695,-.016939,
.019,-.017,
-.019,-.017,
-.019695,-.016939,
-.020368,-.016759,
-.021,-.016464,
-.021571,-.016064,
-.022064,-.015571,
-.022464,-.015,
-.022759,-.014368,
-.022939,-.013695,
-.023,-.013,
0.0*
%
%ADD90MACRO90*%
%ADD56R,.11X.045*%
%ADD11C,.01*%
%ADD14R,.142X.028*%
%ADD18C,.022*%
%ADD23C,.032*%
%ADD12C,.028*%
%ADD37R,.208X.087*%
%ADD65R,.087X.208*%
%ADD10R,.05X.05*%
%AMMACRO89*
4,1,40,-.019,.017,
.019,.017,
.019695,.016939,
.020368,.016759,
.021,.016464,
.021571,.016064,
.022064,.015571,
.022464,.015,
.022759,.014368,
.022939,.013695,
.023,.013,
.023,-.013,
.022939,-.013695,
.022759,-.014368,
.022464,-.015,
.022064,-.015571,
.021571,-.016064,
.021,-.016464,
.020368,-.016759,
.019695,-.016939,
.019,-.017,
-.019,-.017,
-.019695,-.016939,
-.020368,-.016759,
-.021,-.016464,
-.021571,-.016064,
-.022064,-.015571,
-.022464,-.015,
-.022759,-.014368,
-.022939,-.013695,
-.023,-.013,
-.023,.013,
-.022939,.013695,
-.022759,.014368,
-.022464,.015,
-.022064,.015571,
-.021571,.016064,
-.021,.016464,
-.020368,.016759,
-.019695,.016939,
-.019,.017,
0.0*
%
%ADD89MACRO89*%
%AMMACRO59*
4,1,40,-.007,-.0225,
-.008389,-.022378,
-.009736,-.022018,
-.011,-.021428,
-.012142,-.020628,
-.013128,-.019642,
-.013928,-.0185,
-.014518,-.017236,
-.014878,-.015889,
-.015,-.0145,
-.015,.0145,
-.014878,.015889,
-.014518,.017236,
-.013928,.0185,
-.013128,.019642,
-.012142,.020628,
-.011,.021428,
-.009736,.022018,
-.008389,.022378,
-.007,.0225,
.007,.0225,
.008389,.022378,
.009736,.022018,
.011,.021428,
.012142,.020628,
.013128,.019642,
.013928,.0185,
.014518,.017236,
.014878,.015889,
.015,.0145,
.015,-.0145,
.014878,-.015889,
.014518,-.017236,
.013928,-.0185,
.013128,-.019642,
.012142,-.020628,
.011,-.021428,
.009736,-.022018,
.008389,-.022378,
.007,-.0225,
-.007,-.0225,
0.0*
%
%ADD59MACRO59*%
%AMMACRO92*
4,1,8,.197,-.186,
-.197,-.186,
-.197,.186,
.197,.186,
.197,.00925,
-.059,.00925,
-.059,-.00925,
.197,-.00925,
.197,-.186,
0.0*
%
%ADD92MACRO92*%
%AMMACRO29*
4,1,40,.011,-.007,
.011,.007,
.010939,.007695,
.010759,.008368,
.010464,.009,
.010064,.009571,
.009571,.010064,
.009,.010464,
.008368,.010759,
.007695,.010939,
.007,.011,
-.007,.011,
-.007695,.010939,
-.008368,.010759,
-.009,.010464,
-.009571,.010064,
-.010064,.009571,
-.010464,.009,
-.010759,.008368,
-.010939,.007695,
-.011,.007,
-.011,-.007,
-.010939,-.007695,
-.010759,-.008368,
-.010464,-.009,
-.010064,-.009571,
-.009571,-.010064,
-.009,-.010464,
-.008368,-.010759,
-.007695,-.010939,
-.007,-.011,
.007,-.011,
.007695,-.010939,
.008368,-.010759,
.009,-.010464,
.009571,-.010064,
.010064,-.009571,
.010464,-.009,
.010759,-.008368,
.010939,-.007695,
.011,-.007,
0.0*
%
%ADD29MACRO29*%
%AMMACRO20*
4,1,40,.007,.011,
-.007,.011,
-.007695,.010939,
-.008368,.010759,
-.009,.010464,
-.009571,.010064,
-.010064,.009571,
-.010464,.009,
-.010759,.008368,
-.010939,.007695,
-.011,.007,
-.011,-.007,
-.010939,-.007695,
-.010759,-.008368,
-.010464,-.009,
-.010064,-.009571,
-.009571,-.010064,
-.009,-.010464,
-.008368,-.010759,
-.007695,-.010939,
-.007,-.011,
.007,-.011,
.007695,-.010939,
.008368,-.010759,
.009,-.010464,
.009571,-.010064,
.010064,-.009571,
.010464,-.009,
.010759,-.008368,
.010939,-.007695,
.011,-.007,
.011,.007,
.010939,.007695,
.010759,.008368,
.010464,.009,
.010064,.009571,
.009571,.010064,
.009,.010464,
.008368,.010759,
.007695,.010939,
.007,.011,
0.0*
%
%ADD20MACRO20*%
%AMMACRO31*
4,1,40,-.012,.008,
-.012,-.008,
-.011939,-.008695,
-.011759,-.009368,
-.011464,-.01,
-.011064,-.010571,
-.010571,-.011064,
-.01,-.011464,
-.009368,-.011759,
-.008695,-.011939,
-.008,-.012,
.008,-.012,
.008695,-.011939,
.009368,-.011759,
.01,-.011464,
.010571,-.011064,
.011064,-.010571,
.011464,-.01,
.011759,-.009368,
.011939,-.008695,
.012,-.008,
.012,.008,
.011939,.008695,
.011759,.009368,
.011464,.01,
.011064,.010571,
.010571,.011064,
.01,.011464,
.009368,.011759,
.008695,.011939,
.008,.012,
-.008,.012,
-.008695,.011939,
-.009368,.011759,
-.01,.011464,
-.010571,.011064,
-.011064,.010571,
-.011464,.01,
-.011759,.009368,
-.011939,.008695,
-.012,.008,
0.0*
%
%ADD31MACRO31*%
%AMMACRO61*
4,1,40,.008,.012,
-.008,.012,
-.008695,.011939,
-.009368,.011759,
-.01,.011464,
-.010571,.011064,
-.011064,.010571,
-.011464,.01,
-.011759,.009368,
-.011939,.008695,
-.012,.008,
-.012,-.008,
-.011939,-.008695,
-.011759,-.009368,
-.011464,-.01,
-.011064,-.010571,
-.010571,-.011064,
-.01,-.011464,
-.009368,-.011759,
-.008695,-.011939,
-.008,-.012,
.008,-.012,
.008695,-.011939,
.009368,-.011759,
.01,-.011464,
.010571,-.011064,
.011064,-.010571,
.011464,-.01,
.011759,-.009368,
.011939,-.008695,
.012,-.008,
.012,.008,
.011939,.008695,
.011759,.009368,
.011464,.01,
.011064,.010571,
.010571,.011064,
.01,.011464,
.009368,.011759,
.008695,.011939,
.008,.012,
0.0*
%
%ADD61MACRO61*%
%AMMACRO81*
4,1,6,.0135,-.025,
-.0065,-.005,
-.0135,-.005,
-.0135,.005,
-.0065,.005,
.0135,.025,
.0135,-.025,
0.0*
%
%ADD81MACRO81*%
%AMMACRO78*
4,1,40,-.013,-.017,
.013,-.017,
.013695,-.016939,
.014368,-.016759,
.015,-.016464,
.015571,-.016064,
.016064,-.015571,
.016464,-.015,
.016759,-.014368,
.016939,-.013695,
.017,-.013,
.017,.013,
.016939,.013695,
.016759,.014368,
.016464,.015,
.016064,.015571,
.015571,.016064,
.015,.016464,
.014368,.016759,
.013695,.016939,
.013,.017,
-.013,.017,
-.013695,.016939,
-.014368,.016759,
-.015,.016464,
-.015571,.016064,
-.016064,.015571,
-.016464,.015,
-.016759,.014368,
-.016939,.013695,
-.017,.013,
-.017,-.013,
-.016939,-.013695,
-.016759,-.014368,
-.016464,-.015,
-.016064,-.015571,
-.015571,-.016064,
-.015,-.016464,
-.014368,-.016759,
-.013695,-.016939,
-.013,-.017,
0.0*
%
%ADD78MACRO78*%
%AMMACRO16*
4,1,40,-.017,.013,
-.017,-.013,
-.016939,-.013695,
-.016759,-.014368,
-.016464,-.015,
-.016064,-.015571,
-.015571,-.016064,
-.015,-.016464,
-.014368,-.016759,
-.013695,-.016939,
-.013,-.017,
.013,-.017,
.013695,-.016939,
.014368,-.016759,
.015,-.016464,
.015571,-.016064,
.016064,-.015571,
.016464,-.015,
.016759,-.014368,
.016939,-.013695,
.017,-.013,
.017,.013,
.016939,.013695,
.016759,.014368,
.016464,.015,
.016064,.015571,
.015571,.016064,
.015,.016464,
.014368,.016759,
.013695,.016939,
.013,.017,
-.013,.017,
-.013695,.016939,
-.014368,.016759,
-.015,.016464,
-.015571,.016064,
-.016064,.015571,
-.016464,.015,
-.016759,.014368,
-.016939,.013695,
-.017,.013,
0.0*
%
%ADD16MACRO16*%
%AMMACRO21*
4,1,6,.005,.0135,
.005,.0065,
.025,-.0135,
-.025,-.0135,
-.005,.0065,
-.005,.0135,
.005,.0135,
0.0*
%
%ADD21MACRO21*%
%AMMACRO75*
4,1,20,.0655,-.1095,
.051,-.1095,
.051,-.12,
.0375,-.12,
.0375,-.1095,
-.0375,-.1095,
-.0375,-.12,
-.051,-.12,
-.051,-.1095,
-.0655,-.1095,
-.0655,.1095,
-.051,.1095,
-.051,.12,
-.0375,.12,
-.0375,.1095,
.0375,.1095,
.0375,.12,
.051,.12,
.051,.1095,
.0655,.1095,
.0655,-.1095,
0.0*
%
%ADD75MACRO75*%
%AMMACRO30*
4,1,40,.011,-.007,
.011,.007,
.010939,.007695,
.010759,.008368,
.010464,.009,
.010064,.009571,
.009571,.010064,
.009,.010464,
.008368,.010759,
.007695,.010939,
.007,.011,
-.007,.011,
-.007695,.010939,
-.008368,.010759,
-.009,.010464,
-.009571,.010064,
-.010064,.009571,
-.010464,.009,
-.010759,.008368,
-.010939,.007695,
-.011,.007,
-.011,-.007,
-.010939,-.007695,
-.010759,-.008368,
-.010464,-.009,
-.010064,-.009571,
-.009571,-.010064,
-.009,-.010464,
-.008368,-.010759,
-.007695,-.010939,
-.007,-.011,
.007,-.011,
.007695,-.010939,
.008368,-.010759,
.009,-.010464,
.009571,-.010064,
.010064,-.009571,
.010464,-.009,
.010759,-.008368,
.010939,-.007695,
.011,-.007,
0.0*
%
%ADD30MACRO30*%
%AMMACRO25*
4,1,40,.007,.011,
-.007,.011,
-.007695,.010939,
-.008368,.010759,
-.009,.010464,
-.009571,.010064,
-.010064,.009571,
-.010464,.009,
-.010759,.008368,
-.010939,.007695,
-.011,.007,
-.011,-.007,
-.010939,-.007695,
-.010759,-.008368,
-.010464,-.009,
-.010064,-.009571,
-.009571,-.010064,
-.009,-.010464,
-.008368,-.010759,
-.007695,-.010939,
-.007,-.011,
.007,-.011,
.007695,-.010939,
.008368,-.010759,
.009,-.010464,
.009571,-.010064,
.010064,-.009571,
.010464,-.009,
.010759,-.008368,
.010939,-.007695,
.011,-.007,
.011,.007,
.010939,.007695,
.010759,.008368,
.010464,.009,
.010064,.009571,
.009571,.010064,
.009,.010464,
.008368,.010759,
.007695,.010939,
.007,.011,
0.0*
%
%ADD25MACRO25*%
%AMMACRO19*
4,1,40,-.012,.008,
-.012,-.008,
-.011939,-.008695,
-.011759,-.009368,
-.011464,-.01,
-.011064,-.010571,
-.010571,-.011064,
-.01,-.011464,
-.009368,-.011759,
-.008695,-.011939,
-.008,-.012,
.008,-.012,
.008695,-.011939,
.009368,-.011759,
.01,-.011464,
.010571,-.011064,
.011064,-.010571,
.011464,-.01,
.011759,-.009368,
.011939,-.008695,
.012,-.008,
.012,.008,
.011939,.008695,
.011759,.009368,
.011464,.01,
.011064,.010571,
.010571,.011064,
.01,.011464,
.009368,.011759,
.008695,.011939,
.008,.012,
-.008,.012,
-.008695,.011939,
-.009368,.011759,
-.01,.011464,
-.010571,.011064,
-.011064,.010571,
-.011464,.01,
-.011759,.009368,
-.011939,.008695,
-.012,.008,
0.0*
%
%ADD19MACRO19*%
%AMMACRO60*
4,1,40,.008,.012,
-.008,.012,
-.008695,.011939,
-.009368,.011759,
-.01,.011464,
-.010571,.011064,
-.011064,.010571,
-.011464,.01,
-.011759,.009368,
-.011939,.008695,
-.012,.008,
-.012,-.008,
-.011939,-.008695,
-.011759,-.009368,
-.011464,-.01,
-.011064,-.010571,
-.010571,-.011064,
-.01,-.011464,
-.009368,-.011759,
-.008695,-.011939,
-.008,-.012,
.008,-.012,
.008695,-.011939,
.009368,-.011759,
.01,-.011464,
.010571,-.011064,
.011064,-.010571,
.011464,-.01,
.011759,-.009368,
.011939,-.008695,
.012,-.008,
.012,.008,
.011939,.008695,
.011759,.009368,
.011464,.01,
.011064,.010571,
.010571,.011064,
.01,.011464,
.009368,.011759,
.008695,.011939,
.008,.012,
0.0*
%
%ADD60MACRO60*%
%AMMACRO79*
4,1,40,-.013,-.017,
.013,-.017,
.013695,-.016939,
.014368,-.016759,
.015,-.016464,
.015571,-.016064,
.016064,-.015571,
.016464,-.015,
.016759,-.014368,
.016939,-.013695,
.017,-.013,
.017,.013,
.016939,.013695,
.016759,.014368,
.016464,.015,
.016064,.015571,
.015571,.016064,
.015,.016464,
.014368,.016759,
.013695,.016939,
.013,.017,
-.013,.017,
-.013695,.016939,
-.014368,.016759,
-.015,.016464,
-.015571,.016064,
-.016064,.015571,
-.016464,.015,
-.016759,.014368,
-.016939,.013695,
-.017,.013,
-.017,-.013,
-.016939,-.013695,
-.016759,-.014368,
-.016464,-.015,
-.016064,-.015571,
-.015571,-.016064,
-.015,-.016464,
-.014368,-.016759,
-.013695,-.016939,
-.013,-.017,
0.0*
%
%ADD79MACRO79*%
%AMMACRO17*
4,1,40,-.017,.013,
-.017,-.013,
-.016939,-.013695,
-.016759,-.014368,
-.016464,-.015,
-.016064,-.015571,
-.015571,-.016064,
-.015,-.016464,
-.014368,-.016759,
-.013695,-.016939,
-.013,-.017,
.013,-.017,
.013695,-.016939,
.014368,-.016759,
.015,-.016464,
.015571,-.016064,
.016064,-.015571,
.016464,-.015,
.016759,-.014368,
.016939,-.013695,
.017,-.013,
.017,.013,
.016939,.013695,
.016759,.014368,
.016464,.015,
.016064,.015571,
.015571,.016064,
.015,.016464,
.014368,.016759,
.013695,.016939,
.013,.017,
-.013,.017,
-.013695,.016939,
-.014368,.016759,
-.015,.016464,
-.015571,.016064,
-.016064,.015571,
-.016464,.015,
-.016759,.014368,
-.016939,.013695,
-.017,.013,
0.0*
%
%ADD17MACRO17*%
%ADD91R,.001X.001*%
%ADD84R,.06X.012*%
%ADD88R,.023X.04*%
%ADD85R,.06X.014*%
%ADD76R,.044X.012*%
%ADD54R,.04X.016*%
%ADD64R,.016X.04*%
%ADD62R,.014X.06*%
%ADD35R,.012X.044*%
%ADD26R,.045X.03*%
%ADD50R,.133X.128*%
%ADD63R,.128X.133*%
%ADD45R,.075X.02*%
%ADD86R,.05X.065*%
%ADD46R,.036X.024*%
%ADD38R,.065X.05*%
%ADD49R,.065X.025*%
%ADD13C,.315*%
%ADD71R,.025X.065*%
%ADD68R,.045X.055*%
%ADD55R,.048X.016*%
%ADD72R,.081X.065*%
%ADD53R,.016X.048*%
%ADD36R,.055X.045*%
%ADD93R,.394X.172*%
%ADD58R,.045X.075*%
%ADD52R,.054X.074*%
%ADD47R,.065X.081*%
%ADD44R,.094X.026*%
%ADD83R,.075X.045*%
%ADD70R,.0615X.055*%
%ADD66R,.055X.0615*%
%ADD51R,.09X.095*%
%AMMACRO82*
4,1,40,-.0225,.007,
-.022378,.008389,
-.022018,.009736,
-.021428,.011,
-.020628,.012142,
-.019642,.013128,
-.0185,.013928,
-.017236,.014518,
-.015889,.014878,
-.0145,.015,
.0145,.015,
.015889,.014878,
.017236,.014518,
.0185,.013928,
.019642,.013128,
.020628,.012142,
.021428,.011,
.022018,.009736,
.022378,.008389,
.0225,.007,
.0225,-.007,
.022378,-.008389,
.022018,-.009736,
.021428,-.011,
.020628,-.012142,
.019642,-.013128,
.0185,-.013928,
.017236,-.014518,
.015889,-.014878,
.0145,-.015,
-.0145,-.015,
-.015889,-.014878,
-.017236,-.014518,
-.0185,-.013928,
-.019642,-.013128,
-.020628,-.012142,
-.021428,-.011,
-.022018,-.009736,
-.022378,-.008389,
-.0225,-.007,
-.0225,.007,
0.0*
%
%ADD82MACRO82*%
%AMMACRO77*
4,1,40,.007,.0225,
.008389,.022378,
.009736,.022018,
.011,.021428,
.012142,.020628,
.013128,.019642,
.013928,.0185,
.014518,.017236,
.014878,.015889,
.015,.0145,
.015,-.0145,
.014878,-.015889,
.014518,-.017236,
.013928,-.0185,
.013128,-.019642,
.012142,-.020628,
.011,-.021428,
.009736,-.022018,
.008389,-.022378,
.007,-.0225,
-.007,-.0225,
-.008389,-.022378,
-.009736,-.022018,
-.011,-.021428,
-.012142,-.020628,
-.013128,-.019642,
-.013928,-.0185,
-.014518,-.017236,
-.014878,-.015889,
-.015,-.0145,
-.015,.0145,
-.014878,.015889,
-.014518,.017236,
-.013928,.0185,
-.013128,.019642,
-.012142,.020628,
-.011,.021428,
-.009736,.022018,
-.008389,.022378,
-.007,.0225,
.007,.0225,
0.0*
%
%ADD77MACRO77*%
%ADD48R,.095X.09*%
%ADD69R,.06176X.055*%
%ADD67R,.055X.06176*%
%ADD87R,.089X.059*%
%AMMACRO40*
4,1,40,-.008,-.012,
.008,-.012,
.008695,-.011939,
.009368,-.011759,
.01,-.011464,
.010571,-.011064,
.011064,-.010571,
.011464,-.01,
.011759,-.009368,
.011939,-.008695,
.012,-.008,
.012,.008,
.011939,.008695,
.011759,.009368,
.011464,.01,
.011064,.010571,
.010571,.011064,
.01,.011464,
.009368,.011759,
.008695,.011939,
.008,.012,
-.008,.012,
-.008695,.011939,
-.009368,.011759,
-.01,.011464,
-.010571,.011064,
-.011064,.010571,
-.011464,.01,
-.011759,.009368,
-.011939,.008695,
-.012,.008,
-.012,-.008,
-.011939,-.008695,
-.011759,-.009368,
-.011464,-.01,
-.011064,-.010571,
-.010571,-.011064,
-.01,-.011464,
-.009368,-.011759,
-.008695,-.011939,
-.008,-.012,
0.0*
%
%ADD40MACRO40*%
%AMMACRO33*
4,1,40,.012,-.008,
.012,.008,
.011939,.008695,
.011759,.009368,
.011464,.01,
.011064,.010571,
.010571,.011064,
.01,.011464,
.009368,.011759,
.008695,.011939,
.008,.012,
-.008,.012,
-.008695,.011939,
-.009368,.011759,
-.01,.011464,
-.010571,.011064,
-.011064,.010571,
-.011464,.01,
-.011759,.009368,
-.011939,.008695,
-.012,.008,
-.012,-.008,
-.011939,-.008695,
-.011759,-.009368,
-.011464,-.01,
-.011064,-.010571,
-.010571,-.011064,
-.01,-.011464,
-.009368,-.011759,
-.008695,-.011939,
-.008,-.012,
.008,-.012,
.008695,-.011939,
.009368,-.011759,
.01,-.011464,
.010571,-.011064,
.011064,-.010571,
.011464,-.01,
.011759,-.009368,
.011939,-.008695,
.012,-.008,
0.0*
%
%ADD33MACRO33*%
%AMMACRO24*
4,1,40,-.007,-.011,
.007,-.011,
.007695,-.010939,
.008368,-.010759,
.009,-.010464,
.009571,-.010064,
.010064,-.009571,
.010464,-.009,
.010759,-.008368,
.010939,-.007695,
.011,-.007,
.011,.007,
.010939,.007695,
.010759,.008368,
.010464,.009,
.010064,.009571,
.009571,.010064,
.009,.010464,
.008368,.010759,
.007695,.010939,
.007,.011,
-.007,.011,
-.007695,.010939,
-.008368,.010759,
-.009,.010464,
-.009571,.010064,
-.010064,.009571,
-.010464,.009,
-.010759,.008368,
-.010939,.007695,
-.011,.007,
-.011,-.007,
-.010939,-.007695,
-.010759,-.008368,
-.010464,-.009,
-.010064,-.009571,
-.009571,-.010064,
-.009,-.010464,
-.008368,-.010759,
-.007695,-.010939,
-.007,-.011,
0.0*
%
%ADD24MACRO24*%
%AMMACRO27*
4,1,40,-.011,.007,
-.011,-.007,
-.010939,-.007695,
-.010759,-.008368,
-.010464,-.009,
-.010064,-.009571,
-.009571,-.010064,
-.009,-.010464,
-.008368,-.010759,
-.007695,-.010939,
-.007,-.011,
.007,-.011,
.007695,-.010939,
.008368,-.010759,
.009,-.010464,
.009571,-.010064,
.010064,-.009571,
.010464,-.009,
.010759,-.008368,
.010939,-.007695,
.011,-.007,
.011,.007,
.010939,.007695,
.010759,.008368,
.010464,.009,
.010064,.009571,
.009571,.010064,
.009,.010464,
.008368,.010759,
.007695,.010939,
.007,.011,
-.007,.011,
-.007695,.010939,
-.008368,.010759,
-.009,.010464,
-.009571,.010064,
-.010064,.009571,
-.010464,.009,
-.010759,.008368,
-.010939,.007695,
-.011,.007,
0.0*
%
%ADD27MACRO27*%
%AMMACRO73*
4,1,40,.013,.017,
-.013,.017,
-.013695,.016939,
-.014368,.016759,
-.015,.016464,
-.015571,.016064,
-.016064,.015571,
-.016464,.015,
-.016759,.014368,
-.016939,.013695,
-.017,.013,
-.017,-.013,
-.016939,-.013695,
-.016759,-.014368,
-.016464,-.015,
-.016064,-.015571,
-.015571,-.016064,
-.015,-.016464,
-.014368,-.016759,
-.013695,-.016939,
-.013,-.017,
.013,-.017,
.013695,-.016939,
.014368,-.016759,
.015,-.016464,
.015571,-.016064,
.016064,-.015571,
.016464,-.015,
.016759,-.014368,
.016939,-.013695,
.017,-.013,
.017,.013,
.016939,.013695,
.016759,.014368,
.016464,.015,
.016064,.015571,
.015571,.016064,
.015,.016464,
.014368,.016759,
.013695,.016939,
.013,.017,
0.0*
%
%ADD73MACRO73*%
%AMMACRO41*
4,1,40,.017,-.013,
.017,.013,
.016939,.013695,
.016759,.014368,
.016464,.015,
.016064,.015571,
.015571,.016064,
.015,.016464,
.014368,.016759,
.013695,.016939,
.013,.017,
-.013,.017,
-.013695,.016939,
-.014368,.016759,
-.015,.016464,
-.015571,.016064,
-.016064,.015571,
-.016464,.015,
-.016759,.014368,
-.016939,.013695,
-.017,.013,
-.017,-.013,
-.016939,-.013695,
-.016759,-.014368,
-.016464,-.015,
-.016064,-.015571,
-.015571,-.016064,
-.015,-.016464,
-.014368,-.016759,
-.013695,-.016939,
-.013,-.017,
.013,-.017,
.013695,-.016939,
.014368,-.016759,
.015,-.016464,
.015571,-.016064,
.016064,-.015571,
.016464,-.015,
.016759,-.014368,
.016939,-.013695,
.017,-.013,
0.0*
%
%ADD41MACRO41*%
%AMMACRO22*
4,1,6,.025,.0135,
.005,-.0065,
.005,-.0135,
-.005,-.0135,
-.005,-.0065,
-.025,.0135,
.025,.0135,
0.0*
%
%ADD22MACRO22*%
%AMMACRO34*
4,1,20,.1095,.0655,
.1095,.051,
.12,.051,
.12,.0375,
.1095,.0375,
.1095,-.0375,
.12,-.0375,
.12,-.051,
.1095,-.051,
.1095,-.0655,
-.1095,-.0655,
-.1095,-.051,
-.12,-.051,
-.12,-.0375,
-.1095,-.0375,
-.1095,.0375,
-.12,.0375,
-.12,.051,
-.1095,.051,
-.1095,.0655,
.1095,.0655,
0.0*
%
%ADD34MACRO34*%
%AMMACRO80*
4,1,6,.0135,-.005,
.0065,-.005,
-.0135,-.025,
-.0135,.025,
.0065,.005,
.0135,.005,
.0135,-.005,
0.0*
%
%ADD80MACRO80*%
%AMMACRO39*
4,1,40,-.008,-.012,
.008,-.012,
.008695,-.011939,
.009368,-.011759,
.01,-.011464,
.010571,-.011064,
.011064,-.010571,
.011464,-.01,
.011759,-.009368,
.011939,-.008695,
.012,-.008,
.012,.008,
.011939,.008695,
.011759,.009368,
.011464,.01,
.011064,.010571,
.010571,.011064,
.01,.011464,
.009368,.011759,
.008695,.011939,
.008,.012,
-.008,.012,
-.008695,.011939,
-.009368,.011759,
-.01,.011464,
-.010571,.011064,
-.011064,.010571,
-.011464,.01,
-.011759,.009368,
-.011939,.008695,
-.012,.008,
-.012,-.008,
-.011939,-.008695,
-.011759,-.009368,
-.011464,-.01,
-.011064,-.010571,
-.010571,-.011064,
-.01,-.011464,
-.009368,-.011759,
-.008695,-.011939,
-.008,-.012,
0.0*
%
%ADD39MACRO39*%
%AMMACRO32*
4,1,40,.012,-.008,
.012,.008,
.011939,.008695,
.011759,.009368,
.011464,.01,
.011064,.010571,
.010571,.011064,
.01,.011464,
.009368,.011759,
.008695,.011939,
.008,.012,
-.008,.012,
-.008695,.011939,
-.009368,.011759,
-.01,.011464,
-.010571,.011064,
-.011064,.010571,
-.011464,.01,
-.011759,.009368,
-.011939,.008695,
-.012,.008,
-.012,-.008,
-.011939,-.008695,
-.011759,-.009368,
-.011464,-.01,
-.011064,-.010571,
-.010571,-.011064,
-.01,-.011464,
-.009368,-.011759,
-.008695,-.011939,
-.008,-.012,
.008,-.012,
.008695,-.011939,
.009368,-.011759,
.01,-.011464,
.010571,-.011064,
.011064,-.010571,
.011464,-.01,
.011759,-.009368,
.011939,-.008695,
.012,-.008,
0.0*
%
%ADD32MACRO32*%
%AMMACRO15*
4,1,40,-.007,-.011,
.007,-.011,
.007695,-.010939,
.008368,-.010759,
.009,-.010464,
.009571,-.010064,
.010064,-.009571,
.010464,-.009,
.010759,-.008368,
.010939,-.007695,
.011,-.007,
.011,.007,
.010939,.007695,
.010759,.008368,
.010464,.009,
.010064,.009571,
.009571,.010064,
.009,.010464,
.008368,.010759,
.007695,.010939,
.007,.011,
-.007,.011,
-.007695,.010939,
-.008368,.010759,
-.009,.010464,
-.009571,.010064,
-.010064,.009571,
-.010464,.009,
-.010759,.008368,
-.010939,.007695,
-.011,.007,
-.011,-.007,
-.010939,-.007695,
-.010759,-.008368,
-.010464,-.009,
-.010064,-.009571,
-.009571,-.010064,
-.009,-.010464,
-.008368,-.010759,
-.007695,-.010939,
-.007,-.011,
0.0*
%
%ADD15MACRO15*%
%AMMACRO28*
4,1,40,-.011,.007,
-.011,-.007,
-.010939,-.007695,
-.010759,-.008368,
-.010464,-.009,
-.010064,-.009571,
-.009571,-.010064,
-.009,-.010464,
-.008368,-.010759,
-.007695,-.010939,
-.007,-.011,
.007,-.011,
.007695,-.010939,
.008368,-.010759,
.009,-.010464,
.009571,-.010064,
.010064,-.009571,
.010464,-.009,
.010759,-.008368,
.010939,-.007695,
.011,-.007,
.011,.007,
.010939,.007695,
.010759,.008368,
.010464,.009,
.010064,.009571,
.009571,.010064,
.009,.010464,
.008368,.010759,
.007695,.010939,
.007,.011,
-.007,.011,
-.007695,.010939,
-.008368,.010759,
-.009,.010464,
-.009571,.010064,
-.010064,.009571,
-.010464,.009,
-.010759,.008368,
-.010939,.007695,
-.011,.007,
0.0*
%
%ADD28MACRO28*%
%ADD95C,.02*%
%ADD96C,.03*%
%ADD97C,.012*%
%ADD98C,.04*%
%ADD99C,.014*%
%ADD100C,.015*%
%ADD101C,.016*%
%ADD102C,.025*%
%ADD103C,.004*%
%ADD104C,.006*%
%ADD105O,.12702X.08402*%
%ADD114C,.05204*%
%ADD111C,.04604*%
%ADD108C,.09706*%
%ADD112R,.01X.01*%
%ADD116R,.021X.01*%
%ADD115R,.01X.021*%
%ADD109R,.11804X.15004*%
%ADD107C,.11506*%
%ADD113C,.17006*%
%ADD106R,.17206X.17204*%
%ADD110C,.33904*%
G75*
%LPD*%
G75*
G36*
G01X30398Y373871D02*
G03X29085Y376081I-2298J130D01*
G01X29053Y376096D01*
X28249Y376900D01*
Y382629D01*
X28277Y382677D01*
G03Y385031I-1978J1177D01*
G01X28249Y385079D01*
Y386404D01*
X28277Y386452D01*
G03Y388806I-1978J1177D01*
G01X28249Y388854D01*
Y398376D01*
X28277Y398424D01*
G03X27946Y401209I-1978J1177D01*
G02Y401768I286J279D01*
G03X24142Y404180I-1647J1608D01*
G01X24094Y404050D01*
X23499D01*
X21999Y405550D01*
Y409150D01*
X22864Y410016D01*
X35298D01*
X35598Y410316D01*
X35691Y410307D01*
G03X37448Y410897I208J2293D01*
G01X37506Y410948D01*
X40532D01*
X40589Y410843D01*
G03X42000Y409998I1412J757D01*
G01X43400D01*
G03X43962Y410100I0J1602D01*
G02X44502Y409701I141J-374D01*
G03X44498Y409600I1597J-114D01*
G01Y408200D01*
G03X44587Y407674I1602J1D01*
G01X44598Y407642D01*
Y407166D01*
X44511Y407107D01*
G03X47819Y404094I1289J-1907D01*
G01X47833Y404119D01*
X49002Y405288D01*
Y407642D01*
X49013Y407674D01*
G03X49102Y408200I-1513J527D01*
G01Y409600D01*
G03X48751Y410600I-1602J-1D01*
G03X48911Y410843I-1252J999D01*
G01X48968Y410948D01*
X49369D01*
X50998Y409319D01*
Y408414D01*
X50936Y408355D01*
G03X53911Y408789I1794J-1885D01*
G01X53802Y408844D01*
Y410481D01*
X50531Y413752D01*
X48919D01*
X48860Y413846D01*
G03X47500Y414602I-1360J-845D01*
G01X46100D01*
G03X45020Y414182I1J-1602D01*
G02X44480I-270J296D01*
G03X43400Y414602I-1081J-1182D01*
G01X42000D01*
G03X40640Y413846I0J-1601D01*
G01X40581Y413752D01*
X37896D01*
X37837Y413843D01*
G03X36885Y414680I-1937J-1243D01*
G02X36774Y415325I171J362D01*
G01X37999Y416550D01*
Y463550D01*
X40499Y466050D01*
X66999D01*
X68999Y468050D01*
Y492550D01*
X65999Y495550D01*
X39999D01*
X37999Y497550D01*
Y516027D01*
X38063Y516086D01*
G03Y519464I-1564J1689D01*
G01X37999Y519523D01*
Y519802D01*
X38063Y519861D01*
G03Y523239I-1564J1689D01*
G01X37999Y523298D01*
Y529050D01*
X41999Y533050D01*
X57978D01*
X58036Y532954D01*
G03X62023Y535253I1967J1196D01*
G01X61999Y535298D01*
Y536409D01*
X62023Y536454D01*
G03Y538646I-2024J1096D01*
G01X61999Y538691D01*
Y539550D01*
X60999Y540550D01*
X38999D01*
X37999Y541550D01*
Y542348D01*
X60264D01*
X64198Y538415D01*
Y516079D01*
X64126Y516019D01*
G03X67072I1473J-1769D01*
G01X67000Y516079D01*
Y539577D01*
X61426Y545152D01*
X37999D01*
Y547812D01*
X40651D01*
X40698Y547679D01*
G03X43946Y550483I2169J771D01*
G02X43851Y551120I187J354D01*
G01X44280Y551548D01*
X44470D01*
X44530Y551477D01*
G03X45865Y555211I1769J1473D01*
G02X45391Y555640I-76J393D01*
G03X41028Y556855I-2292J210D01*
G02X40453Y556692I-360J174D01*
G03X38520Y556944I-1236J-1942D01*
G02X37999Y557325I-121J381D01*
G01Y564550D01*
X39499Y566050D01*
X41162D01*
X41216Y566010D01*
G03X43982I1383J1840D01*
G01X44036Y566050D01*
X76999D01*
X79045Y568096D01*
G02X79728Y567813I283J-283D01*
G01Y559151D01*
X91532D01*
Y560050D01*
X100499D01*
X103249Y562800D01*
Y597721D01*
G02X103864Y598058I400J0D01*
G03Y601942I1236J1942D01*
G02X103249Y602279I-215J337D01*
G01Y605050D01*
X104999Y606800D01*
X105462D01*
Y606515D01*
X105401Y606456D01*
G03X108855Y606163I1599J-1656D01*
G02X109177Y606800I322J237D01*
G01X109749D01*
X114762Y601787D01*
G02X114798Y601283I-3553J-507D01*
G01X114797Y599777D01*
X114726Y599717D01*
G03X114098Y598373I1124J-1344D01*
G01Y596673D01*
G03X114726Y595329I1752J0D01*
G01X114798Y595269D01*
Y594977D01*
X114726Y594917D01*
G03X114098Y593573I1124J-1344D01*
G01Y591873D01*
G03X114726Y590529I1752J0D01*
G01X114798Y590469D01*
Y590177D01*
X114726Y590117D01*
G03X114098Y588773I1124J-1344D01*
G01Y587073D01*
G03X114726Y585729I1752J0D01*
G01X114798Y585669D01*
Y585377D01*
X114726Y585317D01*
G03X114098Y583973I1124J-1344D01*
G01Y582273D01*
G03X114726Y580929I1752J0D01*
G01X114798Y580869D01*
Y578263D01*
X114743Y578206D01*
G03X114298Y577077I1206J-1128D01*
G01Y575177D01*
G03X114743Y574048I1651J-1D01*
G01X114798Y573991D01*
Y555848D01*
X112999Y554050D01*
X91532D01*
Y554155D01*
X79728D01*
Y552779D01*
X77999Y551050D01*
Y546550D01*
X79728Y544821D01*
Y544151D01*
X80398D01*
X80499Y544050D01*
X103336D01*
G02X103730Y543583I0J-400D01*
G03X107564Y541511I2270J-383D01*
G02X107836I136J-147D01*
G03X111670Y543583I1564J1689D01*
G02X112064Y544050I394J67D01*
G01X113999D01*
X116499Y541550D01*
Y502550D01*
X110473Y496524D01*
G02X109792Y496843I-283J283D01*
G03X105475Y498146I-2293J207D01*
G01X105418Y498042D01*
X91532D01*
Y499154D01*
X79728D01*
Y494152D01*
X91532D01*
Y495238D01*
X106077D01*
X106130Y495199D01*
G03X107706Y494757I1369J1851D01*
G02X108025Y494076I36J-398D01*
G01X105999Y492050D01*
X92999D01*
X90999Y490050D01*
X80499D01*
X79499Y489050D01*
Y474350D01*
X80899Y472950D01*
X90199D01*
X90299Y472850D01*
Y470550D01*
X90099Y470350D01*
X80899D01*
X79699Y469150D01*
Y463950D01*
X80699Y462950D01*
X90199D01*
X90299Y462850D01*
Y460450D01*
X90199Y460350D01*
X80899D01*
X79699Y459150D01*
Y444250D01*
X79728Y444221D01*
Y444152D01*
X79798D01*
X81599Y442350D01*
X100399D01*
X101499Y441250D01*
Y437550D01*
X96199Y432250D01*
Y233250D01*
X84499Y221550D01*
X42221D01*
X42195Y221557D01*
G03X38897Y219032I-696J-2507D01*
G01X38898Y218949D01*
X36499Y216550D01*
Y209550D01*
X37999Y208050D01*
X42499D01*
X46499Y204050D01*
Y198550D01*
X48999Y196050D01*
X51777D01*
X51803Y196043D01*
G03X53195I696J2507D01*
G01X53221Y196050D01*
X94499D01*
X100499Y190050D01*
Y166550D01*
X97999Y164050D01*
X79499D01*
X78499Y163050D01*
Y132162D01*
X72214D01*
Y124609D01*
X78499D01*
Y122713D01*
X72214D01*
Y115160D01*
X78499D01*
Y89550D01*
X76999Y88050D01*
X70999D01*
X69499Y86550D01*
Y68550D01*
X71999Y66050D01*
X77499D01*
X78499Y65050D01*
Y39050D01*
X84999Y32550D01*
X101598D01*
Y31479D01*
X101504Y31420D01*
G03X104494I1495J-2370D01*
G01X104400Y31479D01*
Y32550D01*
X120290D01*
G02X120512Y31817I0J-400D01*
G03X120342Y3730I9409J-14101D01*
G02X120116Y3000I-226J-330D01*
G01X4000D01*
X3099Y3901D01*
Y365650D01*
X6499Y369050D01*
X22749D01*
X24345Y370646D01*
X36639D01*
X36699Y370560D01*
G03X36566Y373549I2300J1600D01*
G01X36508Y373448D01*
X30798D01*
G02X30398Y373871I0J400D01*
G37*
G36*
G01X55131Y654747D02*
G02Y654227I-304J-260D01*
G03X54926Y653921I1219J-1038D01*
G01X54911Y653893D01*
X52098Y651081D01*
Y645919D01*
X61098Y636919D01*
Y635495D01*
X61013Y635435D01*
G03Y631165I1487J-2135D01*
G01X61098Y631105D01*
Y618987D01*
G02X60659Y618589I-400J0D01*
G03X58750Y618012I-259J-2589D01*
G02X58097Y618345I-254J309D01*
G03X56987Y620635I-2597J155D01*
G01X56902Y620695D01*
Y632581D01*
X54784Y634698D01*
X54793Y634791D01*
G03X51105Y636831I-2293J209D01*
G02X50510Y636959I-243J318D01*
G03X50282Y637280I-1410J-760D01*
G02Y637820I296J270D01*
G03X50702Y638900I-1182J1081D01*
G01Y640300D01*
G03X50470Y641129I-1602J-1D01*
G03X46921Y641910I-1471J1771D01*
G02X46847Y641655I-181J-86D01*
G03X46700Y641551I850J-1357D01*
G03X45700Y641902I-1001J-1251D01*
G01X44300D01*
G03X44184Y641897I11J-1602D01*
G02X43762Y642371I-29J399D01*
G03X39705Y641359I-2262J429D01*
G02X39679Y641082I-156J-125D01*
G03X39719Y637088I1688J-1980D01*
G02X39767Y636515I-253J-310D01*
G03X39437Y636022I1732J-1516D01*
G02X39182Y635926I-179J89D01*
G03X38384Y636100I-882J-2126D01*
G02X37999Y636500I15J400D01*
G01Y656550D01*
X45000Y663551D01*
Y695395D01*
X47998D01*
G02X48140Y695389I-14J-2005D01*
G01X48176Y695247D01*
G03X52047Y697419I2234J554D01*
G02X52038Y697691I142J141D01*
G03X48021Y699525I-1738J1509D01*
G02X47700Y699502I-319J2196D01*
G01X45000D01*
Y702550D01*
X6999D01*
X4999Y704550D01*
Y713456D01*
G02X5688Y713733I400J0D01*
G03Y721689I4155J3978D01*
G02X4999Y721966I-289J277D01*
G01Y758362D01*
G02X5688Y758639I400J0D01*
G03Y766595I4155J3978D01*
G02X4999Y766872I-289J277D01*
G01Y771050D01*
X11999Y778050D01*
X38499D01*
X44486Y784036D01*
X44828D01*
X63540Y802748D01*
X73669D01*
X87619Y788798D01*
X108671D01*
X108731Y788727D01*
G03Y791673I1769J1473D01*
G01X108671Y791602D01*
X88781D01*
X87166Y793216D01*
G02X87449Y793898I283J282D01*
G01X109265D01*
X109319Y793858D01*
G03X112542Y797080I1381J1842D01*
G02X112616Y797635I320J240D01*
G03X112818Y797812I-1414J1817D01*
G02X113499Y797528I281J-284D01*
G01Y759850D01*
X89999Y736350D01*
Y618550D01*
X96999Y611550D01*
Y571550D01*
X94499Y569050D01*
X91532D01*
Y569155D01*
X81070D01*
G02X80787Y569838I0J400D01*
G01X88999Y578050D01*
Y610050D01*
X88000Y611048D01*
Y651337D01*
G03X87031Y654641I-6116J1D01*
G01X86999Y654690D01*
Y663050D01*
X82499Y667550D01*
X74999D01*
Y665691D01*
X74975Y665646D01*
G03Y663454I2024J-1096D01*
G01X74999Y663409D01*
Y660050D01*
X81499Y653550D01*
Y644852D01*
G02X80859Y644532I-400J0D01*
G03X80745Y644610I-961J-1282D01*
G01X80650Y644669D01*
Y648381D01*
X77405Y651626D01*
X70928D01*
X70683Y651381D01*
G02X70000Y651664I-283J283D01*
G01Y654602D01*
X63098D01*
Y654455D01*
G02X62388Y654202I-400J0D01*
G03X62367Y654227I-1237J-1018D01*
G02Y654747I304J260D01*
G03X62750Y655787I-1218J1039D01*
G01Y657187D01*
G03X61995Y658547I-1602J0D01*
G01X61900Y658606D01*
Y658750D01*
G02X62093Y658950I200J0D01*
G03X59438Y661092I-94J2600D01*
G01X59456Y660989D01*
X59098Y660631D01*
Y658655D01*
X58992Y658598D01*
G03X58749Y658438I756J-1412D01*
G03X57883Y658783I-1000J-1251D01*
G01X57810Y658789D01*
X56848Y659752D01*
X44887D01*
X44840Y659780D01*
G03Y655320I-1341J-2230D01*
G01X44887Y655348D01*
X54803D01*
X54851Y655219D01*
G03X55131Y654747I1497J569D01*
G37*
G36*
G01X84534Y812102D02*
X81972Y814663D01*
G02X81995Y815250I283J283D01*
G03X81007Y819245I-1495J1750D01*
G01X80852Y819281D01*
Y820950D01*
X77850Y823952D01*
X73757D01*
G02X73522Y824675I0J400D01*
G03X74980Y826591I-2474J3396D01*
G02X75637Y826733I374J-141D01*
G01X81222Y821148D01*
G02X81599Y820749I-23J-399D01*
G03X81716Y820466I400J0D01*
G01X85181Y817002D01*
X86300D01*
G02X86700Y816587I0J-400D01*
G03X89153Y818797I2300J-87D01*
G02X88839Y819405I27J399D01*
G02X92389Y819866I1961J-1205D01*
G03X92981Y819910I276J289D01*
G02X93524Y820416I1820J-1409D01*
G03X93702Y820749I-222J333D01*
G02X94102Y821148I400J-1D01*
G01X96871D01*
X96931Y821077D01*
G03Y824023I1769J1473D01*
G01X96871Y823952D01*
X92141D01*
G02X91824Y824596I0J400D01*
G03X92063Y827021I-1824J1404D01*
G02X92422Y827598I358J177D01*
G01X101530D01*
X105938Y832007D01*
X106041Y831989D01*
G03X108418Y832793I458J2561D01*
G02X108977Y832823I295J-270D01*
G03Y836277I1522J1727D01*
G02X108418Y836307I-264J300D01*
G03X103938Y834092I-1919J-1757D01*
G01X103956Y833989D01*
X100368Y830402D01*
X93110D01*
G02X92724Y830905I0J400D01*
G03X92796Y831669I-2224J595D01*
G02X93195Y832098I399J29D01*
G01X96171D01*
X96231Y832027D01*
G03Y834973I1769J1473D01*
G01X96171Y834902D01*
X93500D01*
Y836234D01*
X93851D01*
X95516Y837898D01*
X95507Y837991D01*
G02X96122Y839776I2293J209D01*
G03X96107Y840338I-292J273D01*
G02X95931Y840527I1594J1661D01*
G01X95871Y840598D01*
X93500D01*
Y841198D01*
X96871D01*
X96931Y841127D01*
G03Y844073I1769J1473D01*
G01X96871Y844002D01*
X93681D01*
X90381Y847302D01*
X78202D01*
G02X77802Y847701I0J400D01*
G03X77586Y848673I-2302J-2D01*
G02X77669Y848932I181J85D01*
G03X76821Y853223I-1129J2006D01*
G02X76477Y853698I48J397D01*
G03X72582Y852532I-2257J452D01*
G02X72307Y851851I-284J-281D01*
G03X70683Y847975I55J-2301D01*
G02X70391Y847302I-292J-273D01*
G01X59381D01*
X49181Y857502D01*
X34548D01*
X30999Y861050D01*
X29362D01*
G02X28962Y861465I0J400D01*
G03X25916Y863728I-2300J85D01*
G02X25418Y863950I-130J378D01*
G03X21444Y861687I-2119J-900D01*
G02X21122Y861050I-322J-237D01*
G01X7499D01*
X5499Y863050D01*
Y870494D01*
G02X6155Y870801I400J0D01*
G03Y879631I3688J4415D01*
G02X5499Y879938I-256J307D01*
G01Y1332674D01*
G02X6155Y1332981I400J0D01*
G03Y1341811I3688J4415D01*
G02X5499Y1342118I-256J307D01*
G01Y1350050D01*
X6999Y1351550D01*
X18747D01*
X18789Y1351406D01*
G03X22801Y1350618I2210J644D01*
G02X23397Y1350652I313J-249D01*
G01X24499Y1349550D01*
Y1071900D01*
X23818Y1071219D01*
X23683Y1071304D01*
G03X19739Y1068642I-1383J-2204D01*
G01X19757Y1068539D01*
X18565Y1067347D01*
X18497Y1067339D01*
G03X17098Y1065750I203J-1589D01*
G01Y1064350D01*
G03X17498Y1063291I1602J0D01*
G02X17398Y1062680I-300J-265D01*
G01Y1057224D01*
X24300D01*
X24301Y1060434D01*
G02X24983Y1060717I400J0D01*
G01X26266Y1059434D01*
G02X25983Y1058752I-283J-282D01*
G01X24898D01*
Y1053348D01*
X31800D01*
Y1053417D01*
G02X32142Y1053558I200J0D01*
G01X44198Y1041502D01*
Y1039605D01*
X53034Y1030769D01*
Y1023079D01*
X53978Y1022136D01*
X53960Y1022033D01*
G03X53934Y1021750I1576J-287D01*
G01Y1020350D01*
G03X54344Y1019280I1601J0D01*
G02X54357Y1018761I-298J-267D01*
G03X53998Y1017750I1242J-1010D01*
G01Y1016781D01*
X53258Y1016041D01*
X53148Y1016070D01*
G03X55089Y1013804I-649J-2520D01*
G01X55079Y1013898D01*
X55930Y1014748D01*
X56999D01*
G03X57999Y1015099I-1J1602D01*
G03X58999Y1014748I1001J1251D01*
G01X59187D01*
X64637Y1009298D01*
X65612D01*
X65659Y1009270D01*
G03X66300Y1014006I1341J2230D01*
G01X66188Y1013975D01*
X65792Y1014370D01*
G02X66075Y1015053I283J283D01*
G01X69606D01*
G02X69960Y1014468I0J-400D01*
G03X70527Y1011631I2040J-1067D01*
G01X70598Y1011571D01*
Y1011419D01*
X74919Y1007098D01*
X79156D01*
X79213Y1006999D01*
G03X79337Y1006815I1387J801D01*
G02X79270Y1006255I-315J-246D01*
G03X79151Y1002746I1429J-1805D01*
G02Y1002154I-269J-296D01*
G03X81345Y998240I1548J-1704D01*
G01X81372Y998248D01*
X82641D01*
X82673Y998237D01*
G03X83199Y998148I527J1513D01*
G01X84599D01*
G03X85599Y998499I-1J1602D01*
G03X86599Y998148I1001J1251D01*
G01X87668D01*
X88598Y997218D01*
Y994929D01*
X88527Y994869D01*
G03X92288Y993355I1473J-1769D01*
G02X92673Y993799I397J44D01*
G03X92857Y993812I-70J2301D01*
G02X93302Y993415I45J-397D01*
G01Y992089D01*
X93372Y992029D01*
G02X93646Y991755I-1485J-1759D01*
G01X93706Y991684D01*
X93999D01*
Y980050D01*
X89499Y975550D01*
X80499D01*
X79499Y974550D01*
Y949550D01*
X80499Y948550D01*
X89999D01*
X90499Y948050D01*
Y946050D01*
X89799Y945350D01*
X87499D01*
X85699Y943550D01*
X70999D01*
X68499Y941050D01*
Y929550D01*
X71499Y926550D01*
X72214D01*
Y926184D01*
X82118D01*
Y926550D01*
X97472D01*
X97528Y926443D01*
G03X98945Y925588I1417J747D01*
G01X100545D01*
G03X101545Y925938I1J1601D01*
G03X102545Y925588I999J1251D01*
G01X104145D01*
G03X105562Y926443I0J1602D01*
G01X105618Y926550D01*
X107545D01*
X107601Y926502D01*
G03X109827Y926066I1498J1748D01*
G01X109944Y926105D01*
X113499Y922550D01*
Y815218D01*
G02X112803Y814949I-400J0D01*
G03X108801Y813277I-1703J-1549D01*
G01X108806Y813188D01*
X107719Y812102D01*
X84534D01*
G37*
G36*
G01X6499Y1847050D02*
X4999Y1848550D01*
Y1855213D01*
G02X5688Y1855490I400J0D01*
G03Y1863446I4155J3978D01*
G02X4999Y1863723I-289J277D01*
G01Y1890914D01*
G02X5683Y1891195I400J0D01*
G03X34288Y1906720I12037J11937D01*
G02X34962Y1907087I391J84D01*
G01X40366Y1901683D01*
X40381Y1901647D01*
G03X41393Y1900531I2118J903D01*
G01X41418Y1900517D01*
X42337Y1899598D01*
X42450D01*
X48999Y1893050D01*
Y1878050D01*
X51499Y1875550D01*
X74999D01*
X77499Y1873050D01*
Y1864550D01*
X75999Y1863050D01*
X59499D01*
X48344Y1851895D01*
X48203Y1852017D01*
G03X43909Y1849796I-1704J-1967D01*
G01X43919Y1849702D01*
X41267Y1847050D01*
X6499D01*
G37*
G36*
G01X131121Y1308800D02*
X125100D01*
X124500Y1309400D01*
Y1309450D01*
X123602Y1310348D01*
Y1314919D01*
X125952Y1317269D01*
Y1317732D01*
X126057Y1317789D01*
G03X126300Y1317949I-756J1412D01*
G03X126587Y1317766I1000J1251D01*
G01X126698Y1317711D01*
Y1316263D01*
X127107Y1315855D01*
X127102Y1315765D01*
G03X130451Y1318096I2597J-160D01*
G02X130194Y1318623I116J383D01*
G03X130302Y1319200I-1494J578D01*
G01Y1320600D01*
G03X128700Y1322202I-1602J0D01*
G01X127731D01*
X127126Y1322806D01*
Y1323421D01*
X127245Y1323474D01*
G03X128426Y1325300I-821J1826D01*
G01Y1328200D01*
G03X126425Y1330202I-2002J0D01*
G01X125025D01*
G03X123261Y1329146I0J-2001D01*
G02X122553Y1329151I-353J189D01*
G03X118768Y1329604I-2046J-1055D01*
G02X118174Y1329592I-302J262D01*
G03X117725Y1329961I-1674J-1580D01*
G02X117656Y1330583I213J338D01*
G01X125150Y1338077D01*
Y1339800D01*
X126695D01*
X126719Y1339794D01*
G03X127099Y1339748I381J1556D01*
G01X128499D01*
G03X128879Y1339794I-1J1602D01*
G01X128903Y1339800D01*
X130095D01*
X130119Y1339794D01*
G03X130499Y1339748I381J1556D01*
G01X131899D01*
G03X132279Y1339794I-1J1602D01*
G01X132303Y1339800D01*
X137100D01*
X141200Y1343900D01*
Y1350148D01*
X141869D01*
X145399Y1346619D01*
X145398Y1346534D01*
G03X147172Y1348967I2602J-34D01*
G01X147055Y1348927D01*
X143031Y1352952D01*
X133200D01*
Y1354252D01*
X133183D01*
G02X133041Y1354593I0J200D01*
G01X134474Y1356026D01*
Y1361974D01*
X135000Y1362500D01*
X139048D01*
X209999Y1291550D01*
X210999D01*
X341092Y1048977D01*
G02X340733Y1048388I-353J-189D01*
G03X342635Y1044841I-34J-2302D01*
G02X343324Y1044814I337J-216D01*
G01X764999Y258550D01*
X765999Y257050D01*
X837460Y222516D01*
G02X837391Y221770I-174J-360D01*
G03X839606Y217902I608J-2220D01*
G02X840168Y217899I279J-286D01*
G01X861418Y196648D01*
X883945D01*
G02X884133Y195896I-1J-400D01*
G03X888701I2284J-4282D01*
G02X888889Y196648I189J352D01*
G01X893918D01*
X910418Y180148D01*
X935918D01*
X939893Y176174D01*
X939963D01*
X946302Y169835D01*
G02X946017Y169152I-283J-283D01*
G03X945507Y169105I-17J-2602D01*
G01X945488Y169102D01*
X935500D01*
Y170402D01*
X928598D01*
Y170366D01*
G02X927884Y170118I-400J0D01*
G03X927701Y170312I-1252J-998D01*
G02X927656Y170857I269J297D01*
G03X928000Y171850I-1257J992D01*
G01Y173250D01*
G03X926399Y174852I-1602J0D01*
G01X924999D01*
G03X923999Y174501I1J-1602D01*
G03X922999Y174852I-1001J-1251D01*
G01X921599D01*
G03X921073Y174763I1J-1602D01*
G01X921041Y174752D01*
X917172D01*
X917145Y174760D01*
G03X915043Y170767I-646J-2210D01*
G02X915084Y170186I-253J-310D01*
G03X914864Y169911I1917J-1759D01*
G01X914804Y169826D01*
X914292D01*
X909502Y165036D01*
X901546D01*
Y166049D01*
X889792D01*
Y165036D01*
X888108D01*
X888095Y165222D01*
G03X882935Y165492I-2596J-173D01*
G01X882906Y165326D01*
X877072D01*
X877015Y165425D01*
G03X875628Y166226I-1387J-800D01*
G01X874228D01*
G03X873228Y165875I1J-1602D01*
G03X872228Y166226I-1001J-1251D01*
G01X870828D01*
G03X870302Y166137I1J-1602D01*
G01X870270Y166126D01*
X868173D01*
X868146Y166134D01*
G03X865985Y162191I-646J-2210D01*
G02X865996Y161599I-263J-301D01*
G03X868222Y157714I1579J-1675D01*
G01X868249Y157722D01*
X870270D01*
X870302Y157711D01*
G03X870828Y157622I527J1513D01*
G01X872228D01*
G03X873228Y157973I-1J1602D01*
G03X874228Y157622I1001J1251D01*
G01X875628D01*
G03X877191Y158876I0J1601D01*
G01X877226Y159032D01*
X880804D01*
X880864Y158947D01*
G03X885134I2135J1487D01*
G01X885194Y159032D01*
X889792D01*
Y158045D01*
X901546D01*
Y159032D01*
X905304D01*
X905364Y158947D01*
G03X909634I2135J1487D01*
G01X909694Y159032D01*
X909964D01*
X913954Y163022D01*
X920384D01*
X920441Y162923D01*
G03X921445Y162169I1387J801D01*
G01X921598Y162131D01*
Y160745D01*
X921512Y160685D01*
G03X925134Y157063I1487J-2135D01*
G01X925194Y157148D01*
X925531D01*
X925588Y157043D01*
G03X926153Y156440I1412J756D01*
G01X926248Y156381D01*
Y156319D01*
X928168Y154398D01*
X940058D01*
X950400Y164741D01*
Y169701D01*
X941125Y178976D01*
X941055D01*
X937080Y182952D01*
X911580D01*
X895080Y199452D01*
X862580D01*
X843108Y218923D01*
G02X843565Y219566I283J283D01*
G01X870499Y206550D01*
X872499Y205550D01*
X885499D01*
X886999Y207050D01*
Y231050D01*
X885999Y232050D01*
X846499D01*
X774499Y266550D01*
X764513Y285075D01*
G02X765148Y285548I352J190D01*
G01X766547Y284148D01*
X783804D01*
X783864Y284063D01*
G03X788134I2135J1487D01*
G01X788194Y284148D01*
X812913D01*
X815314Y286550D01*
X817450D01*
X818500Y285500D01*
Y280500D01*
X807500Y269500D01*
Y264000D01*
X813500Y258000D01*
X840500D01*
X845000Y262500D01*
X853456D01*
X853494Y262484D01*
G03X855306I906J2116D01*
G01X855344Y262500D01*
X857000D01*
Y272500D01*
X856597Y272903D01*
X856672Y273035D01*
G03X856880Y273824I-1394J789D01*
G01Y276424D01*
G03X856338Y277624I-1602J-1D01*
G02Y278224I265J300D01*
G03X856707Y278700I-1059J1202D01*
G02X857186Y278900I357J-181D01*
G03X857678Y278822I494J1524D01*
G01X858847D01*
X860147Y277522D01*
X860527D01*
X861999Y276050D01*
X884999D01*
X885499Y276550D01*
Y281050D01*
X884999Y281550D01*
X871499D01*
X870499Y282550D01*
Y285050D01*
X871499Y286050D01*
X884999D01*
X885999Y287050D01*
Y301050D01*
X884999Y302050D01*
X873999D01*
X872999Y303050D01*
Y305050D01*
X873499Y305550D01*
X884499D01*
X885499Y306550D01*
Y311050D01*
X884499Y312050D01*
X873499D01*
X872999Y312550D01*
Y315050D01*
X873999Y316050D01*
X884499D01*
X884999Y316550D01*
Y331550D01*
X874499Y342050D01*
X866881D01*
X866843Y342067D01*
G03X866200Y342202I-644J-1467D01*
G01X863600D01*
G03X862957Y342067I1J-1602D01*
G01X862919Y342050D01*
X838450D01*
X837000Y343500D01*
Y363500D01*
X833450Y367050D01*
X771999D01*
X771045Y366096D01*
X771029Y366085D01*
G03X770317Y365373I1449J-2161D01*
G01X770306Y365357D01*
X768999Y364050D01*
Y355550D01*
X768766Y355317D01*
X768409Y355674D01*
X758640D01*
X740598Y337631D01*
X740597Y331028D01*
G02X739845Y330839I-400J1D01*
G01X225499Y1285050D01*
Y1285550D01*
X225999Y1286050D01*
X226999D01*
X237999Y1275050D01*
X770499Y615050D01*
X771499Y614050D01*
X868999D01*
X871999Y611050D01*
X884499D01*
X886499Y613050D01*
Y636050D01*
X884999Y637550D01*
X768999D01*
X375078Y1122555D01*
X375124Y1122665D01*
G03X372569Y1125811I-2125J885D01*
G01X372452Y1125789D01*
X262999Y1260550D01*
Y1261550D01*
X263999Y1262550D01*
X265499D01*
X858999Y1018050D01*
X861499Y1017050D01*
X884999D01*
X885999Y1018050D01*
Y1042050D01*
X884999Y1043050D01*
X838999D01*
X260999Y1276550D01*
X181999Y1355550D01*
Y1363423D01*
X182103Y1363480D01*
G03X183019Y1364394I-1102J2021D01*
G01X183033Y1364419D01*
X186802Y1368188D01*
Y1371842D01*
X186813Y1371874D01*
G03X186902Y1372400I-1513J527D01*
G01Y1373200D01*
G02X187584Y1373483I400J0D01*
G01X189027Y1372040D01*
X189040Y1371985D01*
G03X189753Y1370990I1559J364D01*
G01X189848Y1370931D01*
Y1370073D01*
X189708Y1370029D01*
G03X192683Y1368965I791J-2479D01*
G01X192650Y1369015D01*
Y1370882D01*
X192756Y1370939D01*
G03X192999Y1371099I-756J1412D01*
G03X193745Y1370769I999J1251D01*
G01X193808Y1370759D01*
X196898Y1367669D01*
Y1366700D01*
G03X197653Y1365340I1602J0D01*
G01X197748Y1365281D01*
Y1364729D01*
X197676Y1364669D01*
G03X197063Y1361926I1473J-1769D01*
G02X196874Y1361396I-362J-170D01*
G03X200554Y1359542I1125J-2346D01*
G01X200550Y1359561D01*
Y1361071D01*
X200622Y1361131D01*
G03Y1364669I-1473J1769D01*
G01X200550Y1364729D01*
Y1365232D01*
X200656Y1365289D01*
G03X200899Y1365449I-756J1412D01*
G03X201899Y1365098I1001J1251D01*
G01X203299D01*
G03X203674Y1365143I-2J1602D01*
G01X203697Y1365148D01*
X206804D01*
X206864Y1365063D01*
G03X210486Y1368685I2135J1487D01*
G01X210400Y1368745D01*
Y1370224D01*
X211500D01*
Y1375398D01*
X215034D01*
X215084Y1375366D01*
G03X214020Y1378341I1415J2184D01*
G01X213976Y1378202D01*
X204000D01*
Y1379502D01*
X197350D01*
G02X196960Y1379991I0J400D01*
G03X197000Y1380350I-1561J356D01*
G01Y1381750D01*
G03X196129Y1383175I-1601J0D01*
G02X196073Y1383852I183J356D01*
G03X194054Y1387910I-1372J1848D01*
G01X194027Y1387902D01*
X193288D01*
X189035Y1383649D01*
X188883Y1383802D01*
X188195D01*
X188135Y1383887D01*
G03X183865I-2135J-1487D01*
G01X183805Y1383802D01*
X181798D01*
X180500Y1385100D01*
X154948D01*
X116817Y1423232D01*
G02X117143Y1423912I283J282D01*
G03X119647Y1425748I247J2289D01*
G01X119679Y1425908D01*
X143142D01*
X143182Y1425762D01*
G03X144563Y1424224I2241J624D01*
G01X144689Y1424173D01*
Y1422971D01*
X156493D01*
Y1432975D01*
X144689D01*
Y1431380D01*
X144583Y1431323D01*
G03X143509Y1430527I2149J-4021D01*
G01X142992Y1430012D01*
X128928D01*
X128870Y1430065D01*
G03X127753Y1430502I-1117J-1209D01*
G01X125843D01*
G03X124726Y1430065I0J-1646D01*
G01X124668Y1430012D01*
X119699D01*
X119682Y1430193D01*
G03X115743Y1428368I-2292J-217D01*
G02Y1427809I-286J-279D01*
G03X115179Y1425561I1647J-1608D01*
G02X114794Y1425050I-384J-111D01*
G01X111499D01*
X103999Y1432550D01*
Y1437986D01*
G02X104478Y1438378I400J0D01*
G03X107164Y1441210I457J2256D01*
G02X107551Y1441710I387J100D01*
G01X124442D01*
G02X124589Y1441699I-1J-998D01*
G01X124591D01*
G02X125188Y1441376I-148J-987D01*
G01Y1440441D01*
G03X126790Y1438840I1601J0D01*
G01X128390D01*
G03X129390Y1439190I1J1601D01*
G03X130390Y1438840I999J1251D01*
G01X131990D01*
G03X133592Y1440441I0J1602D01*
G01Y1440908D01*
X143642D01*
X143682Y1440762D01*
G03X144603Y1439470I2242J624D01*
G01X144689Y1439411D01*
Y1437971D01*
X156493D01*
Y1447975D01*
X144689D01*
Y1446509D01*
X144603Y1446450D01*
G03X143682Y1445158I1321J-1916D01*
G01X143642Y1445012D01*
X133592D01*
Y1445541D01*
G03X131990Y1447142I-1601J0D01*
G01X130906D01*
X129499Y1448550D01*
X125999D01*
X123999Y1446550D01*
Y1446050D01*
X123763Y1445814D01*
X107133D01*
X107079Y1445928D01*
G03X104488Y1447186I-2080J-987D01*
G02X103999Y1447576I-89J390D01*
G01Y1464550D01*
X102542Y1466007D01*
G02X102683Y1466348I141J141D01*
G01X102901D01*
X102924Y1466343D01*
G03X103299Y1466298I377J1557D01*
G01X104699D01*
G03X106300Y1467900I0J1601D01*
G01Y1469300D01*
G03X105950Y1470300I-1601J1D01*
G03X106300Y1471300I-1251J999D01*
G01Y1472700D01*
G03X105879Y1473783I-1601J1D01*
G02X105869Y1474312I295J270D01*
G03X106250Y1475350I-1220J1037D01*
G01Y1476319D01*
X108840Y1478909D01*
G02X109523Y1478626I283J-283D01*
G01X109522Y1477782D01*
X109481Y1477728D01*
G03X109148Y1476750I1268J-977D01*
G01Y1475350D01*
G03X109569Y1474267I1601J-1D01*
G02X109579Y1473738I-295J-270D01*
G03X109198Y1472700I1220J-1037D01*
G01Y1471300D01*
G03X109548Y1470300I1601J-1D01*
G03X109198Y1469300I1251J-999D01*
G01Y1467900D01*
G03X110799Y1466298I1602J0D01*
G01X112199D01*
G03X112574Y1466343I-2J1602D01*
G01X112597Y1466348D01*
X113398D01*
Y1463962D01*
X105918Y1456483D01*
X105893Y1456469D01*
G03X109018Y1453344I1106J-2019D01*
G01X109032Y1453369D01*
X117800Y1462138D01*
Y1467292D01*
X117812Y1467324D01*
G03X117900Y1467850I-1513J524D01*
G01Y1468506D01*
G02X118593Y1468778I400J0D01*
G03X120498Y1467948I1905J1772D01*
G01X120499D01*
Y1465050D01*
X120599Y1464950D01*
Y1463750D01*
X121199Y1463150D01*
X122507D01*
X122557Y1463118D01*
G03X125059I1251J1932D01*
G01X125109Y1463150D01*
X139399D01*
X140499Y1462050D01*
Y1455550D01*
X142499Y1453550D01*
X143999D01*
X145499Y1455050D01*
X152499D01*
X152999Y1454550D01*
X154103D01*
Y1454452D01*
X164007D01*
Y1454558D01*
X165499Y1456050D01*
Y1470550D01*
X164499Y1471550D01*
X133499D01*
X129499Y1475550D01*
X122499D01*
X120499Y1473550D01*
Y1473152D01*
G03X120041Y1473111I2J-2602D01*
G01X119938Y1473093D01*
X119630Y1473402D01*
X117718D01*
X117659Y1473496D01*
G03X117461Y1473752I-1359J-847D01*
G02X117451Y1474292I290J275D01*
G03X117850Y1475350I-1203J1058D01*
G01Y1476750D01*
G03X116249Y1478352I-1602J0D01*
G01X115180D01*
X114886Y1478646D01*
Y1480779D01*
X117947D01*
Y1483066D01*
X119005D01*
X119037Y1483098D01*
X121321D01*
X121359Y1483082D01*
G03X121999Y1482948I641J1468D01*
G01X123599D01*
G03X125200Y1484550I0J1601D01*
G01Y1486150D01*
G03X125023Y1486883I-1601J1D01*
G01X125000Y1486926D01*
Y1490362D01*
X120111Y1495252D01*
X99387D01*
X97518Y1493383D01*
X97493Y1493369D01*
G03X97087Y1489614I1106J-2019D01*
G02X96981Y1488945I-263J-301D01*
G03X100560Y1487008I1018J-2395D01*
G01X100542Y1487111D01*
X101580Y1488148D01*
X106463D01*
Y1480496D01*
X104318Y1478352D01*
X103249D01*
G03X101648Y1476750I0J-1601D01*
G01Y1475350D01*
G03X101649Y1475272I1601J-18D01*
G02X101250Y1474852I-400J-20D01*
G01X98678D01*
X98485Y1475046D01*
X98492Y1475138D01*
G03X93384Y1476015I-2593J212D01*
G02X92714Y1475835I-387J103D01*
G01X52499Y1516050D01*
Y1545050D01*
X46602Y1550947D01*
X46600Y1551026D01*
G03X44375Y1553251I-2301J-76D01*
G01X44296Y1553253D01*
X39499Y1558050D01*
Y1565550D01*
X47983Y1574034D01*
X60471Y1561547D01*
X60453Y1561444D01*
G03X63472Y1558425I2561J-458D01*
G01X63575Y1558443D01*
X65819Y1556198D01*
X76315D01*
G02X76712Y1555754I0J-400D01*
G03X77199Y1554066I2288J-254D01*
G02X77169Y1553534I-313J-249D01*
G03X76698Y1552400I1130J-1134D01*
G01Y1551000D01*
G03X77049Y1550000I1602J1D01*
G03X76698Y1549000I1251J-1001D01*
G01Y1547600D01*
G03X77499Y1546213I1601J0D01*
G01X77598Y1546156D01*
Y1545119D01*
X77755Y1544963D01*
X77748Y1544871D01*
G03X81705Y1543099I2295J-180D01*
G02X82281Y1543101I289J-277D01*
G03X85200Y1546626I1651J1604D01*
G02X85132Y1546883I111J167D01*
G03X85302Y1547600I-1432J718D01*
G01Y1549000D01*
G03X84951Y1550000I-1602J-1D01*
G03X85302Y1551000I-1251J1001D01*
G01Y1552400D01*
G03X84501Y1553787I-1601J0D01*
G01X84402Y1553844D01*
Y1554312D01*
X84428Y1554358D01*
G03X84706Y1555160I-1999J1142D01*
G02X85384Y1555384I396J-59D01*
G01X86998Y1553769D01*
Y1552800D01*
G03X88600Y1551198I1602J0D01*
G01X90000D01*
G03X91000Y1551549I-1J1602D01*
G03X92000Y1551198I1001J1251D01*
G01X93400D01*
G03X93554Y1551206I-6J1602D01*
G02X93978Y1550703I38J-398D01*
G03X97630Y1551904I2222J-603D01*
G02X97733Y1552260I124J157D01*
G03X97995Y1552302I-233J2290D01*
G01X98102Y1552326D01*
X100854Y1549574D01*
G02X100487Y1548900I-283J-283D01*
G03X102250Y1547137I-487J-2250D01*
G02X102924Y1547504I391J84D01*
G01X111198Y1539230D01*
Y1515694D01*
X111098Y1515637D01*
G03X110393Y1514795I801J-1387D01*
G01X110378Y1514754D01*
X110205Y1514581D01*
X109735Y1515051D01*
X109872Y1515192D01*
G03X106513Y1514865I-1871J1808D01*
G01X106598Y1514805D01*
Y1514223D01*
X106669Y1514153D01*
G02X106550Y1513506I-283J-282D01*
G03X108318Y1508217I1148J-2556D01*
G01X108425Y1508242D01*
X109522Y1507144D01*
Y1505363D01*
X109023D01*
Y1496959D01*
X117947D01*
Y1505363D01*
X117446D01*
Y1507839D01*
X117625Y1507858D01*
G03X118809Y1508604I-176J1592D01*
G01X118868Y1508698D01*
X120384D01*
X120424Y1508681D01*
G03X119406Y1512596I1075J2369D01*
G01X119046Y1512730D01*
G03X119050Y1512850I-1597J113D01*
G01Y1514250D01*
G03X118206Y1515661I-1601J0D01*
G01X118100Y1515718D01*
Y1522387D01*
G02X118563Y1522782I400J0D01*
G03X121314Y1523971I436J2768D01*
G01X121373Y1524058D01*
X144690D01*
Y1522972D01*
X156492D01*
Y1527974D01*
X144690D01*
Y1526862D01*
X121478D01*
X121420Y1526961D01*
G03X118563Y1528318I-2421J-1411D01*
G02X118100Y1528713I-63J395D01*
G01Y1538980D01*
X103063Y1554017D01*
G02X103346Y1554700I283J283D01*
G01X113000D01*
Y1559050D01*
X129499D01*
X132499Y1562050D01*
Y1600050D01*
X133499Y1601050D01*
X158564D01*
G02X158806Y1600332I-1J-400D01*
G03X157950Y1598985I1394J-1832D01*
G02X157726Y1598829I-196J42D01*
G03X159650Y1596065I-326J-2279D01*
G02X159874Y1596221I196J-42D01*
G03X161594Y1600332I326J2279D01*
G02X161836Y1601050I243J318D01*
G01X331499D01*
X362299Y1591370D01*
X400199Y1578466D01*
G02X400208Y1577712I-129J-379D01*
G03X402945Y1576780I791J-2162D01*
G02X403412Y1577372I338J213D01*
G01X437860Y1565643D01*
X826689Y1432656D01*
X847999Y1424550D01*
X850499Y1422050D01*
X884999D01*
X885999Y1423050D01*
Y1447050D01*
X884999Y1448050D01*
X829660D01*
X828424Y1446814D01*
X754999Y1470050D01*
X754759Y1469810D01*
X727623Y1478379D01*
X328731Y1611477D01*
G03X328698Y1611488I-460J-1324D01*
G03X325054Y1612107I-4208J-13738D01*
G03X324500Y1612118I-560J-14250D01*
G01X209430D01*
X206499Y1615050D01*
Y1631068D01*
X206900Y1631469D01*
Y1674095D01*
X181443Y1699552D01*
X181461Y1699655D01*
G03X177599Y1702366I-2561J458D01*
G02X176999Y1702713I-200J347D01*
G01Y1733750D01*
X173199Y1737550D01*
X146999D01*
X146499Y1738050D01*
X115499D01*
X114999Y1738550D01*
Y1740300D01*
X111580D01*
X111529Y1740424D01*
G03X110988Y1741215I-2129J-876D01*
G02X111003Y1741807I276J289D01*
G03X107760Y1745058I-1504J1743D01*
G02X107186Y1745026I-302J262D01*
G03X106099Y1745452I-1088J-1176D01*
G01X104499D01*
G03X103499Y1745101I1J-1602D01*
G03X102499Y1745452I-1001J-1251D01*
G01X100899D01*
G03X99298Y1743850I0J-1601D01*
G01Y1743256D01*
G02X99199Y1743254I-87J1853D01*
G01X83361Y1743253D01*
G02X83182Y1743327I0J253D01*
G03X82381Y1743831I-1503J-1500D01*
G01X82249Y1743962D01*
X82118D01*
Y1744761D01*
X72999D01*
Y1746657D01*
X82118D01*
Y1748250D01*
X82183Y1748309D01*
G03X82285Y1748407I-2223J2416D01*
G01X82526Y1748648D01*
X82894D01*
X82922Y1748480D01*
G03X86949Y1750338I2272J368D01*
G01X86902Y1750467D01*
X86961Y1750609D01*
G03X83133Y1752895I-1620J1636D01*
G01X83090Y1752752D01*
X82688D01*
X82632Y1752802D01*
G03X82361Y1752990I-929J-1050D01*
G03X82231Y1753056I-1625J-3039D01*
G01X82118Y1753111D01*
Y1754210D01*
X72999D01*
Y1775590D01*
G02X73547Y1775962I400J0D01*
G03Y1780238I853J2138D01*
G02X72999Y1780610I-148J372D01*
G01Y1783050D01*
X80999Y1791050D01*
X90004D01*
G02X90200Y1790866I-2897J-3282D01*
G01X94506Y1786559D01*
X94980Y1786085D01*
G03X95010Y1786054I1022J959D01*
G02X95097Y1785845I-209J-210D01*
G03Y1785795I1401J-25D01*
G01X95098Y1785792D01*
Y1782952D01*
X93580D01*
X92790Y1783741D01*
G03X91669Y1784433I-2020J-2018D01*
G01X91532Y1784478D01*
Y1785691D01*
X79728D01*
Y1775687D01*
X91532D01*
Y1777019D01*
X91636Y1777076D01*
G03X92844Y1778691I-1174J2137D01*
G01X92878Y1778848D01*
X95227D01*
G03X97155Y1779339I20J3952D01*
G03X97209Y1779368I-636J1249D01*
G03X99201Y1782800I-1960J3432D01*
G01X99200D01*
Y1783395D01*
X99500D01*
X99560Y1783315D01*
G03X103336Y1783457I1839J1385D01*
G02X103956Y1783523I337J-216D01*
G01X110876Y1776603D01*
G02X111198Y1775826I-778J-778D01*
G01Y1769186D01*
G02X110876Y1768409I-1100J1D01*
G01X110640Y1768173D01*
G02X110236Y1767917I-776J779D01*
G02X109700Y1768293I-136J376D01*
G01Y1768350D01*
G03X108099Y1769952I-1602J0D01*
G01X106499D01*
G03X105499Y1769601I1J-1602D01*
G03X104499Y1769952I-1001J-1251D01*
G01X102899D01*
G03X101298Y1768350I0J-1601D01*
G01Y1767774D01*
G02X100795Y1767728I-503J2731D01*
G01X92536D01*
X92488Y1767859D01*
G03X91937Y1768724I-2225J-809D01*
G01X91805Y1768856D01*
G03X91607Y1769034I-1744J-1740D01*
G01X91532Y1769094D01*
Y1770691D01*
X79728D01*
Y1760687D01*
X91532D01*
Y1761913D01*
X91642Y1761968D01*
G03X92625Y1763440I-813J1607D01*
G01X92639Y1763624D01*
X96844D01*
G02X97193Y1763028I1J-400D01*
G03X101479Y1761585I2006J-1129D01*
G02X102080Y1761874I396J-55D01*
G03X102899Y1761648I820J1376D01*
G01X104499D01*
G03X105499Y1761999I-1J1602D01*
G03X106499Y1761648I1001J1251D01*
G01X108099D01*
G03X108148Y1761649I-8J1602D01*
G01X108310Y1761324D01*
G03X110000Y1762175I1789J-1449D01*
G02X109607Y1762709I-17J399D01*
G03X109700Y1763250I-1509J538D01*
G01Y1763549D01*
G02X109899Y1763749I200J0D01*
G03X113542Y1765271I-34J5203D01*
G01X113778Y1765507D01*
G03X115301Y1769186I-3680J3678D01*
G01X115300D01*
Y1775826D01*
X115301D01*
G03X113778Y1779505I-5203J1D01*
G01X102916Y1790367D01*
G02X102999Y1790997I283J283D01*
G01Y1795650D01*
X90399Y1808250D01*
Y1813750D01*
X92399Y1815750D01*
X126499D01*
X138199Y1804050D01*
X160938D01*
G02X161306Y1803494I0J-400D01*
G03X165173Y1797650I3867J-1643D01*
G01X169473D01*
G03X173340Y1803494I0J4201D01*
G02X173708Y1804050I368J156D01*
G01X266499D01*
X291999Y1829550D01*
X871499D01*
X872999Y1828050D01*
X884999D01*
X885999Y1829050D01*
Y1853050D01*
X884999Y1854050D01*
X871499D01*
X870499Y1853050D01*
X843999D01*
X831999Y1841050D01*
X280999D01*
X262499Y1822550D01*
X142499D01*
X138999Y1826050D01*
Y1831420D01*
X143096D01*
X143123Y1831252D01*
G03X144544Y1829649I1976J320D01*
G01X144689Y1829607D01*
Y1828483D01*
X156493D01*
Y1838487D01*
X144689D01*
Y1837158D01*
X144590Y1837100D01*
G03X143623Y1835692I1009J-1729D01*
G01X143596Y1835524D01*
X138999D01*
Y1846420D01*
X143580D01*
X143594Y1846236D01*
G03X144579Y1844763I1796J135D01*
G01X144689Y1844708D01*
Y1843483D01*
X156493D01*
Y1853487D01*
X144689D01*
Y1852236D01*
X144579Y1852181D01*
G03X143594Y1850708I811J-1608D01*
G01X143580Y1850524D01*
X140472D01*
X140499Y1850550D01*
X134304D01*
X134284Y1850728D01*
G03X132692Y1852156I-1592J-173D01*
G01X131092D01*
G03X130092Y1851805I1J-1602D01*
G03X129092Y1852156I-1001J-1251D01*
G01X127492D01*
G03X125900Y1850728I0J-1601D01*
G01X125880Y1850550D01*
X111317D01*
G02X110381Y1851168I2525J4843D01*
G01X109499Y1852050D01*
Y1893550D01*
X114499Y1898550D01*
X134999D01*
X136999Y1896550D01*
X210499D01*
X214500Y1892548D01*
Y1875000D01*
X219500Y1870000D01*
X245500D01*
X252000Y1876500D01*
Y1904051D01*
X256802Y1908853D01*
X256913Y1908824D01*
G03X259725Y1911636I586J2226D01*
G01X259696Y1911747D01*
X259999Y1912050D01*
X280999D01*
X285249Y1916300D01*
Y1926300D01*
X288499Y1929550D01*
X312137D01*
X312169Y1929539D01*
G03X312699Y1929448I532J1511D01*
G01X314299D01*
G03X314829Y1929539I-2J1602D01*
G01X314861Y1929550D01*
X323499D01*
X325999Y1932050D01*
Y1936884D01*
X326042Y1936939D01*
G03X326563Y1938994I-2043J1611D01*
G01X326545Y1939096D01*
X327499Y1940050D01*
X342999D01*
X345499Y1942550D01*
Y1948050D01*
X344998Y1948551D01*
X344985Y1948573D01*
G03X344163Y1949395I-1986J-1164D01*
G01X344141Y1949408D01*
X342499Y1951050D01*
X336922D01*
Y1951455D01*
X337007Y1951515D01*
G03X334929Y1956184I-1487J2135D01*
G02X334459Y1956704I-92J390D01*
G03X332200Y1960144I-2460J846D01*
G02X331934Y1960810I32J399D01*
G03X327468Y1961945I-1935J1740D01*
G02X327079Y1961452I-389J-93D01*
G01X326202D01*
Y1962274D01*
X325276D01*
X323642Y1963908D01*
Y1969674D01*
X323319D01*
Y1969961D01*
X323384Y1970021D01*
G03X323734Y1970487I-1084J1179D01*
G01X323789Y1970598D01*
X327595D01*
X327649Y1970484D01*
G03X328179Y1973459I2351J1116D01*
G01X328121Y1973402D01*
X323691D01*
X323631Y1973490D01*
G03X323099Y1973988I-1332J-889D01*
G01X322999Y1974046D01*
Y1974550D01*
X315999Y1981550D01*
X253499D01*
X251974Y1980026D01*
X246026D01*
X241000Y1975000D01*
Y1961050D01*
X239500Y1959550D01*
X217499D01*
X215499Y1961550D01*
X200999D01*
X195499Y1956050D01*
X144799D01*
X142499Y1958350D01*
Y1979501D01*
X138500Y1983500D01*
X116999D01*
X113999Y1980500D01*
Y1978050D01*
X111999Y1976050D01*
X100499D01*
X95949Y1971500D01*
X54000D01*
X53000Y1972500D01*
Y1974048D01*
X50499Y1976550D01*
X48539D01*
X48002Y1977088D01*
X46012D01*
X45965Y1977116D01*
G03X43283I-1341J-2230D01*
G01X43236Y1977088D01*
X42745D01*
X42208Y1976550D01*
X41499D01*
X39750Y1974802D01*
X39749D01*
X39499Y1974552D01*
X39387D01*
X39386Y1974550D01*
X35999D01*
X35499Y1975050D01*
Y1980050D01*
X34499Y1981050D01*
X32940D01*
X32895Y1981074D01*
G03X30703I-1096J-2024D01*
G01X30658Y1981050D01*
X30499D01*
X29499Y1980050D01*
Y1979142D01*
G03Y1978958I2300J-92D01*
G01Y1977550D01*
X27931Y1975982D01*
X27814Y1976021D01*
G03X25388Y1975593I-815J-2471D01*
G01X25333Y1975550D01*
X22500D01*
Y1976252D01*
X19098D01*
Y1975550D01*
X8000D01*
X6000Y1977550D01*
Y1986500D01*
X8500Y1989000D01*
X1029500D01*
X1030399Y1988101D01*
Y1744601D01*
X1030400Y1744600D01*
Y1697400D01*
X1028360Y1695360D01*
G02X1027683Y1695579I-282J283D01*
G03X1017924Y1685820I-8392J-1367D01*
G02X1018143Y1685143I-64J-395D01*
G01X1015700Y1682700D01*
Y1676300D01*
X1013900Y1674500D01*
X974000D01*
X971500Y1672000D01*
Y1668402D01*
X969700D01*
G03X968098Y1666800I0J-1602D01*
G01Y1664200D01*
G03X968506Y1663133I1602J1D01*
G02Y1662867I-150J-133D01*
G03X968098Y1661800I1194J-1068D01*
G01Y1659200D01*
G03X969700Y1657598I1602J0D01*
G01X971500D01*
Y1651000D01*
X972500Y1650000D01*
X979365D01*
G02X979762Y1649556I-1J-400D01*
G03X984352Y1649301I2288J-254D01*
G02X984752Y1649700I400J-1D01*
G01X989300D01*
X991500Y1647500D01*
X1015200D01*
X1016000Y1646700D01*
Y1645200D01*
X1015300Y1644500D01*
X974000D01*
X972004Y1642504D01*
X966171D01*
X965452Y1641784D01*
X965359Y1641793D01*
G03X962963Y1638781I-209J-2293D01*
G02X962453Y1638278I-380J-125D01*
G03X963471Y1634629I-751J-2176D01*
G01X963531Y1634700D01*
X985181D01*
X986079Y1635598D01*
X990902D01*
X993106Y1633394D01*
Y1633300D01*
X993200D01*
X994000Y1632500D01*
X1015100D01*
X1016000Y1631600D01*
Y1625200D01*
X1015300Y1624500D01*
X989802D01*
G02X989402Y1624900I0J400D01*
G03X984876Y1624307I-2302J0D01*
G02X984489Y1623804I-386J-103D01*
G01X983380D01*
G02X983057Y1624440I0J400D01*
G03X979343I-1857J1360D01*
G02X979020Y1623804I-323J-236D01*
G01X956217D01*
X952010Y1628010D01*
G03X948190Y1624190I-1910J-1910D01*
G01X953979Y1618400D01*
X983000D01*
X984500Y1616900D01*
Y1611900D01*
X987600Y1608800D01*
X1014000D01*
X1016100Y1606700D01*
Y1514700D01*
X1015100Y1513700D01*
X950200D01*
X944500Y1508000D01*
Y1434300D01*
X949800Y1429000D01*
X1017100D01*
X1020300Y1425800D01*
X1028300D01*
X1030000Y1424100D01*
Y4000D01*
X1029000Y3000D01*
X139726D01*
G02X139500Y3730I0J400D01*
G03X139330Y31817I-9579J13986D01*
G02X139552Y32550I222J333D01*
G01X177999D01*
X180499Y30050D01*
Y18550D01*
X183499Y15550D01*
X209999D01*
X220999Y26550D01*
X233499D01*
X237500Y30551D01*
Y72500D01*
X239000Y74000D01*
X239996D01*
X240049Y73961D01*
G03X240999Y73648I951J1289D01*
G01X243599D01*
G03X244866Y74271I-1J1602D01*
G01X244926Y74348D01*
X248526D01*
X252316Y78138D01*
Y89347D01*
X250999Y90663D01*
Y105550D01*
X237999Y118550D01*
X198499D01*
X195999Y121050D01*
X191293D01*
X191263Y121214D01*
G03X188353Y123010I-2265J-414D01*
G01X188326Y123002D01*
X186597D01*
X186574Y123007D01*
G03X186199Y123052I-377J-1557D01*
G01X184799D01*
G03X183198Y121450I0J-1601D01*
G01Y121050D01*
X121999D01*
X119499Y123550D01*
Y149450D01*
X113499Y155450D01*
Y163750D01*
X113549Y163800D01*
Y166700D01*
X113499Y166750D01*
Y196050D01*
X115999Y198550D01*
X153999D01*
X157999Y202550D01*
Y230050D01*
X156499Y231550D01*
X123499D01*
X120999Y234050D01*
Y246839D01*
G02X121606Y247181I400J0D01*
G03X124349Y247448I1193J1969D01*
G01X124406Y247500D01*
X125980D01*
X126038Y247405D01*
G03X127399Y246648I1361J845D01*
G01X128999D01*
G03X129999Y246999I-1J1602D01*
G03X130999Y246648I1001J1251D01*
G01X132599D01*
G03X133960Y247405I0J1602D01*
G01X134018Y247500D01*
X154103D01*
Y247365D01*
X164007D01*
Y254918D01*
X154103D01*
Y253893D01*
G03X153207Y253291I1097J-2601D01*
G01X153135Y253221D01*
X152832Y252917D01*
G02X152810Y252899I-89J87D01*
G02X152744Y252880I-66J106D01*
G01X134200D01*
Y253350D01*
G03X132599Y254952I-1602J0D01*
G01X130999D01*
G03X129999Y254601I1J-1602D01*
G03X128999Y254952I-1001J-1251D01*
G01X127399D01*
G03X125987Y254106I0J-1601D01*
G01X125930Y254000D01*
X124291D01*
X124231Y254079D01*
G03X121547Y254827I-1834J-1391D01*
G02X120999Y255199I-148J372D01*
G01Y406050D01*
X134749Y419800D01*
X142001D01*
G02X142400Y419420I0J-400D01*
G03X147558Y419077I2599J129D01*
G01X147569Y419138D01*
X149400Y420969D01*
Y421952D01*
X149999Y422550D01*
Y423262D01*
X150000D01*
Y428552D01*
X150499Y429050D01*
X153316D01*
X154728Y427638D01*
X154659Y427508D01*
G03X159187Y424949I2300J-1216D01*
G02X159859Y424970I343J-207D01*
G03X163769Y428357I2140J1480D01*
G02X164041Y429050I272J293D01*
G01X166998D01*
Y426034D01*
X166964Y425984D01*
G03X166698Y425100I1336J-884D01*
G01Y423700D01*
G03X167410Y422369I1602J1D01*
G01X167498Y422309D01*
Y421295D01*
X167413Y421235D01*
G03X170387I1487J-2135D01*
G01X170302Y421295D01*
Y422211D01*
X170413Y422266D01*
G03X170700Y422449I-713J1434D01*
G03X171700Y422098I1001J1251D01*
G01X173100D01*
G03X174487Y422899I0J1601D01*
G01X174544Y422998D01*
X174847D01*
X174907Y422927D01*
G03X178387Y426735I1993J1673D01*
G01X178302Y426795D01*
Y427598D01*
X178450D01*
Y429050D01*
X184000D01*
X187550Y425500D01*
X206000D01*
X211999Y431499D01*
Y475550D01*
X202999Y484550D01*
Y498050D01*
X199499Y501550D01*
X195704D01*
X195680Y501556D01*
G03X195300Y501602I-381J-1556D01*
G01X193700D01*
G03X193320Y501556I1J-1602D01*
G01X193296Y501550D01*
X188099D01*
X186499Y503150D01*
Y508050D01*
X187999Y509550D01*
X209999D01*
X210999Y508550D01*
X212999Y510550D01*
Y512550D01*
X212516Y513033D01*
X213813Y514331D01*
X213950Y514240D01*
G03X217535Y514913I1450J2160D01*
G01X217595Y514998D01*
X218171D01*
X218231Y514927D01*
G03Y517873I1769J1473D01*
G01X218171Y517802D01*
X217595D01*
X217535Y517887D01*
G03X213078Y517574I-2135J-1487D01*
G01X213064Y517546D01*
X211032Y515514D01*
X210034D01*
X208999Y516550D01*
Y524550D01*
X209360Y524912D01*
X209497D01*
X211200Y526615D01*
Y540111D01*
X200186Y551126D01*
G02X200384Y551800I283J283D01*
G03X197650Y554534I-484J2250D01*
G02X196976Y554336I-391J85D01*
G01X196497Y554814D01*
X188001D01*
X185298Y552111D01*
Y537501D01*
X185269Y537454D01*
G03Y534772I2230J-1341D01*
G01X185298Y534725D01*
Y533001D01*
X185269Y532954D01*
G03X184992Y530917I2230J-1341D01*
G01X184999Y530891D01*
Y524550D01*
X183999Y523550D01*
X180999D01*
X180779Y523770D01*
X180790Y523866D01*
G03X180800Y524050I-1591J179D01*
G01Y525650D01*
G03X180667Y526290I-1601J1D01*
G01X180650Y526328D01*
Y529912D01*
X178321Y532241D01*
G02X178657Y532921I283J283D01*
G03X179530Y538047I343J2579D01*
G01X179471Y538060D01*
X178580Y538952D01*
X178365D01*
G02X178224Y539293I0J200D01*
G01X178938Y540007D01*
X179041Y539989D01*
G03X176938Y542092I458J2561D01*
G01X176956Y541989D01*
X175518Y540552D01*
X170687D01*
G02X170404Y541234I0J400D01*
G01X172958Y543788D01*
Y545266D01*
X173459D01*
Y553670D01*
X167838D01*
Y554494D01*
X165269Y557062D01*
X165281Y557159D01*
G03X164392Y559567I-2781J341D01*
G02X164334Y560091I270J295D01*
G03X164372Y560158I-328J230D01*
G01X164743Y560143D01*
G03X168687Y563135I2457J857D01*
G01X168602Y563195D01*
Y563557D01*
X173200D01*
Y564544D01*
X174272D01*
X174498Y564319D01*
Y563781D01*
X172598Y561882D01*
Y560122D01*
X172188Y559711D01*
X172109Y559708D01*
G03X174634Y558026I91J-2600D01*
G01X174588Y558147D01*
X174923Y558482D01*
G02X175578Y558346I283J-283D01*
G03X180134Y557813I2421J954D01*
G01X180194Y557898D01*
X181055D01*
X181112Y557799D01*
G03X181544Y557315I1386J802D01*
G03X185761Y556525I1955J-1215D01*
G02X186155Y556998I393J73D01*
G01X186968D01*
X187318Y556648D01*
X191804D01*
X191864Y556563D01*
G03X195950Y559771I2135J1487D01*
G01X195900Y559828D01*
Y561824D01*
X197000D01*
Y565648D01*
X198004D01*
G02X198403Y565222I0J-400D01*
G03X202298Y567305I2596J-172D01*
G02X202220Y567939I200J346D01*
G03X197934Y570592I-1803J1876D01*
G01X197890Y570452D01*
X189500D01*
Y571102D01*
X182500D01*
Y571307D01*
G03Y571350I-1601J21D01*
G01Y572750D01*
G03X180899Y574352I-1602J0D01*
G01X179499D01*
G03X179299Y574339I4J-1602D01*
G01X179202Y574327D01*
X179108Y574420D01*
Y574573D01*
X199476Y594940D01*
X350499D01*
G03Y599660I0J2360D01*
G01X197522D01*
X174390Y576527D01*
Y572050D01*
G03X174472Y571431I2359J-2D01*
G02X174156Y571388I-174J98D01*
G01X172046Y573498D01*
X159702D01*
G02X159302Y573891I0J400D01*
G03X159182Y574586I-2302J-40D01*
G01X159171Y574617D01*
Y574850D01*
X159588D01*
X159639Y574798D01*
X160151D01*
X160178Y574790D01*
G03X161496Y579202I646J2210D01*
G01X161448Y579216D01*
X161412Y579252D01*
X161299D01*
X161280Y579256D01*
G03X160368I-456J-2256D01*
G01X160349Y579252D01*
X154713D01*
X148848Y573387D01*
Y567811D01*
X152810Y563848D01*
X153041D01*
X153073Y563837D01*
G03X153599Y563748I527J1513D01*
G01X154999D01*
G03X155054Y563749I-2J1602D01*
G02X155425Y563170I14J-400D01*
G03X158618Y559547I2324J-1170D01*
G02X159143Y559251I133J-377D01*
G01X159236Y559185D01*
G02X159892Y558525I-1488J-2135D01*
G03X163374Y554838I2608J-1025D01*
G01X163491Y554876D01*
X164535Y553832D01*
Y545266D01*
X166818D01*
G02X167101Y544583I0J-400D01*
G01X166919Y544402D01*
X159800D01*
Y544950D01*
G03X159045Y546310I-1602J0D01*
G01X158950Y546369D01*
Y547677D01*
X158961Y547709D01*
G03X154297Y547164I-2462J841D01*
G02X153958Y546552I-339J-212D01*
G01X153399D01*
G03X152596Y546336I0J-1601D01*
G02X152336Y546388I-101J173D01*
G03X149854Y547210I-1837J-1388D01*
G01X149827Y547202D01*
X148458D01*
X148426Y547213D01*
G03X148222Y547269I-525J-1513D01*
G01X148062Y547302D01*
Y548298D01*
X149629D01*
X153329Y551998D01*
X155362D01*
X155406Y551974D01*
G03Y556026I1094J2026D01*
G01X155362Y556002D01*
X151671D01*
X148745Y553075D01*
G02X148062Y553358I-283J283D01*
G01Y553502D01*
X144902D01*
Y554498D01*
X148062D01*
Y562769D01*
X142929Y567902D01*
X142438D01*
X142394Y567926D01*
G03X139661Y564284I-1094J-2026D01*
G02X139607Y563677I-285J-281D01*
G03X138914Y560707I1333J-1877D01*
G01X138938Y560663D01*
Y556199D01*
G02X138520Y555800I-400J0D01*
G03X137976Y555759I-100J-2300D01*
G02X137499Y556152I-77J393D01*
G01Y614884D01*
X143580D01*
X143594Y614700D01*
G03X144579Y613227I1796J135D01*
G01X144689Y613172D01*
Y611947D01*
X156493D01*
Y621951D01*
X144689D01*
Y620700D01*
X144579Y620645D01*
G03X143594Y619172I811J-1608D01*
G01X143580Y618988D01*
X137499D01*
Y628608D01*
X137515Y628645D01*
G03X137640Y629265I-1477J620D01*
G01Y629858D01*
G02X137998Y629885I362J-2411D01*
G01X137999Y629884D01*
X143580D01*
X143594Y629700D01*
G03X144579Y628227I1796J135D01*
G01X144689Y628172D01*
Y626947D01*
X156493D01*
Y636951D01*
X144689D01*
Y635700D01*
X144579Y635645D01*
G03X143594Y634172I811J-1608D01*
G01X143580Y633988D01*
X137640D01*
Y634365D01*
G03X137515Y634985I-1602J0D01*
G01X137499Y635022D01*
Y653108D01*
X137515Y653145D01*
G03X137640Y653765I-1477J620D01*
G01Y654469D01*
G02X138772Y654648I1132J-3489D01*
G01X153323D01*
X153382Y654554D01*
G03X154007Y653937I1601J996D01*
G01X154103Y653879D01*
Y652877D01*
X164007D01*
Y660430D01*
X154103D01*
Y659459D01*
X153996Y659402D01*
G03X153345Y658835I867J-1653D01*
G01X153286Y658752D01*
X137647D01*
X137638Y658942D01*
G03X137515Y659485I-1600J-77D01*
G01X137499Y659522D01*
Y677050D01*
X141049Y680600D01*
X216900D01*
X220098Y677403D01*
Y667320D01*
X227319Y660098D01*
X235181D01*
X255437Y680355D01*
G02X256087Y679914I282J-283D01*
G03X279393Y688294I15570J-6704D01*
G02X279575Y689050I182J356D01*
G01X310499D01*
Y689148D01*
X326580D01*
X350197Y712766D01*
X350290Y712757D01*
G03X348206Y714841I209J2293D01*
G01X348215Y714748D01*
X325418Y691952D01*
X310499D01*
Y694437D01*
X327200Y711138D01*
Y725050D01*
X345499D01*
X464499Y606050D01*
X558499D01*
X563999Y611550D01*
Y626550D01*
X557999Y632550D01*
X481499D01*
X372999Y741050D01*
X337499D01*
X337000Y741548D01*
Y741750D01*
G03X336999Y741815I-1601J8D01*
G01Y744285D01*
G03X337000Y744350I-1600J57D01*
G01Y745750D01*
G03X336999Y745815I-1601J8D01*
G01Y747050D01*
X330999Y753050D01*
X328999D01*
X324060Y757988D01*
Y762552D01*
X323998D01*
X321500Y765048D01*
Y770048D01*
X321214Y770335D01*
X321331Y770475D01*
G03X321534Y770787I-1232J1024D01*
G01X321589Y770898D01*
X324805D01*
X324865Y770813D01*
G03Y773787I2135J1487D01*
G01X324805Y773702D01*
X321491D01*
X321431Y773790D01*
G03X320100Y774502I-1331J-888D01*
G01X318700D01*
G03X317700Y774151I1J-1602D01*
G03X317146Y774438I-1000J-1251D01*
G01X317097Y774452D01*
X313999Y777550D01*
X251050D01*
X242000Y768500D01*
Y758050D01*
X241000Y757050D01*
X183499D01*
X169499Y743050D01*
X162172D01*
G02X161860Y743700I0J400D01*
G03X153489Y745135I-3789J3032D01*
G02X152828Y744721I-378J-131D01*
G01X152499Y745050D01*
Y793550D01*
X158499Y799550D01*
X176999D01*
X181999Y804550D01*
Y819828D01*
X182006Y819854D01*
G03Y821246I-2507J696D01*
G01X181999Y821272D01*
Y824384D01*
X182042Y824439D01*
G03Y827661I-2043J1611D01*
G01X181999Y827716D01*
Y829551D01*
X185098D01*
Y823820D01*
X195819Y813098D01*
X219781D01*
X238900Y832218D01*
Y897855D01*
X238986Y897915D01*
G03Y902185I-1487J2135D01*
G01X238900Y902245D01*
Y905694D01*
X232451Y912143D01*
Y917065D01*
X227500D01*
Y920500D01*
X225000Y923000D01*
X200500D01*
X193500Y916000D01*
X184999D01*
X182726Y918272D01*
Y919700D01*
G03X182065Y921187I-2001J1D01*
G01X181999Y921246D01*
Y922036D01*
G02X182532Y922413I400J0D01*
G03X183200Y922298I669J1887D01*
G01X184600D01*
G03X186568Y923935I0J2001D01*
G01X186598Y924098D01*
X192605D01*
X192665Y924013D01*
G03Y926987I2135J1487D01*
G01X192605Y926902D01*
X186602D01*
Y927200D01*
G03X185420Y929026I-2001J0D01*
G01X185302Y929079D01*
Y929509D01*
X185390Y929569D01*
G03X186102Y930900I-888J1331D01*
G01Y932300D01*
G03X185783Y933259I-1601J0D01*
G02X186103Y933898I321J239D01*
G01X188462D01*
Y935098D01*
X210298D01*
Y925615D01*
X212001Y923912D01*
X232497D01*
X234700Y926115D01*
Y943611D01*
X226497Y951814D01*
X213001D01*
X210298Y949111D01*
Y939102D01*
X188462D01*
Y940302D01*
X185302D01*
Y941298D01*
X188462D01*
Y943671D01*
X188502Y943711D01*
Y949329D01*
X186329Y951502D01*
X181999D01*
Y960148D01*
X182680D01*
X183330Y960798D01*
X184399D01*
G03X185399Y961149I-1J1602D01*
G03X186399Y960798I1001J1251D01*
G01X187799D01*
G03X188748Y961110I-1J1602D01*
G01X188800Y961148D01*
X191354D01*
X191414Y961063D01*
G03X195036Y964685I2135J1487D01*
G01X194950Y964745D01*
Y965524D01*
X197000D01*
Y969648D01*
X197804D01*
X197864Y969563D01*
G03Y972537I2135J1487D01*
G01X197804Y972452D01*
X190418D01*
X190183Y972216D01*
G02X189501Y972499I-282J283D01*
G01X189500Y974802D01*
X189400D01*
Y979606D01*
X189522Y979657D01*
G03X186548Y980329I-1022J2393D01*
G01X186598Y980272D01*
Y974802D01*
X182598D01*
Y973502D01*
X182238D01*
X182199Y973651D01*
G03X182027Y974066I-1551J-400D01*
G01X181999Y974113D01*
Y974987D01*
X182027Y975034D01*
G03X182250Y975850I-1378J815D01*
G01Y977250D01*
G03X182027Y978066I-1601J1D01*
G01X181999Y978113D01*
Y998052D01*
X255639Y1071692D01*
G02X256284Y1071577I282J-283D01*
G03X257346Y1087809I15373J7145D01*
G02X256608Y1088023I-338J214D01*
G01Y1089855D01*
X270800Y1104047D01*
Y1120046D01*
X284127Y1133373D01*
G03X280873Y1136627I-1627J1627D01*
G01X266984Y1122739D01*
G02X266302Y1123022I-282J283D01*
G01Y1126303D01*
X271502Y1131503D01*
Y1134362D01*
X271526Y1134406D01*
G03X267474I-2026J1094D01*
G01X267498Y1134362D01*
Y1133161D01*
X262298Y1127961D01*
Y1108310D01*
X253983Y1099994D01*
G02X253300Y1100277I-283J283D01*
G01Y1122300D01*
X251443Y1124157D01*
G02X251584Y1124498I141J141D01*
G01X251598D01*
X253002Y1125902D01*
Y1126783D01*
X253009Y1126809D01*
G03Y1128191I-2509J691D01*
G01X253002Y1128217D01*
Y1131498D01*
X251198Y1133302D01*
X249751D01*
Y1134359D01*
G02X250351Y1134705I400J0D01*
G03Y1138695I1149J1995D01*
G02X249751Y1139041I-200J346D01*
G01Y1141102D01*
X245202D01*
Y1141398D01*
X243348Y1143252D01*
X230802D01*
X228448Y1140898D01*
Y1125902D01*
X228548Y1125802D01*
Y1125402D01*
X201402D01*
X200901Y1124900D01*
X198400D01*
X198300Y1124800D01*
X195100D01*
X183100Y1112800D01*
X144400D01*
X143900Y1112300D01*
Y1097400D01*
X144100Y1097200D01*
X213501D01*
X215202Y1095498D01*
X215502D01*
X217700Y1093300D01*
X224493D01*
X224515Y1093124D01*
G03X224590Y1092754I2286J271D01*
G01X224598Y1092727D01*
Y1092361D01*
X224358D01*
X224321Y1092376D01*
G03X223700Y1092502I-623J-1476D01*
G01X222100D01*
G03X220834Y1091881I0J-1601D01*
G02X220175Y1091921I-316J245D01*
G03X218800Y1092702I-1375J-820D01*
G01X216200D01*
G03X214883Y1092012I0J-1602D01*
G02X214294Y1091936I-329J228D01*
G03X210465Y1091448I-1694J-1975D01*
G01X210405Y1091362D01*
X156492D01*
Y1092462D01*
X144690D01*
Y1087460D01*
X156492D01*
Y1088560D01*
X210405D01*
X210465Y1088474D01*
G03X214181Y1087894I2135J1487D01*
G02X214779Y1087761I243J-317D01*
G03X215140Y1087300I1420J740D01*
G02Y1086700I-265J-300D01*
G03X214598Y1085500I1060J-1201D01*
G01Y1082900D01*
G03X215932Y1081321I1601J0D01*
G01X216098Y1081293D01*
Y1070600D01*
X218800Y1067898D01*
X219971D01*
X220031Y1067827D01*
G03X220228Y1070982I1769J1473D01*
G02X219672Y1070991I-273J292D01*
G01X218902Y1071762D01*
Y1081293D01*
X219068Y1081321D01*
G03X220402Y1082900I-267J1579D01*
G01Y1085500D01*
G03X219860Y1086700I-1602J-1D01*
G02Y1087300I265J300D01*
G03X220320Y1087996I-1060J1200D01*
G02X220980Y1088156I380J-126D01*
G03X222100Y1087698I1121J1143D01*
G01X223269D01*
X224499Y1086469D01*
Y1086231D01*
X223898Y1085631D01*
Y1085486D01*
X223098Y1084686D01*
Y1084619D01*
X223004Y1084560D01*
G03X222248Y1083200I845J-1360D01*
G01Y1081800D01*
G03X222455Y1081014I1602J2D01*
G02X222382Y1080743I-174J-98D01*
G03X226277Y1078138I1318J-2243D01*
G01X226286Y1078204D01*
X228281Y1080198D01*
X228650D01*
G03X230252Y1081800I0J1602D01*
G01Y1082769D01*
X234281Y1086798D01*
X235450D01*
G03X235532Y1086800I-8J2002D01*
G02X235948Y1086401I16J-399D01*
G01Y1080221D01*
X239187Y1076983D01*
G02X238904Y1076300I-283J-283D01*
G01X229000D01*
X227400Y1074700D01*
Y1074150D01*
G02X227004Y1073750I-400J0D01*
G03X227790Y1068660I24J-2602D01*
G01X227905Y1068695D01*
X230900Y1065700D01*
X231228D01*
X231265Y1065548D01*
G03X235706Y1065441I2235J552D01*
G01X235720Y1065490D01*
X235931Y1065700D01*
X239712D01*
X239744Y1065540D01*
G03X240786Y1064044I2256J460D01*
G02X240858Y1063421I-211J-340D01*
G01X182682Y1005245D01*
G02X181999Y1005527I-283J283D01*
G01Y1006100D01*
X173100Y1014999D01*
Y1061000D01*
X168600Y1065500D01*
X164006D01*
Y1065942D01*
X155600D01*
Y1067459D01*
X156493D01*
Y1082463D01*
X144689D01*
Y1081700D01*
X140500D01*
X140000Y1082200D01*
Y1092500D01*
X136400Y1096100D01*
Y1100381D01*
X131300Y1105481D01*
Y1118500D01*
X131346Y1118546D01*
X144690D01*
Y1117460D01*
X156492D01*
Y1122462D01*
X144690D01*
Y1121350D01*
X135115D01*
G02X134832Y1122032I0J400D01*
G01X136116Y1123316D01*
G02X136725Y1123265I283J-283D01*
G03X140486Y1125921I1875J1335D01*
G02X140813Y1126550I328J229D01*
G01X155999D01*
X157499Y1128050D01*
Y1141550D01*
X141000Y1158049D01*
Y1175500D01*
X138950Y1177550D01*
X100999D01*
X96499Y1182050D01*
X81999D01*
X73499Y1190550D01*
Y1209550D01*
X85499Y1221550D01*
Y1225499D01*
X85528Y1225547D01*
G03X87971Y1231398I-18048J10971D01*
G01X88009Y1231550D01*
X92499D01*
Y1235050D01*
X93999Y1236550D01*
X132499D01*
X133499Y1235550D01*
Y1231550D01*
X132999Y1231050D01*
X126499D01*
X124999Y1229550D01*
Y1225050D01*
X125164Y1224886D01*
Y1224748D01*
X124272Y1223857D01*
X124179Y1223866D01*
G03X125442Y1219803I-209J-2293D01*
G02X126098Y1219495I256J-308D01*
G01Y1218115D01*
X120097D01*
Y1217514D01*
X118981D01*
X118583Y1217116D01*
G02X117900Y1217399I-283J283D01*
G01Y1221769D01*
X118000Y1221826D01*
G03X118800Y1223213I-802J1387D01*
G01Y1224613D01*
G03X118450Y1225613I-1601J1D01*
G03X118800Y1226613I-1251J999D01*
G01Y1228013D01*
G03X117199Y1229614I-1601J0D01*
G01X115799D01*
G03X114439Y1228859I0J-1602D01*
G01X114380Y1228764D01*
X114118D01*
X114059Y1228859D01*
G03X112699Y1229614I-1360J-847D01*
G01X111299D01*
G03X109939Y1228859I0J-1602D01*
G01X109880Y1228764D01*
X109118D01*
X109059Y1228859D01*
G03X107699Y1229614I-1360J-847D01*
G01X106299D01*
G03X104939Y1228859I0J-1602D01*
G01X104880Y1228764D01*
X101231D01*
X101060Y1228593D01*
X100957Y1228611D01*
G03X101013Y1223499I-458J-2561D01*
G02X101476Y1223219I79J-392D01*
G03X104332Y1221653I2210J644D01*
G01X104359Y1221662D01*
X105901D01*
X105924Y1221656D01*
G03X106299Y1221612I373J1557D01*
G01X107699D01*
G03X109139Y1222513I0J1601D01*
G02X109859I360J-175D01*
G03X110498Y1221826I1441J699D01*
G01X110598Y1221769D01*
Y1220464D01*
X110058D01*
Y1215091D01*
X109918Y1214952D01*
X108940D01*
Y1215945D01*
X108957Y1215983D01*
G03Y1217743I-2018J880D01*
G01X108940Y1217781D01*
Y1220464D01*
X104938D01*
Y1219064D01*
X104672D01*
X104645Y1219073D01*
G03X101714Y1216584I-646J-2210D01*
G02X101275Y1216137I-397J-49D01*
G03X103134Y1212063I-276J-2587D01*
G01X103194Y1212148D01*
X104937D01*
Y1207654D01*
X104851Y1207594D01*
G03X104286Y1207036I1311J-1892D01*
G01X104226Y1206952D01*
X100418D01*
X98598Y1205131D01*
Y1204745D01*
X98512Y1204685D01*
G03X101500Y1200425I1487J-2135D01*
G01X101552Y1200462D01*
X103331D01*
X103388Y1200356D01*
G03X103548Y1200113I1412J756D01*
G03X103203Y1199247I1251J-1000D01*
G01X103197Y1199174D01*
X102294Y1198271D01*
X102245Y1198257D01*
G03X103546Y1193840I655J-2207D01*
G01X103573Y1193848D01*
X104098D01*
X104172Y1193923D01*
G02X104832Y1193775I283J-283D01*
G03X104936Y1193529I2168J772D01*
G02X104577Y1192952I-358J-177D01*
G01X82580D01*
X79283Y1196248D01*
X79292Y1196341D01*
G03X77208Y1194257I-2293J209D01*
G01X77301Y1194266D01*
X81418Y1190148D01*
X115080D01*
X116900Y1191969D01*
Y1195355D01*
X116986Y1195415D01*
G03X117633Y1199039I-1487J2135D01*
G01X117597Y1199090D01*
Y1199469D01*
X116605Y1200462D01*
X116382D01*
X113580Y1203264D01*
X111618D01*
X111559Y1203359D01*
G03X111000Y1203900I-1360J-846D01*
G01X110900Y1203957D01*
Y1206761D01*
X111501D01*
Y1212570D01*
X112193Y1213262D01*
X114060D01*
Y1220464D01*
X113400D01*
Y1221769D01*
X113500Y1221826D01*
G03X113939Y1222200I-802J1386D01*
G02X114559I310J-253D01*
G03X114998Y1221826I1241J1012D01*
G01X115098Y1221769D01*
Y1215052D01*
X115083Y1215017D01*
G03X119404Y1212278I2416J-967D01*
G02X120097Y1212005I293J-272D01*
G01Y1211551D01*
X121898D01*
Y1209095D01*
X121812Y1209035D01*
G03X124786I1487J-2135D01*
G01X124700Y1209095D01*
Y1211551D01*
X126501D01*
Y1212152D01*
X126834D01*
X128793Y1214111D01*
X132107D01*
X134188Y1212030D01*
X134111Y1211898D01*
G03X133898Y1211100I1388J-798D01*
G01Y1209700D01*
G03X133987Y1209174I1602J1D01*
G01X133998Y1209142D01*
Y1207895D01*
X133913Y1207835D01*
G03X137522Y1204195I1486J-2135D01*
G02X138248Y1203963I326J-232D01*
G01Y1202558D01*
X138368Y1202439D01*
X138350Y1202336D01*
G03X141227Y1204461I2561J-458D01*
G01X141052Y1204482D01*
Y1208281D01*
X141146Y1208340D01*
G03X141902Y1209700I-845J1360D01*
G01Y1211100D01*
G03X141663Y1211940I-1602J-2D01*
G02X142004Y1212550I341J210D01*
G01X174999D01*
X178499Y1216050D01*
Y1272915D01*
G02X178988Y1273305I400J0D01*
G03X179290Y1277843I510J2245D01*
G01X179197Y1277834D01*
X178499Y1278532D01*
Y1283500D01*
X183499Y1288500D01*
Y1309050D01*
X181999Y1310550D01*
X152500D01*
X150750Y1308800D01*
X143907D01*
X143882Y1308807D01*
G03X143467Y1308862I-416J-1547D01*
G01X141867D01*
G03X141452Y1308807I1J-1602D01*
G01X141427Y1308800D01*
X134877D01*
X134821Y1308846D01*
G03X133800Y1309214I-1021J-1233D01*
G01X132198D01*
G03X131177Y1308846I0J-1601D01*
G01X131121Y1308800D01*
G37*
G36*
G01X60884Y611110D02*
X63522Y608472D01*
X69954D01*
X71023Y609541D01*
X74775D01*
Y610542D01*
X75505D01*
X75541Y610387D01*
G03X77101Y609148I1560J363D01*
G01X78501D01*
G03X78620Y609153I-8J1602D01*
G02X79050Y608754I30J-399D01*
G01Y607922D01*
X79041Y607895D01*
G03X81122Y604951I2210J-646D01*
G02X81499Y604551I-23J-399D01*
G01Y588322D01*
G02X80874Y587991I-400J0D01*
G03X75895Y579679I-2725J-4015D01*
G02X75992Y579043I-186J-354D01*
G01X70999Y574050D01*
X39999D01*
X37999Y576050D01*
Y583246D01*
X50628D01*
X58802Y591419D01*
Y608471D01*
X58895Y608530D01*
G03X60201Y610836I-1495J2370D01*
G02X60884Y611110I400J-9D01*
G37*
G36*
G01X46466Y587298D02*
X55316Y596149D01*
G02X55998Y595866I282J-283D01*
G01Y592581D01*
X49466Y586048D01*
X37999D01*
Y587298D01*
X46466D01*
G37*
G36*
G01X45499Y1904550D02*
X38499Y1911550D01*
Y1912161D01*
G02X38840Y1912302I200J0D01*
G01X39185Y1911958D01*
X39200Y1911922D01*
G03X40729Y1915387I2397J1012D01*
G01X40610Y1915345D01*
X38600Y1917355D01*
Y1918850D01*
G03X38510Y1919380I-1601J1D01*
G01X38499Y1919412D01*
Y1920188D01*
X38510Y1920220D01*
G03X38600Y1920750I-1511J529D01*
G01Y1922148D01*
X42221D01*
X42278Y1922099D01*
G03X43592Y1926620I1721J1951D01*
G02X43247Y1927298I-62J395D01*
G01X43999Y1928050D01*
Y1929048D01*
X44000Y1929049D01*
Y1933668D01*
X44200D01*
Y1937200D01*
X45000Y1938000D01*
X56500D01*
Y1938051D01*
X69499Y1951050D01*
X84499D01*
X89499Y1946050D01*
Y1917050D01*
X84999Y1912550D01*
X72999D01*
X68474Y1908026D01*
X58026D01*
X58000Y1908000D01*
X52500D01*
X52000Y1907500D01*
Y1905500D01*
X51050Y1904550D01*
X45499D01*
G37*
G36*
G01X55475Y1941525D02*
X35024D01*
X31499Y1945050D01*
Y1951550D01*
X32499Y1952550D01*
X56950D01*
X59000Y1950500D01*
Y1945050D01*
X55475Y1941525D01*
G37*
G36*
G01X106549Y1581100D02*
X54949D01*
X49999Y1586050D01*
Y1601050D01*
X52499Y1603550D01*
X108499D01*
X109499Y1602550D01*
Y1584050D01*
X106549Y1581100D01*
G37*
G36*
G01X80980Y1626979D02*
Y1638551D01*
G03X78716Y1644014I-7726J-1D01*
G01X77332Y1645398D01*
G02X77656Y1646079I283J283D01*
G03X80248Y1646530I495J4827D01*
G01X80289Y1646550D01*
X85867D01*
X95598Y1636819D01*
Y1634479D01*
X95504Y1634420D01*
G03X98494I1495J-2370D01*
G01X98400Y1634479D01*
Y1637981D01*
X96514Y1639867D01*
G02X96797Y1640550I283J283D01*
G01X129500D01*
X129850Y1640200D01*
X129900D01*
X130000Y1640100D01*
Y1635100D01*
X130050Y1635050D01*
Y1616600D01*
X126000Y1612550D01*
X45499D01*
X43499Y1614550D01*
Y1619978D01*
X72719D01*
G03X79190Y1622659I-1J9152D01*
G03X80980Y1626979I-4320J4321D01*
G37*
G36*
G01X43499Y1624082D02*
Y1629999D01*
X60050Y1646550D01*
X70551D01*
X70611Y1646474D01*
G03X71909Y1645017I13276J10521D01*
G01X75814Y1641112D01*
G02X76876Y1638551I-2561J-2563D01*
G01Y1626980D01*
G02X76288Y1625561I-2006J0D01*
G02X72718Y1624082I-3570J3569D01*
G01X43499D01*
G37*
G36*
G01X114001Y1899752D02*
X110751Y1896502D01*
X110198D01*
Y1895948D01*
X108298Y1894048D01*
Y1893848D01*
X106999Y1892550D01*
Y1866550D01*
X104499Y1864050D01*
X80499D01*
X79499Y1865050D01*
Y1874550D01*
X76499Y1877550D01*
X55999D01*
X54999Y1878550D01*
Y1899223D01*
X55121Y1899274D01*
G03X56100Y1900750I-623J1476D01*
G01Y1902350D01*
G03Y1902390I-1601J20D01*
G02X56500Y1902800I400J10D01*
G01X57749D01*
X58974Y1904025D01*
X73525D01*
X77000Y1907500D01*
X86000D01*
X94000Y1915500D01*
X93974Y1915526D01*
Y1947526D01*
X100499Y1954050D01*
X133999D01*
X137499Y1950550D01*
Y1910550D01*
X131499Y1904550D01*
X118999D01*
X114200Y1899752D01*
X114001D01*
G37*
G36*
G01X44200Y1954550D02*
Y1956752D01*
X45999Y1958550D01*
Y1961150D01*
X46020Y1961193D01*
G03X46200Y1961955I-1521J762D01*
G01Y1963174D01*
X46223Y1963217D01*
G03X46400Y1963950I-1424J732D01*
G01Y1965550D01*
G03X46379Y1965812I-1601J3D01*
G01X46362Y1965913D01*
X49398Y1968948D01*
X51299D01*
G03X52493Y1969483I-1J1602D01*
G01X52553Y1969550D01*
X96999D01*
X99499Y1972050D01*
X108999D01*
X112499Y1968550D01*
Y1959050D01*
X110999Y1957550D01*
X94499D01*
X91499Y1954550D01*
X44200D01*
G37*
G36*
G01X100499Y47950D02*
X91532D01*
Y48642D01*
X81806D01*
X79999Y50450D01*
Y52450D01*
X81188Y53640D01*
X91532D01*
Y53926D01*
X92489D01*
X92512Y53950D01*
X99999D01*
X101598Y52352D01*
Y49048D01*
X100499Y47950D01*
G37*
G36*
G01X85649Y34400D02*
X80999Y39050D01*
Y46550D01*
X81499Y47050D01*
X81700D01*
X82001Y46748D01*
X100452D01*
X101400Y45800D01*
Y36200D01*
X99600Y34400D01*
X85649D01*
G37*
G36*
G01X77499Y68050D02*
X72999D01*
X71499Y69550D01*
Y76050D01*
X72499Y77050D01*
X89499D01*
X89999Y76550D01*
Y70550D01*
X89499Y70050D01*
X79499D01*
X77499Y68050D01*
G37*
G36*
G01X89499Y79550D02*
X71999D01*
X70999Y80550D01*
Y85550D01*
X71999Y86550D01*
X77499D01*
X77999Y86050D01*
Y83050D01*
X78499Y82550D01*
X88999D01*
X89999Y81550D01*
Y80050D01*
X89499Y79550D01*
G37*
G36*
G01X102499Y445050D02*
X101000Y443552D01*
X82698D01*
X80900Y445349D01*
Y453252D01*
X81699Y454050D01*
X101999D01*
X102499Y453550D01*
Y445050D01*
G37*
G36*
G01X81098Y455252D02*
X80900Y455448D01*
Y458552D01*
X81299Y458950D01*
X91899D01*
X93999Y461050D01*
X101999D01*
X102499Y460550D01*
Y455750D01*
X102001Y455252D01*
X81098D01*
G37*
G36*
G01X99999Y485050D02*
X81499D01*
X80999Y485550D01*
Y488050D01*
X81499Y488550D01*
X91999D01*
X93999Y490550D01*
X101499D01*
X102999Y489050D01*
Y488050D01*
X99999Y485050D01*
G37*
G36*
G01X100499Y475550D02*
X81499D01*
X80999Y476050D01*
Y482550D01*
X81499Y483050D01*
X100499D01*
X100999Y482550D01*
Y476050D01*
X100499Y475550D01*
G37*
G36*
G01X76688Y821148D02*
X78048Y819788D01*
Y817469D01*
X78216Y817302D01*
X78207Y817209D01*
G03X78557Y815766I2293J-208D01*
G02X78219Y815152I-338J-214D01*
G01X69800D01*
Y816600D01*
X68110D01*
G02X67723Y817104I-1J400D01*
G03X65415Y820000I-2223J596D01*
G02X65000Y820400I-15J400D01*
G01Y821148D01*
X76688D01*
G37*
G36*
G01X80499Y1118050D02*
X73499Y1125050D01*
Y1150700D01*
X75699Y1152900D01*
X98648D01*
Y1152898D01*
X106102D01*
X107400Y1151600D01*
Y1140900D01*
X105800Y1139300D01*
X100700D01*
X97999Y1136599D01*
Y1136032D01*
X97998Y1136031D01*
Y1121051D01*
X95848Y1118902D01*
Y1118900D01*
X94999Y1118050D01*
X80499D01*
G37*
G36*
G01X145999Y1133550D02*
X123999Y1155550D01*
X77650D01*
X75499Y1157701D01*
Y1179050D01*
X76999Y1180550D01*
X95499D01*
X99499Y1176550D01*
X100300D01*
X100501Y1176348D01*
X138151D01*
X138800Y1175700D01*
Y1158249D01*
X155999Y1141050D01*
Y1134550D01*
X154999Y1133550D01*
X145999D01*
G37*
G36*
G01X101638Y1237752D02*
X98860D01*
X79999Y1256613D01*
Y1263613D01*
X80999Y1264613D01*
X90499D01*
X91499Y1263613D01*
Y1257613D01*
X101999Y1247113D01*
X109999D01*
X111999Y1249113D01*
Y1260613D01*
X112999Y1261613D01*
X140499D01*
X146986Y1268100D01*
X151800D01*
X152999Y1266901D01*
Y1239550D01*
X149999Y1236550D01*
X135999D01*
X134936Y1237613D01*
X133135D01*
X132997Y1237752D01*
X106360D01*
X106305Y1237796D01*
G03X105299Y1238152I-1007J-1246D01*
G01X102699D01*
G03X101693Y1237796I1J-1602D01*
G01X101638Y1237752D01*
G37*
G36*
G01X108999Y1250113D02*
X107999Y1249113D01*
X102499D01*
X92999Y1258613D01*
Y1264613D01*
X91499Y1266113D01*
X80499D01*
X79999Y1266613D01*
Y1269613D01*
X80499Y1270113D01*
X95999D01*
X104499Y1261613D01*
X107999D01*
X108999Y1260613D01*
Y1250113D01*
G37*
G36*
G01X123499Y1280113D02*
Y1272550D01*
X122999Y1272050D01*
X99062D01*
X92499Y1278613D01*
Y1284613D01*
X91499Y1285613D01*
X80999D01*
X80499Y1286113D01*
Y1294113D01*
X80999Y1294613D01*
X93999D01*
X100499Y1288113D01*
Y1282613D01*
X101999Y1281113D01*
X109999D01*
X111499Y1282613D01*
Y1293613D01*
X112999Y1295113D01*
X142187D01*
X143400Y1293900D01*
Y1286800D01*
X142701Y1286102D01*
X135648D01*
Y1285400D01*
X128786D01*
X123499Y1280113D01*
G37*
G36*
G01X108499Y1282613D02*
X102999D01*
X101999Y1283613D01*
Y1288613D01*
X94499Y1296113D01*
X80999D01*
X80499Y1296613D01*
Y1299113D01*
X80999Y1299613D01*
X97499D01*
X102999Y1294113D01*
X108499D01*
X108999Y1293613D01*
Y1283113D01*
X108499Y1282613D01*
G37*
G36*
G01X139352Y1643931D02*
Y1644802D01*
X130448D01*
Y1642613D01*
X93768D01*
X88500Y1647881D01*
Y1651831D01*
X79499Y1660832D01*
Y1669113D01*
X80499Y1670113D01*
X89999D01*
X90999Y1669113D01*
Y1663113D01*
X101999Y1652113D01*
X112999D01*
X114499Y1653613D01*
Y1664113D01*
X115999Y1665613D01*
X161436D01*
X161999Y1665050D01*
Y1651550D01*
X161249Y1650800D01*
X147186D01*
X140034Y1643648D01*
G02X139352Y1643931I-282J283D01*
G37*
G36*
G01X110999Y1654613D02*
X109999Y1653613D01*
X102999D01*
X92499Y1664113D01*
Y1670113D01*
X90999Y1671613D01*
X79999D01*
X79499Y1672113D01*
Y1675113D01*
X79999Y1675613D01*
X95499D01*
X105499Y1665613D01*
X109999D01*
X110999Y1664613D01*
Y1654613D01*
G37*
G36*
G01Y1688113D02*
X109999Y1687113D01*
X102999D01*
X101499Y1688613D01*
Y1694113D01*
X93999Y1701613D01*
X80499D01*
X79999Y1702113D01*
Y1704613D01*
X80499Y1705113D01*
X97999D01*
X103999Y1699113D01*
X109999D01*
X110999Y1698113D01*
Y1688113D01*
G37*
G36*
G01X133763Y1697758D02*
X134145D01*
X134287Y1697900D01*
X135100D01*
X135400Y1697600D01*
Y1691800D01*
X124499Y1680899D01*
Y1677113D01*
X123499Y1676113D01*
X107361D01*
X107329Y1676124D01*
G03X106800Y1676214I-529J-1511D01*
G01X106799D01*
X104199D01*
X104198D01*
G03X103669Y1676124I0J-1601D01*
G01X103637Y1676113D01*
X99999D01*
X91999Y1684113D01*
Y1690113D01*
X91532Y1690580D01*
Y1690690D01*
X91422D01*
X90999Y1691113D01*
X80499D01*
X79999Y1691613D01*
Y1699613D01*
X80499Y1700113D01*
X93499D01*
X99999Y1693613D01*
Y1688113D01*
X102499Y1685613D01*
X111999D01*
X112999Y1686613D01*
Y1698113D01*
X113999Y1699113D01*
X128999D01*
X130212Y1697900D01*
X132060D01*
X132100Y1697881D01*
G03X133736Y1697749I991J2078D01*
G01X133763Y1697758D01*
G37*
G36*
G01X91285Y1114867D02*
X90798Y1114381D01*
Y1107919D01*
X92269Y1106448D01*
X97999D01*
Y1105050D01*
X100499Y1102550D01*
X105499D01*
X106499Y1101550D01*
Y1101112D01*
X106148D01*
Y1097108D01*
X106499D01*
Y1096050D01*
X107499Y1095050D01*
X111598D01*
Y1093050D01*
X99999D01*
X98499Y1091550D01*
Y1089550D01*
X98100Y1089152D01*
X96799D01*
G03X96269Y1089061I2J-1602D01*
G01X96237Y1089050D01*
X88999D01*
X86999Y1091050D01*
Y1096135D01*
X87010Y1096167D01*
G03X87102Y1096700I-1510J535D01*
G01Y1098300D01*
G03X87010Y1098833I-1602J-2D01*
G01X86999Y1098865D01*
Y1110135D01*
X87010Y1110167D01*
G03X87102Y1110700I-1510J535D01*
G01Y1112300D01*
G03X87010Y1112833I-1602J-2D01*
G01X86999Y1112865D01*
Y1115050D01*
X87499Y1115550D01*
X91002D01*
G02X91285Y1114867I0J-400D01*
G37*
G36*
G01X100400Y1114300D02*
X99602Y1115098D01*
Y1116100D01*
G03X99245Y1117108I-1602J0D01*
G01X99200Y1117163D01*
Y1118289D01*
X100800Y1119889D01*
Y1132352D01*
X100999Y1132550D01*
X113777D01*
X113803Y1132543D01*
G03X115195I696J2507D01*
G01X115221Y1132550D01*
X117999D01*
X119499Y1131050D01*
Y1118050D01*
X118499Y1117050D01*
X108550D01*
X108498Y1117087D01*
G03X104639Y1116057I-1499J-2127D01*
G01X104624Y1116024D01*
X102900Y1114300D01*
X100400D01*
G37*
G36*
G01X109261Y1262050D02*
X108497Y1262814D01*
X106234D01*
X102499Y1266550D01*
Y1268550D01*
X103148Y1269198D01*
X125850D01*
X126124Y1268925D01*
X127091D01*
X127816Y1268200D01*
X127919D01*
X127920Y1268198D01*
X135701D01*
X135999Y1267901D01*
Y1262814D01*
X112501D01*
X111737Y1262050D01*
X109261D01*
G37*
G36*
G01X85700Y1568548D02*
X83900Y1570348D01*
Y1576898D01*
X91752D01*
Y1579050D01*
X112499D01*
X117499Y1584050D01*
Y1596550D01*
X124999Y1604050D01*
X131499D01*
X133149Y1602400D01*
X132851Y1602102D01*
X132248D01*
Y1601498D01*
X131298Y1600548D01*
Y1562550D01*
X91150D01*
X91050Y1562650D01*
X91048Y1562652D01*
G03X90952Y1562748I-1675J-1579D01*
G01X90950Y1562750D01*
X85700Y1568000D01*
Y1568548D01*
G37*
G36*
G01X115237Y1666550D02*
X110761D01*
X110497Y1666814D01*
X106234D01*
X101999Y1671050D01*
Y1674550D01*
X102360Y1674912D01*
X123997D01*
X124135Y1675050D01*
X135499D01*
X137499Y1673050D01*
Y1667050D01*
X137264Y1666814D01*
X115501D01*
X115237Y1666550D01*
G37*
G36*
G01X109999Y38550D02*
X107999Y40550D01*
Y69550D01*
X110999Y72550D01*
X173737D01*
X173769Y72539D01*
G03X174299Y72448I532J1511D01*
G01X175699D01*
G03X176229Y72539I-2J1602D01*
G01X176261Y72550D01*
X177637D01*
X177669Y72539D01*
G03X178199Y72448I532J1511D01*
G01X179799D01*
G03X180329Y72539I-2J1602D01*
G01X180361Y72550D01*
X181137D01*
X181169Y72539D01*
G03X181699Y72448I532J1511D01*
G01X183299D01*
G03X183829Y72539I-2J1602D01*
G01X183861Y72550D01*
X189771D01*
X189827Y72503D01*
G03X193171I1672J1994D01*
G01X193227Y72550D01*
X201999D01*
X202924Y71624D01*
Y60376D01*
X202999D01*
Y59050D01*
X182499Y38550D01*
X109999D01*
G37*
G36*
G01X108499Y74550D02*
X107499Y75550D01*
Y114550D01*
X111499Y118550D01*
X184237D01*
X184269Y118539D01*
G03X184799Y118448I532J1511D01*
G01X186199D01*
G03X186729Y118539I-2J1602D01*
G01X186761Y118550D01*
X186999D01*
X187499Y118050D01*
Y108050D01*
X180999Y101550D01*
Y100412D01*
X180988Y100380D01*
G03X180898Y99850I1511J-529D01*
G01Y98448D01*
X180499Y98050D01*
X174499D01*
X170999Y94550D01*
Y77050D01*
X168499Y74550D01*
X108499D01*
G37*
G36*
G01X185499Y481301D02*
Y455050D01*
X183999Y453550D01*
X175499D01*
X172352Y456698D01*
Y456802D01*
X172248D01*
X170999Y458050D01*
X128999D01*
X128949Y458000D01*
X123400D01*
X123100Y458300D01*
Y464800D01*
X125350Y467050D01*
X142499D01*
X143298Y467848D01*
X144200D01*
Y468752D01*
X155999Y480550D01*
X174300D01*
X176250Y482500D01*
X184300D01*
X185499Y481301D01*
G37*
G36*
G01X155499Y1128550D02*
X141499D01*
X128999Y1141050D01*
X112499D01*
X111499Y1142050D01*
Y1145050D01*
X112999Y1146550D01*
X128999D01*
X143999Y1131550D01*
X155499D01*
X155999Y1131050D01*
Y1129050D01*
X155499Y1128550D01*
G37*
G36*
G01X115499Y1299548D02*
X118802Y1302850D01*
Y1302852D01*
X119499Y1303550D01*
Y1306050D01*
X120748Y1307298D01*
X121730D01*
X121981Y1307550D01*
X149999D01*
X150999Y1306550D01*
Y1298050D01*
X149499Y1296550D01*
X116499D01*
X115499Y1297550D01*
Y1299548D01*
G37*
G36*
G01X111999Y1310550D02*
X109999Y1312550D01*
Y1319962D01*
X114380D01*
X114439Y1319867D01*
G03X115799Y1319112I1360J847D01*
G01X116086D01*
Y1315402D01*
X115497D01*
Y1310550D01*
X111999D01*
G37*
G36*
G01X122499Y1718550D02*
X120999Y1720050D01*
Y1723050D01*
X113499Y1730550D01*
Y1735050D01*
X115298Y1736848D01*
X121787D01*
X121846Y1736756D01*
G03X123199Y1736012I1353J858D01*
G01X124799D01*
G03X126152Y1736756I0J1602D01*
G01X126211Y1736848D01*
X136078D01*
X136113Y1736834D01*
G03X136704Y1736722I588J1489D01*
G01X138304D01*
G03X138895Y1736834I3J1601D01*
G01X138930Y1736848D01*
X146001D01*
X146501Y1736348D01*
X146700D01*
X148499Y1734550D01*
Y1728050D01*
X145499Y1725050D01*
Y1723812D01*
X145488Y1723780D01*
G03X145398Y1723250I1511J-529D01*
G01Y1721948D01*
X144999Y1721550D01*
X143231D01*
X142499Y1722282D01*
Y1725050D01*
X141999Y1725550D01*
X135999D01*
X134999Y1724550D01*
Y1720550D01*
X132999Y1718550D01*
X122499D01*
G37*
G36*
G01X138499Y1957550D02*
X116999D01*
X115999Y1958550D01*
Y1979499D01*
X118000Y1981500D01*
X137500D01*
X139499Y1979501D01*
Y1958550D01*
X138499Y1957550D01*
G37*
G36*
G01X135400Y423897D02*
G03X135398Y423813I1599J-80D01*
G01Y422413D01*
G03X135400Y422329I1601J-4D01*
G01Y421002D01*
X134251D01*
X132800Y419550D01*
X126999D01*
X125999Y420550D01*
Y432235D01*
X126010Y432267D01*
G03X126102Y432800I-1510J535D01*
G01Y434400D01*
G03X126010Y434933I-1602J-2D01*
G01X125999Y434965D01*
Y435799D01*
X127700Y437500D01*
X129599D01*
X130999Y438900D01*
Y442050D01*
X131499Y442550D01*
X132777D01*
X132803Y442543D01*
G03X134195I696J2507D01*
G01X134221Y442550D01*
X135896D01*
X135949Y442511D01*
G03X138613Y442248I1551J2089D01*
G01X138741Y442308D01*
X139499Y441550D01*
X140449D01*
X140470Y441546D01*
G03X140799Y441512I328J1567D01*
G01X142038D01*
X142499Y441050D01*
Y438550D01*
X144999Y436050D01*
X145999D01*
X146499Y435550D01*
Y431050D01*
X145914Y430464D01*
X143438D01*
Y430050D01*
X136499D01*
X135400Y428951D01*
Y427897D01*
G03X135398Y427813I1599J-80D01*
G01Y426413D01*
G03X135400Y426329I1601J-4D01*
G01Y423897D01*
G37*
G36*
G01X150299Y446114D02*
X150298D01*
G03X149135Y445613I0J-1601D01*
G01X149076Y445550D01*
X148422D01*
X148363Y445613D01*
G03X147200Y446114I-1163J-1100D01*
G01X147199D01*
X145799D01*
X145798D01*
G03X144635Y445613I0J-1601D01*
G01X144576Y445550D01*
X143422D01*
X143363Y445613D01*
G03X142200Y446114I-1163J-1100D01*
G01X142199D01*
X140799D01*
G03X139989Y445894I0J-1601D01*
G02X139717Y445962I-101J173D01*
G03X134901Y444470I-2217J-1362D01*
G02X134502Y444050I-399J-20D01*
G01X126999D01*
X125999Y445050D01*
Y454799D01*
X127900Y456700D01*
X170300D01*
X171300Y455700D01*
Y450600D01*
X170250Y449550D01*
X168150D01*
X168124Y449557D01*
G03X167699Y449614I-423J-1544D01*
G01X166299D01*
G03X165874Y449557I-2J-1601D01*
G01X165848Y449550D01*
X164150D01*
X164124Y449557D01*
G03X163699Y449614I-423J-1544D01*
G01X162299D01*
G03X161874Y449557I-2J-1601D01*
G01X161848Y449550D01*
X159300D01*
X157499Y447749D01*
Y447341D01*
X157483Y447303D01*
G03Y445495I2117J-904D01*
G01X157499Y445457D01*
Y444599D01*
X156900Y444000D01*
X154000D01*
X153600Y444400D01*
Y444450D01*
X153281Y444769D01*
X153269Y444828D01*
G03X151699Y446114I-1570J-315D01*
G01X150299D01*
G37*
G36*
G01X140508Y482050D02*
X142499D01*
X143499Y481050D01*
Y469749D01*
X142750Y469000D01*
X132300D01*
X130999Y470301D01*
Y480050D01*
X132999Y482050D01*
X137892D01*
X137937Y482025D01*
G03X140463I1263J2275D01*
G01X140508Y482050D01*
G37*
G36*
G01X149100Y483050D02*
X143198D01*
X142997Y483252D01*
X134298D01*
X132999Y484550D01*
Y488550D01*
X134999Y490550D01*
X149000D01*
X150300Y489250D01*
Y484250D01*
X149100Y483050D01*
G37*
G36*
G01X161200Y482100D02*
X152500D01*
X151800Y482800D01*
Y489350D01*
X151502Y489648D01*
Y489748D01*
X150950Y490299D01*
Y490314D01*
X150935D01*
X149498Y491752D01*
X149398D01*
X149100Y492050D01*
X136499D01*
X133999Y494550D01*
Y499050D01*
X135999Y501050D01*
X144499D01*
X157499Y514050D01*
X161499D01*
X161999Y513550D01*
Y482899D01*
X161200Y482100D01*
G37*
G36*
G01X136298Y502252D02*
X134499Y504050D01*
Y513550D01*
X135499Y514550D01*
X147499D01*
X147999Y514050D01*
Y506249D01*
X144001Y502252D01*
X136298D01*
G37*
G36*
G01X161975Y529358D02*
X159768Y527152D01*
X158699D01*
G03X157098Y525550I0J-1601D01*
G01Y524150D01*
G03X157521Y523066I1600J0D01*
G02X157481Y522486I-295J-271D01*
G03X157139Y522096I1017J-1237D01*
G01X157080Y522002D01*
X156530D01*
X154273Y524258D01*
X154284Y524354D01*
G03X150440Y526927I-2585J296D01*
G02X149853Y527200I-194J350D01*
G03X145567Y528641I-2553J-500D01*
G02X144900Y528939I-267J298D01*
G01Y535181D01*
X144824Y535257D01*
G02X144965Y535598I141J141D01*
G01X145700D01*
G03X146960Y536045I-1J2002D01*
G02X147239Y536018I126J-156D01*
G03X150769Y536027I1761J1482D01*
G01X150829Y536098D01*
X152080D01*
X153730Y537748D01*
X154030D01*
Y537477D01*
X153985Y537422D01*
G03X158396Y536788I2014J-1647D01*
G01X158343Y536912D01*
X158950Y537519D01*
Y537931D01*
X159045Y537990D01*
G03X159800Y539350I-847J1360D01*
G01Y539698D01*
X165700D01*
G02X165983Y539016I0J-400D01*
G01X165034Y538068D01*
Y537490D01*
X161975D01*
Y529358D01*
G37*
G36*
G01X140770Y519837D02*
G02X140291Y519637I-357J181D01*
G03X139799Y519714I-491J-1524D01*
G01X138199D01*
G03X137959Y519696I-1J-1601D01*
G02X137499Y520092I-60J396D01*
G01Y522937D01*
X137528Y522985D01*
G03Y525673I-2228J1344D01*
G01X137499Y525721D01*
Y526708D01*
X137588Y526767D01*
G03X138302Y528100I-887J1333D01*
G01Y528428D01*
G02X138989Y528706I400J0D01*
G03X140425Y528098I1437J1394D01*
G01X141825D01*
G03X141891Y528100I-28J2001D01*
G01X141894D01*
X142098D01*
Y526320D01*
X141931Y526292D01*
G03X140598Y524713I269J-1579D01*
G01Y522113D01*
G03X141139Y520913I1601J0D01*
G02Y520313I-265J-300D01*
G03X140770Y519837I1059J-1202D01*
G37*
G36*
G01X249600Y696500D02*
X248851Y695752D01*
X237364D01*
X237362Y695754D01*
X232946D01*
X226999Y701701D01*
Y709050D01*
X224999Y711050D01*
X204999D01*
X191499Y697550D01*
X145499D01*
X144999Y698050D01*
Y705050D01*
X145999Y706050D01*
X181499D01*
X196999Y721550D01*
X235999D01*
X237499Y720050D01*
Y713050D01*
X240999Y709550D01*
Y705100D01*
X242348Y703751D01*
Y702398D01*
X249600D01*
Y696500D01*
G37*
G36*
G01X196499Y693050D02*
X145999D01*
X144999Y694050D01*
Y695050D01*
X145999Y696050D01*
X191999D01*
X204999Y709050D01*
X221999D01*
X222999Y708050D01*
Y698550D01*
X222499Y698050D01*
X201499D01*
X196499Y693050D01*
G37*
G36*
G01X197999Y731550D02*
X188999Y722550D01*
X145499D01*
X144999Y723050D01*
Y725550D01*
X145999Y726550D01*
X181499D01*
X197499Y742550D01*
X221999D01*
X222499Y742050D01*
Y732050D01*
X221999Y731550D01*
X197999D01*
G37*
G36*
G01X179499Y728050D02*
X145499D01*
X144499Y729050D01*
Y735050D01*
X145499Y736050D01*
X166999D01*
X184999Y754050D01*
X242948D01*
Y753798D01*
X251852D01*
Y754050D01*
X270999D01*
X274499Y750550D01*
Y731050D01*
X273999Y730550D01*
X231999D01*
X230999Y731550D01*
Y741050D01*
X227999Y744050D01*
X195499D01*
X179499Y728050D01*
G37*
G36*
G01X135981Y1219050D02*
X134957Y1220074D01*
X134499D01*
Y1225550D01*
X133995Y1226054D01*
X133986Y1226066D01*
G03X133652Y1226400I-1287J-953D01*
G01X133640Y1226409D01*
X133499Y1226550D01*
X133407D01*
X133368Y1226568D01*
G03X132699Y1226714I-668J-1455D01*
G01X131299D01*
G03X130630Y1226568I-1J-1601D01*
G01X130591Y1226550D01*
X128907D01*
X128868Y1226568D01*
G03X128199Y1226714I-668J-1455D01*
G01X126799D01*
G03X126490Y1226684I-1J-1601D01*
G01X126385Y1226664D01*
X126200Y1226848D01*
Y1229052D01*
X126698Y1229550D01*
X133499D01*
X133860Y1229912D01*
X133950D01*
Y1230002D01*
X134999Y1231050D01*
Y1233050D01*
X135999Y1234050D01*
X149499D01*
X150499Y1233050D01*
Y1220050D01*
X149499Y1219050D01*
X135981D01*
G37*
G36*
G01X128999Y1271050D02*
X127499Y1272550D01*
Y1281912D01*
X127700D01*
Y1282252D01*
X128999Y1283550D01*
X135648D01*
Y1283498D01*
X143552D01*
Y1283550D01*
X166999D01*
X167999Y1282550D01*
Y1272550D01*
X166499Y1271050D01*
X128999D01*
G37*
G36*
G01X171999Y1622050D02*
X134550D01*
X131400Y1625200D01*
Y1640300D01*
X132100Y1641000D01*
X140449D01*
X142499Y1643050D01*
X172499D01*
X173999Y1641550D01*
Y1624050D01*
X171999Y1622050D01*
G37*
G36*
G01X137143Y1700756D02*
X138200Y1701813D01*
Y1701814D01*
X144499Y1708113D01*
X167999D01*
X168999Y1707113D01*
Y1696113D01*
X168499Y1695613D01*
X158300D01*
X148635Y1685948D01*
X148534Y1685966D01*
G03X145534Y1682966I-434J-2566D01*
G01X145552Y1682865D01*
X138893Y1676206D01*
X136042D01*
X135997Y1676252D01*
X129860D01*
X129499Y1676613D01*
Y1683400D01*
X136748Y1690648D01*
X138202D01*
Y1698552D01*
X137143D01*
Y1700756D01*
G37*
G36*
G01X221499Y1901050D02*
X217499D01*
X208999Y1909550D01*
X146499D01*
X145499Y1910550D01*
Y1912050D01*
X145999Y1912550D01*
X221499D01*
X222499Y1911550D01*
Y1902050D01*
X221499Y1901050D01*
G37*
G36*
G01X239200Y1899000D02*
X237650Y1900550D01*
X229999D01*
X225999Y1904550D01*
Y1912550D01*
X223999Y1914550D01*
X145999D01*
X145499Y1915050D01*
Y1922050D01*
X145999Y1922550D01*
X164517D01*
X164518Y1922548D01*
X211747D01*
X211984Y1922312D01*
X216043D01*
X216243Y1922112D01*
X221360D01*
X221797Y1922548D01*
X228000D01*
X231001Y1925550D01*
X237999D01*
X238499Y1925050D01*
Y1917550D01*
X241499Y1914550D01*
Y1909900D01*
X243348Y1908050D01*
Y1906898D01*
X250701D01*
X251000Y1906600D01*
Y1904750D01*
X250798Y1904549D01*
Y1900798D01*
X249031Y1899031D01*
X248981Y1899017D01*
G03X248949Y1899008I607J-2220D01*
G01X248922Y1899000D01*
X239200D01*
G37*
G36*
G01X240499Y1937050D02*
X232499D01*
X231499Y1938050D01*
Y1945050D01*
X225499Y1951050D01*
X209999D01*
X203499Y1944550D01*
X146499D01*
X145499Y1945550D01*
Y1951550D01*
X146499Y1952550D01*
X197499D01*
X203499Y1958550D01*
X216800D01*
X217001Y1958348D01*
X239998D01*
X240199Y1958550D01*
X241948D01*
Y1957798D01*
X250852D01*
Y1958550D01*
X272999D01*
X274999Y1956550D01*
Y1941550D01*
X273499Y1940050D01*
X243499D01*
X240499Y1937050D01*
G37*
G36*
G01X221499Y1939050D02*
X219499Y1937050D01*
X204999D01*
X202499Y1939550D01*
X145999D01*
X145499Y1940050D01*
Y1941550D01*
X146499Y1942550D01*
X204999D01*
X211499Y1949050D01*
X220499D01*
X221499Y1948050D01*
Y1939050D01*
G37*
G36*
G01X171400Y436382D02*
X169530Y438252D01*
Y441019D01*
X169499Y441050D01*
Y445050D01*
X168995Y445554D01*
X168986Y445566D01*
G03X168652Y445900I-1287J-953D01*
G01X168640Y445909D01*
X168499Y446050D01*
X168407D01*
X168368Y446068D01*
G03X167699Y446214I-668J-1455D01*
G01X166299D01*
G03X165630Y446068I-1J-1601D01*
G01X165591Y446050D01*
X164407D01*
X164368Y446068D01*
G03X163699Y446214I-668J-1455D01*
G01X162334D01*
X161999Y446550D01*
Y448050D01*
X162298Y448348D01*
X170748D01*
X171798Y449398D01*
X172352D01*
Y449952D01*
X172512Y450113D01*
X173548D01*
Y449398D01*
X184652D01*
Y450113D01*
X184999D01*
X185999Y449113D01*
Y435113D01*
X184286Y433400D01*
X171400D01*
Y436382D01*
G37*
G36*
G01X173301Y512152D02*
G03X173387Y512237I-1575J1679D01*
G03X173421Y512270I-1516J1596D01*
G01X175200Y514050D01*
Y514052D01*
X176048Y514898D01*
X176049D01*
X180650Y519500D01*
Y519502D01*
X183498Y522348D01*
X184497D01*
X184761Y522613D01*
X201999D01*
X202999Y521613D01*
Y510752D01*
X187501D01*
X185298Y508548D01*
Y507412D01*
X170900Y493014D01*
Y492711D01*
X170844Y492653D01*
G03Y489453I1655J-1600D01*
G01X170900Y489395D01*
Y483778D01*
X170892Y483751D01*
G03X170798Y483082I2208J-651D01*
G01X170799Y482999D01*
X170100Y482300D01*
X164602D01*
Y489452D01*
X163999D01*
Y502850D01*
X173301Y512152D01*
G37*
G36*
G01X155499Y802050D02*
X150499Y807050D01*
Y830550D01*
X152481Y832532D01*
X152605Y832479D01*
G03X155696Y833910I895J2121D01*
G01X155740Y834050D01*
X164499D01*
X165546Y835097D01*
X165687Y834960D01*
G03X166799Y834512I1111J1153D01*
G01X168199D01*
G03X169063Y834764I2J1601D01*
G01X169198Y834851D01*
X169499Y834550D01*
Y824550D01*
X168999Y824050D01*
X166999D01*
X166914Y823964D01*
X165438D01*
Y821488D01*
X164499Y820550D01*
X160704D01*
X160680Y820556D01*
G03X160300Y820602I-381J-1556D01*
G01X158700D01*
G03X158320Y820556I1J-1602D01*
G01X158296Y820550D01*
X157400D01*
X156300Y819450D01*
Y811900D01*
X158200Y810000D01*
X173899D01*
X175499Y808400D01*
Y804050D01*
X173499Y802050D01*
X155499D01*
G37*
G36*
G01X178934Y836115D02*
X178800Y836248D01*
Y837513D01*
G03X177199Y839114I-1601J0D01*
G01X175934D01*
X173499Y841550D01*
X169108D01*
X169094Y841736D01*
G03X163904I-2595J-186D01*
G01X163890Y841550D01*
X155499D01*
X153499Y843550D01*
Y850550D01*
X157499Y854550D01*
X191499D01*
X191999Y854050D01*
Y850550D01*
X193149Y849400D01*
X192501Y848752D01*
X185001D01*
X183498Y847249D01*
Y844602D01*
X184016Y844085D01*
X183934Y843950D01*
G03X183698Y843113I1366J-837D01*
G01Y842044D01*
X183100Y841447D01*
Y836115D01*
X178934D01*
G37*
G36*
G01X169499Y877548D02*
G03Y877352I2600J-98D01*
G01Y868050D01*
X167999Y866550D01*
X155499D01*
X154499Y867550D01*
Y877550D01*
X155999Y879050D01*
X168499D01*
X169499Y878050D01*
Y877548D01*
G37*
G36*
G01X210450Y852550D02*
X195499D01*
X191499Y856550D01*
X154999D01*
X153999Y857550D01*
Y864550D01*
X154499Y865050D01*
X171499D01*
X173499Y867050D01*
Y874550D01*
X177999Y879050D01*
X200700D01*
X200725Y879075D01*
X209998D01*
Y871748D01*
X211600D01*
Y853700D01*
X210450Y852550D01*
G37*
G36*
G01X155600Y881952D02*
X154499Y883052D01*
Y887050D01*
X155499Y888050D01*
X193050D01*
X199618Y894618D01*
X199748Y894552D01*
G03X202568Y895127I1051J2048D01*
G01X202628Y895198D01*
X203218D01*
X203315Y895296D01*
G02X203997Y895013I282J-283D01*
G01X203998Y888902D01*
X201438D01*
Y883781D01*
X199608Y881952D01*
X155600D01*
G37*
G36*
G01X154499Y889550D02*
X153999Y890050D01*
Y897050D01*
X155499Y898550D01*
X168499D01*
X170999Y901050D01*
Y908050D01*
X175499Y912550D01*
X175500D01*
X177450Y914500D01*
X181350D01*
X181425Y914425D01*
X191575D01*
X192500Y913500D01*
Y907250D01*
X184798Y899548D01*
Y899348D01*
X184499Y899050D01*
Y893050D01*
X180999Y889550D01*
X156597D01*
G03X156401I-98J-2600D01*
G01X154499D01*
G37*
G36*
G01X154899Y899650D02*
X153999Y900550D01*
Y911050D01*
X155499Y912550D01*
X166499D01*
X167499Y911550D01*
Y901050D01*
X166264Y899814D01*
X165048D01*
Y899752D01*
X155001D01*
X154899Y899650D01*
G37*
G36*
G01X244800Y1095900D02*
X234500D01*
X233900Y1096500D01*
Y1106700D01*
X227800Y1112800D01*
X224899D01*
X224798Y1112902D01*
X207402D01*
X207301Y1112800D01*
X206300D01*
X197100Y1103600D01*
X146400D01*
X146100Y1103900D01*
Y1110400D01*
X146900Y1111200D01*
X188900D01*
X201900Y1124200D01*
X228548D01*
Y1123898D01*
X236452D01*
Y1124200D01*
X242800D01*
X246700Y1120300D01*
Y1097800D01*
X244800Y1095900D01*
G37*
G36*
G01X223400Y1096700D02*
X215700D01*
X213900Y1098500D01*
X146200D01*
X145900Y1098800D01*
Y1101100D01*
X146500Y1101700D01*
X197900D01*
X207900Y1111700D01*
X224300D01*
X225400Y1110600D01*
Y1098700D01*
X223400Y1096700D01*
G37*
G36*
G01X155499Y1214550D02*
X154999Y1215050D01*
Y1259248D01*
X156902D01*
Y1267800D01*
X172200D01*
X175499Y1264501D01*
Y1216050D01*
X173999Y1214550D01*
X155499D01*
G37*
G36*
G01X180999Y1288550D02*
X153999D01*
X152999Y1289550D01*
Y1306550D01*
X155499Y1309050D01*
X179999D01*
X181999Y1307050D01*
Y1289550D01*
X180999Y1288550D01*
G37*
G36*
G01X154999Y1712113D02*
X153999Y1713113D01*
Y1732113D01*
X155499Y1733613D01*
X174499D01*
X175798Y1732314D01*
Y1713412D01*
X174499Y1712113D01*
X154999D01*
G37*
G36*
G01X161910Y1810695D02*
G03X161699Y1816884I-3839J2967D01*
G02X161998Y1817550I299J266D01*
G01X259499D01*
X260499Y1816550D01*
Y1812050D01*
X258499Y1810050D01*
X162227D01*
G02X161910Y1810695I0J400D01*
G37*
G36*
G01X235641Y1928619D02*
G03X230399Y1929055I-2541J1181D01*
G01X230430Y1928943D01*
X229537Y1928050D01*
X227499D01*
X224800Y1925352D01*
X220635D01*
X220198Y1924914D01*
X217405D01*
X217205Y1925114D01*
X213146D01*
X212909Y1925352D01*
X166198D01*
X163999Y1927550D01*
Y1936050D01*
X164999Y1937050D01*
X202499D01*
X204073Y1935476D01*
X239924D01*
X240297Y1935848D01*
X240997D01*
X242698Y1937550D01*
X248999D01*
X250499Y1936050D01*
Y1932550D01*
X248499Y1930550D01*
X244499D01*
X241999Y1928050D01*
X236003D01*
G02X235641Y1928619I0J400D01*
G37*
G36*
G01X209999Y18550D02*
X187499D01*
X183999Y22050D01*
Y37050D01*
X195499Y48550D01*
X208999D01*
X211999Y45550D01*
Y20550D01*
X209999Y18550D01*
G37*
G36*
G01X189704Y486050D02*
X189645Y486110D01*
G03X188327Y486779I-1646J-1610D01*
G01X188261Y486788D01*
X187199Y487850D01*
X182099D01*
X180999Y488950D01*
Y491750D01*
X181698Y492448D01*
X182980D01*
X184766Y494235D01*
X184878Y494205D01*
G03X185299Y494148I423J1545D01*
G01X186699D01*
G03X188300Y495750I0J1601D01*
G01Y497150D01*
G03X186699Y498752I-1602J0D01*
G01X185299D01*
G03X185234Y498750I17J-1601D01*
G01X185230D01*
X182668D01*
X182664D01*
G03X182599Y498752I-82J-1599D01*
G01X181199D01*
G03X181134Y498750I17J-1601D01*
G01X181130D01*
X180999D01*
X180399Y499350D01*
Y500550D01*
X180799Y500950D01*
X187000D01*
X187601Y500348D01*
X199001D01*
X201798Y497552D01*
Y487348D01*
X200499Y486050D01*
X189704D01*
G37*
G36*
G01X188499Y553613D02*
X195999D01*
X209999Y539613D01*
Y527113D01*
X208999Y526113D01*
X187499D01*
X186499Y527113D01*
Y551613D01*
X188499Y553613D01*
G37*
G36*
G01X189799Y844714D02*
G03X189237Y844613I-2J-1601D01*
G01X189203Y844600D01*
X187295D01*
X187261Y844613D01*
G03X186699Y844714I-560J-1500D01*
G01X185299D01*
X185298D01*
G03X185187Y844711I-12J-1601D01*
G01X185096Y844704D01*
X184700Y845100D01*
Y846751D01*
X185499Y847550D01*
X192999D01*
X193449Y848000D01*
X210500D01*
X211500Y847000D01*
Y834500D01*
X209000Y832000D01*
X195500D01*
X195218Y832282D01*
Y833897D01*
X193532Y835582D01*
Y836631D01*
X193531Y836632D01*
Y841082D01*
X193499Y841113D01*
Y844050D01*
X192949Y844600D01*
X191795D01*
X191761Y844613D01*
G03X191199Y844714I-560J-1500D01*
G01X189799D01*
G37*
G36*
G01X201635Y898749D02*
X201518Y898787D01*
G03X198612Y895881I-719J-2187D01*
G01X198650Y895764D01*
X192138Y889252D01*
X187360D01*
X186499Y890113D01*
Y898613D01*
X194243Y906357D01*
Y906748D01*
X195202D01*
Y914652D01*
X195020D01*
G02X194879Y914993I0J200D01*
G01X201499Y921613D01*
X224688D01*
X225999Y920302D01*
Y909698D01*
X225414Y909113D01*
X211999D01*
X206891Y904005D01*
X206801Y904011D01*
G03X206699Y904014I-98J-1598D01*
G01X205299D01*
G03X203698Y902413I0J-1601D01*
G01Y901013D01*
G03X203701Y900911I1601J-4D01*
G01X203707Y900821D01*
X201635Y898749D01*
G37*
G36*
G01X178000Y1615500D02*
X176500Y1617000D01*
Y1635800D01*
X178313Y1637613D01*
X195499D01*
X196499Y1636613D01*
Y1636217D01*
X196493Y1636193D01*
G03X196448Y1635813I1556J-377D01*
G01Y1634413D01*
G03X196493Y1634033I1601J-3D01*
G01X196499Y1634009D01*
Y1631717D01*
X196493Y1631693D01*
G03X196448Y1631313I1556J-377D01*
G01Y1629913D01*
G03X196493Y1629533I1601J-3D01*
G01X196499Y1629509D01*
Y1626200D01*
X198200Y1624499D01*
Y1618000D01*
X195700Y1615500D01*
X178000D01*
G37*
G36*
G01X179461Y1697570D02*
X204098Y1672933D01*
Y1659500D01*
X202118D01*
X202075Y1659522D01*
G03X199725I-1175J-2322D01*
G01X199682Y1659500D01*
X195549D01*
X179362Y1675688D01*
Y1676398D01*
X180229D01*
X183102Y1679271D01*
Y1681562D01*
X183126Y1681606D01*
G03X179960Y1684700I-2026J1094D01*
G02X179362Y1685047I-198J347D01*
G01Y1688619D01*
X179429Y1688679D01*
G03X177473Y1692662I-1529J1721D01*
G02X176999Y1693055I-74J393D01*
G01Y1697513D01*
G02X177599Y1697860I400J0D01*
G03X179358Y1697552I1301J2253D01*
G01X179461Y1697570D01*
G37*
G36*
G01X205100Y52300D02*
X204200Y53200D01*
Y60883D01*
X204435D01*
Y72361D01*
X204434D01*
Y83434D01*
X205314Y84314D01*
X207670D01*
X207855Y84500D01*
X215800D01*
X216917Y83383D01*
Y78600D01*
X216918D01*
Y74330D01*
X216917D01*
Y60883D01*
X217000D01*
Y56000D01*
X213300Y52300D01*
X205100D01*
G37*
G36*
G01X189200Y428100D02*
X187999Y429301D01*
Y473548D01*
X189302D01*
Y480902D01*
X190400Y482000D01*
X203850D01*
X210798Y475052D01*
Y433698D01*
X205200Y428100D01*
X189200D01*
G37*
G36*
G01X201614Y816461D02*
G02X201248Y815902I-367J-159D01*
G01X196981D01*
X187900Y824982D01*
Y832111D01*
X190771D01*
X190780Y832103D01*
Y825584D01*
X193098Y823266D01*
Y822300D01*
G03X194700Y820698I1602J0D01*
G01X195929D01*
X196929Y819698D01*
X199819D01*
X201457Y818061D01*
X201439Y817958D01*
G03X201614Y816461I2561J-459D01*
G37*
G36*
G01X227034Y824316D02*
X218619Y815902D01*
X206752D01*
G02X206386Y816461I1J400D01*
G03X205043Y819884I-2386J1039D01*
G02Y820616I161J366D01*
G03X201865Y824487I-1043J2384D01*
G01X201805Y824402D01*
X200944D01*
X200887Y824501D01*
G03X200346Y825060I-1387J-801D01*
G01X200252Y825119D01*
Y826161D01*
X202951D01*
Y830798D01*
X209498D01*
X211115Y832416D01*
G02X211798Y832133I283J-283D01*
G01Y826903D01*
X213702Y824998D01*
X226751D01*
G02X227034Y824316I0J-400D01*
G37*
G36*
G01X207900Y881100D02*
X207300Y881700D01*
Y887300D01*
X207900Y887900D01*
X210900D01*
X213400Y890400D01*
Y892993D01*
X213452Y893050D01*
G03Y896150I-1702J1550D01*
G01X213400Y896207D01*
Y896900D01*
X213798Y897298D01*
X222201D01*
X222798Y896702D01*
Y883898D01*
X220102Y881202D01*
X213001D01*
X212900Y881100D01*
X207900D01*
G37*
G36*
G01X215999Y29050D02*
X214499Y30550D01*
Y51050D01*
X218999Y55550D01*
Y72050D01*
X219499Y72550D01*
X225499D01*
X225744Y72796D01*
X229651D01*
X230855Y73999D01*
X230928Y74005D01*
G03X233044Y76121I-179J2295D01*
G01X233050Y76194D01*
X233700Y76845D01*
Y77752D01*
X234499Y78550D01*
X238499D01*
X238999Y78050D01*
Y75202D01*
X238502D01*
X236802Y73502D01*
X236348D01*
Y73047D01*
X236298Y72998D01*
Y71850D01*
X235999Y71550D01*
Y30749D01*
X234300Y29050D01*
X215999D01*
G37*
G36*
G01X228481Y662902D02*
X222900Y668482D01*
Y673634D01*
G02X223583Y673917I400J0D01*
G01X226500Y671000D01*
X236469D01*
G02X236847Y670467I1J-400D01*
G03X237867Y667428I2453J-867D01*
G02X237929Y666812I-221J-333D01*
G01X234019Y662902D01*
X228481D01*
G37*
G36*
G01X234999Y833199D02*
X228000Y826200D01*
X214200D01*
X212999Y827401D01*
Y878199D01*
X214400Y879600D01*
X232100D01*
X234999Y876701D01*
Y833199D01*
G37*
G36*
G01X235415Y877984D02*
X232598Y880802D01*
X225198D01*
X224000Y882000D01*
Y897500D01*
X223000Y898500D01*
X218091D01*
X218032Y898589D01*
G03X216700Y899302I-1332J-888D01*
G01X215812D01*
X214800Y900313D01*
Y900947D01*
X211783Y903964D01*
X211097D01*
X211074Y903970D01*
G03X210699Y904014I-373J-1557D01*
G01X209980D01*
G02X209697Y904697I0J400D01*
G01X212500Y907500D01*
X225500D01*
X226161Y908161D01*
X232469D01*
X236098Y904532D01*
Y902245D01*
X236012Y902185D01*
G03Y897915I1487J-2135D01*
G01X236098Y897855D01*
X236097Y878267D01*
G02X235415Y877984I-400J0D01*
G37*
G36*
G01X233499Y943113D02*
Y926613D01*
X231999Y925113D01*
X212499D01*
X211499Y926113D01*
Y948613D01*
X213499Y950613D01*
X225999D01*
X233499Y943113D01*
G37*
G36*
G01X251100Y1125700D02*
X236452D01*
Y1126502D01*
X229650D01*
Y1140400D01*
X231300Y1142050D01*
X242850D01*
X244000Y1140900D01*
Y1133000D01*
X244900Y1132100D01*
X250700D01*
X251800Y1131000D01*
Y1126400D01*
X251100Y1125700D01*
G37*
G36*
G01X250252Y704550D02*
Y705002D01*
X243698D01*
X242499Y706201D01*
Y719599D01*
X243048Y720148D01*
X252181D01*
X256032Y724000D01*
X259600D01*
X260999Y722601D01*
Y706050D01*
X259499Y704550D01*
X250252D01*
G37*
G36*
G01X251852Y755550D02*
Y756402D01*
X245498D01*
X243900Y758000D01*
Y765604D01*
Y765608D01*
G03Y765792I-2300J92D01*
G01Y765796D01*
Y768300D01*
X246685Y771085D01*
X246717Y771100D01*
G03X247949Y772332I-1118J2350D01*
G01X247964Y772364D01*
X251150Y775550D01*
X283999D01*
X285999Y773550D01*
Y757050D01*
X284499Y755550D01*
X251852D01*
G37*
G36*
G01X244299Y1909502D02*
X243499Y1910301D01*
Y1927050D01*
X245499Y1929050D01*
X249999D01*
X251499Y1930550D01*
Y1931851D01*
X251700Y1932052D01*
Y1932752D01*
X252999Y1934050D01*
X258999D01*
X259999Y1933050D01*
Y1922050D01*
X258999Y1921050D01*
X252499D01*
X251200Y1919751D01*
Y1910600D01*
X250102Y1909502D01*
X244299D01*
G37*
G36*
G01X282999Y1960550D02*
X244550D01*
X243100Y1962000D01*
Y1974000D01*
X247150Y1978050D01*
X282499D01*
X283499Y1977050D01*
Y1961050D01*
X282999Y1960550D01*
G37*
G36*
G01X284999Y699050D02*
X267499D01*
X266499Y700050D01*
Y723050D01*
X267499Y724050D01*
X283999D01*
X285499Y722550D01*
Y699550D01*
X284999Y699050D01*
G37*
G36*
G01X264999Y1913550D02*
X263999Y1914550D01*
Y1933050D01*
X266499Y1935550D01*
X277999D01*
X283213Y1930336D01*
X283205Y1930243D01*
G03X283475Y1928954I2294J-192D01*
G01X283499Y1928909D01*
Y1917550D01*
X279499Y1913550D01*
X264999D01*
G37*
G36*
G01X292999Y697550D02*
X289499Y701050D01*
Y716550D01*
X297999Y725050D01*
X322798D01*
Y712962D01*
X307386Y697550D01*
X292999D01*
G37*
G36*
G01X464999Y608050D02*
X377102Y695947D01*
G02X377179Y696574I282J284D01*
G03X374023Y699730I-1180J1976D01*
G02X373396Y699653I-343J205D01*
G01X346797Y726252D01*
X311243D01*
X311185Y726352D01*
G03X309799Y727152I-1386J-801D01*
G01X308199D01*
G03X306813Y726352I0J-1601D01*
G01X306755Y726252D01*
X289741D01*
X289716Y726259D01*
G03X288394Y726286I-717J-2709D01*
G01X288287Y726262D01*
X283499Y731050D01*
Y736050D01*
X283999Y736550D01*
X305499D01*
X308999Y740050D01*
Y740788D01*
X309010Y740820D01*
G03X309100Y741350I-1511J529D01*
G01Y742750D01*
G03X309079Y743012I-1601J3D01*
G01X309062Y743113D01*
X309499Y743550D01*
X318999D01*
X319648Y742902D01*
Y738988D01*
X320660D01*
X321399Y738250D01*
X327903D01*
X327907D01*
G03X328091I92J2300D01*
G01X328095D01*
X336583D01*
X337999Y739666D01*
X370883D01*
X480499Y630050D01*
X557999D01*
X562499Y625550D01*
Y612550D01*
X557999Y608050D01*
X464999D01*
G37*
G36*
G01X290999Y755050D02*
X289499Y756550D01*
Y768050D01*
X290499Y769050D01*
X307999D01*
X308749Y768300D01*
Y757537D01*
X308745Y757517D01*
G03Y756583I2254J-467D01*
G01X308749Y756563D01*
Y755800D01*
X307999Y755050D01*
X290999D01*
G37*
G36*
G01X288298Y1930752D02*
X287499Y1931550D01*
Y1937550D01*
X288499Y1938550D01*
X290999D01*
X291499Y1939050D01*
Y1946050D01*
X291999Y1946550D01*
X294473D01*
X294514Y1946403D01*
G03X296058Y1945226I1544J424D01*
G01X297658D01*
G03X298972Y1945912I0J1601D01*
G02X299583Y1945966I328J-229D01*
G01X301499Y1944050D01*
X304999D01*
X306499Y1942550D01*
X306551D01*
G02X306834Y1941867I0J-400D01*
G01X306598Y1941631D01*
Y1940631D01*
X305477Y1939510D01*
X305430Y1939496D01*
G03X308452Y1938311I769J-2486D01*
G01X308375Y1938444D01*
X309400Y1939469D01*
Y1940469D01*
X311481Y1942550D01*
X311999D01*
X312999Y1943550D01*
Y1945050D01*
X313999Y1946050D01*
X321999D01*
X322170Y1945880D01*
Y1940402D01*
X322114Y1940344D01*
G03X322885Y1936199I1885J-1794D01*
G01X322999Y1936145D01*
Y1931550D01*
X322200Y1930752D01*
X288298D01*
G37*
G36*
G01X288499Y1958550D02*
X285999Y1961050D01*
Y1972050D01*
X286999Y1973050D01*
X305999D01*
X311374Y1967675D01*
X311317Y1967549D01*
G03X311176Y1966891I1460J-657D01*
G01Y1965491D01*
G03X311463Y1964575I1601J-1D01*
G01X311499Y1964524D01*
Y1963858D01*
X311463Y1963807D01*
G03X311176Y1962891I1314J-915D01*
G01Y1961491D01*
G03X311183Y1961337I1601J-4D01*
G01X311192Y1961243D01*
X308499Y1958550D01*
X298033D01*
X297992Y1958570D01*
G03X295724I-1134J-2342D01*
G01X295683Y1958550D01*
X288499D01*
G37*
G36*
G01X767709Y286952D02*
X759083Y295577D01*
X753765Y305460D01*
G02X754117Y306050I352J190D01*
G01X760499D01*
X761499Y305050D01*
X792499D01*
X793499Y304050D01*
Y287550D01*
X792901Y286952D01*
X788194D01*
X788134Y287037D01*
G03X783864I-2135J-1487D01*
G01X783804Y286952D01*
X767709D01*
G37*
G36*
G01X753580Y324624D02*
G03X753523Y325045I-1602J-2D01*
G02X753909Y325550I386J105D01*
G01X762499D01*
X763499Y324550D01*
Y321050D01*
X764499Y320050D01*
X777999D01*
X778499Y320550D01*
Y321288D01*
X778510Y321320D01*
G03X778600Y321850I-1511J529D01*
G01Y323250D01*
G03X778510Y323780I-1601J1D01*
G01X778499Y323812D01*
Y325288D01*
X778510Y325320D01*
G03X778600Y325850I-1511J529D01*
G01Y327152D01*
X778999Y327550D01*
X780499D01*
X780999Y327050D01*
Y323550D01*
X781499Y323050D01*
Y319550D01*
X783999Y317050D01*
X793999D01*
X794499Y316550D01*
Y310050D01*
X791499Y307050D01*
X765704D01*
X765680Y307056D01*
G03X765300Y307102I-381J-1556D01*
G01X763700D01*
G03X763320Y307056I1J-1602D01*
G01X763296Y307050D01*
X761198D01*
X760997Y307252D01*
X755797D01*
X753499Y309550D01*
X752499D01*
X750476Y311573D01*
X749499Y313388D01*
Y319050D01*
X752073Y321624D01*
X752143Y321631D01*
G03X753580Y323224I-164J1593D01*
G01Y324624D01*
G37*
G36*
G01X770200Y363552D02*
X772497Y365848D01*
X785554D01*
X786978Y364424D01*
Y346924D01*
X785478Y345424D01*
X770978D01*
X770212Y346190D01*
X770305Y346327D01*
G03X770580Y347224I-1327J897D01*
G01Y348624D01*
G03X770045Y349818I-1602J-1D01*
G01X769978Y349878D01*
Y350470D01*
X770045Y350530D01*
G03X770580Y351724I-1067J1195D01*
G01Y353124D01*
G03X770045Y354318I-1602J-1D01*
G01X769978Y354378D01*
Y354830D01*
X770200Y355052D01*
Y363552D01*
G37*
G36*
G01X812373Y310071D02*
X813873Y308571D01*
Y306632D01*
X813872Y306631D01*
Y289072D01*
X812871Y288071D01*
X796373D01*
X794873Y289571D01*
Y308725D01*
X795700Y309552D01*
Y309898D01*
X795873Y310071D01*
X812373D01*
G37*
G36*
G01X805524Y343576D02*
X801999Y340050D01*
X793999D01*
X791999Y342050D01*
Y363050D01*
X794499Y365550D01*
X833251D01*
X835700Y363101D01*
Y344500D01*
X834776Y343576D01*
X805524D01*
G37*
G36*
G01X819999Y304050D02*
X826499D01*
X829499Y307050D01*
X832499D01*
X833499Y306050D01*
Y295399D01*
X827052Y288952D01*
X825498D01*
Y282198D01*
X825400Y282100D01*
X819999D01*
X819702Y282397D01*
Y285998D01*
X818999Y286700D01*
Y303050D01*
X819999Y304050D01*
G37*
G36*
G01X841120Y311106D02*
G02X840752Y310550I-368J-156D01*
G01X819999D01*
X819499Y311050D01*
Y316050D01*
X819999Y316550D01*
X865499D01*
X867499Y314550D01*
Y311550D01*
X866275Y310326D01*
X847557D01*
X846408Y311474D01*
X846433Y311581D01*
G03X841120Y311106I-2733J619D01*
G37*
G36*
G01X849499Y319050D02*
X806999D01*
X804499Y321550D01*
Y339050D01*
X806499Y341050D01*
X827648D01*
Y339998D01*
X836552D01*
Y341050D01*
X837751D01*
X837952Y340848D01*
X873201D01*
X883499Y330550D01*
Y323050D01*
X882999Y322550D01*
X874499D01*
X864999Y332050D01*
X853999D01*
X851999Y330050D01*
Y321550D01*
X849499Y319050D01*
G37*
G36*
G01X839676Y282000D02*
X828500D01*
X828102Y282398D01*
Y288248D01*
X839278Y299424D01*
Y306924D01*
X840278Y307924D01*
X845994D01*
X846395Y307522D01*
X865880D01*
X872478Y300924D01*
X873426D01*
X873501Y300848D01*
X883554D01*
X884478Y299924D01*
Y293924D01*
X883478Y292924D01*
X867478D01*
X863478Y296924D01*
X852278D01*
X850778Y295424D01*
Y284924D01*
X849778Y283924D01*
X841600D01*
X839676Y282000D01*
G37*
G36*
G01X854278Y283924D02*
X853278Y284924D01*
Y294924D01*
X854076Y295722D01*
X862180D01*
X866478Y291424D01*
X883978D01*
X884478Y290924D01*
Y287924D01*
X883978Y287424D01*
X870478D01*
X866978Y283924D01*
X854278D01*
G37*
G36*
G01X866198Y317550D02*
X865997Y317752D01*
X857797D01*
X856499Y319050D01*
Y329550D01*
X857499Y330550D01*
X862499D01*
X872499Y320550D01*
X882999D01*
X883798Y319752D01*
Y317848D01*
X883499Y317550D01*
X866198D01*
G37*
G36*
G01X1014700Y1431300D02*
X952200D01*
X948000Y1435500D01*
Y1509100D01*
X949900Y1511000D01*
X1014500D01*
X1016200Y1509300D01*
Y1432800D01*
X1014700Y1431300D01*
G37*
%LPC*%
G75*
G36*
G01X100345Y528390D02*
X101945D01*
G02X102945Y528039I-1J-1602D01*
G02X103945Y528390I1001J-1251D01*
G01X105545D01*
G02X107146Y526788I-1J-1602D01*
G01Y526315D01*
G03X107351Y526306I205J2329D01*
G01X108399D01*
G02X111112Y525182I0J-3835D01*
G01X111373Y524920D01*
G02X111502Y524771I-1005J-1001D01*
G02X111653Y524640I-852J-1134D01*
G02X112918Y521587I-3052J-3053D01*
G01Y520417D01*
G02X112136Y518014I-4084J0D01*
G01Y517942D01*
X111421Y517227D01*
G02X109018Y516232I-2403J2403D01*
G01X101161D01*
G03X100102Y515908I0J-1894D01*
G03X100181Y515313I302J-263D01*
G02X97336Y511711I-1281J-1913D01*
G03X97064I-136J-147D01*
G02X95248Y515688I-1564J1689D01*
G02X96509Y518191I4425J-660D01*
G01X96908Y518590D01*
G02X99017Y519957I4253J-4252D01*
G03X99168Y520602I-143J374D01*
G02X98744Y521688I1177J1085D01*
G01Y522420D01*
G03X97425Y522648I-1319J-3703D01*
G01X83790D01*
G03X83660Y522640I-4J-988D01*
G01X83659D01*
G03X83090Y522359I130J-980D01*
G02X82232Y521755I-2171J2173D01*
G01X82118Y521701D01*
Y520672D01*
X72214D01*
Y528225D01*
X82118D01*
Y526936D01*
X82220Y526878D01*
G02X82383Y526782I-2034J-3641D01*
G01X82432Y526752D01*
X98734D01*
X98750Y526933D01*
G02X100345Y528390I1595J-145D01*
G37*
G36*
G01X83989Y531605D02*
X83947Y531748D01*
X82702D01*
X82644Y531694D01*
G02X82211Y531355I-1973J2074D01*
G01X82118Y531296D01*
Y530121D01*
X72214D01*
Y537674D01*
X82118D01*
Y536368D01*
G02X82678Y535920I-1744J-2754D01*
G03X82809Y535866I131J131D01*
G01X83895D01*
X83897Y536049D01*
G02X87846Y534417I2302J-24D01*
G03Y533858I286J-279D01*
G02X83989Y531605I-1647J-1608D01*
G37*
G36*
G01X70932Y546685D02*
G02X70234Y544593I1568J-1686D01*
G03X69568Y544815I-394J-71D01*
G02X70266Y546907I-1568J1686D01*
G03X70932Y546685I394J71D01*
G37*
G36*
G01X63681Y452907D02*
G02X62186Y454764I-2281J-306D01*
G03X62719Y455193I137J376D01*
G02X64214Y453336I2281J306D01*
G03X63681Y452907I-137J-376D01*
G37*
G36*
G01X83652Y750453D02*
Y745747D01*
X84602Y744798D01*
Y719453D01*
X73997Y708848D01*
X37001D01*
X31298Y714552D01*
Y740048D01*
X38001Y746752D01*
X74748D01*
Y749348D01*
X45001D01*
X43298Y751052D01*
Y779048D01*
X47501Y783252D01*
X81648D01*
X85402Y779498D01*
Y752202D01*
X83652Y750453D01*
G37*
G36*
G01X22400Y1318721D02*
Y1317110D01*
X22460Y1317051D01*
G02X19471Y1317657I-1962J-2001D01*
G01X19598Y1317707D01*
Y1318721D01*
X19526Y1318781D01*
G02X22472I1473J1769D01*
G01X22400Y1318721D01*
G37*
G36*
G01X91532Y903554D02*
X93864D01*
X93909Y903577D01*
G02X92889Y900630I1090J-2027D01*
G01X92836Y900750D01*
X91532D01*
Y899664D01*
X79728D01*
Y904666D01*
X91532D01*
Y903554D01*
G37*
G36*
G01X93001Y896252D02*
X98497D01*
X100200Y894548D01*
Y890052D01*
X99467Y889319D01*
X99600Y889178D01*
G02X99757Y888993I-1903J-1774D01*
G01X99765Y888983D01*
X100200Y888548D01*
Y888120D01*
X100208Y888094D01*
G02Y886706I-2508J-694D01*
G01X100200Y886680D01*
Y883617D01*
X100222Y883574D01*
G02Y881226I-2322J-1174D01*
G01X100200Y881183D01*
Y881052D01*
X99965Y880817D01*
X99957Y880807D01*
G02X99493Y880343I-2057J1593D01*
G01X99483Y880335D01*
X97997Y878848D01*
X81001D01*
X80187Y879663D01*
X79728D01*
Y880122D01*
X79298Y880552D01*
Y889548D01*
X79728Y889978D01*
Y894667D01*
X81417D01*
X81501Y894752D01*
X91501D01*
X93001Y896252D01*
G37*
G36*
G01X91532Y870750D02*
Y869664D01*
X79728D01*
Y874666D01*
X91532D01*
Y873554D01*
X107380D01*
X107432Y873673D01*
G02X107909Y870684I2567J-1123D01*
G01X107849Y870750D01*
X91532D01*
G37*
G36*
G01X98497Y848348D02*
X81501D01*
X80187Y849663D01*
X79728D01*
Y864667D01*
X81417D01*
X81501Y864752D01*
X91501D01*
X93001Y866252D01*
X98497D01*
X100200Y864548D01*
Y860052D01*
X99448Y859300D01*
X100700Y858048D01*
Y850552D01*
X98497Y848348D01*
G37*
G36*
G01X180398Y1772500D02*
Y1773469D01*
X179412Y1774454D01*
Y1776445D01*
X179307Y1776502D01*
G02X179064Y1776662I756J1412D01*
G02X178821Y1776502I-999J1252D01*
G01X178716Y1776445D01*
Y1774245D01*
X178801Y1774185D01*
G02X175179Y1770563I-1487J-2135D01*
G01X175119Y1770648D01*
X171418D01*
X169381Y1772686D01*
G03X168818Y1772690I-284J-282D01*
G02X165512Y1776685I-1820J1859D01*
G01X165598Y1776745D01*
Y1780092D01*
X161446D01*
Y1781508D01*
X160341D01*
G02X159683Y1780797I-1470J701D01*
G03X159741Y1780258I321J-238D01*
G02X156540Y1780435I-1714J-1958D01*
G01X156626Y1780495D01*
Y1780817D01*
G02X156528Y1780881I841J1395D01*
G01X156368D01*
X156320Y1780851D01*
G02X155471Y1780608I-848J1358D01*
G01X154071D01*
G02X153545Y1780696I-2J1601D01*
G01X153513Y1780708D01*
X152279D01*
X149320Y1783667D01*
Y1790135D01*
X154786Y1795602D01*
X161227D01*
X161254Y1795610D01*
G02X164145Y1792890I646J-2210D01*
G03X164535Y1792402I390J-88D01*
G01X164601D01*
X164651Y1792434D01*
G02X168202Y1790544I1249J-1934D01*
G01X168205Y1790348D01*
X170465D01*
X172048Y1788766D01*
G02X172165Y1788490I-283J-283D01*
G03X172565Y1788096I400J6D01*
G01X173200D01*
Y1787082D01*
X175062D01*
Y1787313D01*
G02X175107Y1787688I1602J-2D01*
G01X175112Y1787711D01*
Y1788777D01*
X185587Y1799252D01*
X296111D01*
X296158Y1799280D01*
G02X298840I1341J-2230D01*
G01X298887Y1799252D01*
X333611D01*
X333658Y1799280D01*
G02Y1794820I1341J-2230D01*
G01X333611Y1794848D01*
X298887D01*
X298840Y1794820D01*
G02X296158I-1341J2230D01*
G01X296111Y1794848D01*
X187411D01*
X181989Y1789427D01*
G03X182111Y1788778I283J-283D01*
G02X183066Y1787313I-646J-1465D01*
G01Y1785913D01*
G02X183046Y1785664I-1602J3D01*
G03X183441Y1785202I395J-62D01*
G01X190000D01*
Y1783902D01*
X198368D01*
X198913Y1784446D01*
X198906Y1784538D01*
G02X203258Y1782832I2593J212D01*
G03X203242Y1782554I135J-147D01*
G02X202052Y1778816I-1743J-1504D01*
G01X201900Y1778778D01*
Y1772969D01*
X195580Y1766648D01*
X184418D01*
X181248Y1769819D01*
Y1771081D01*
X181153Y1771140D01*
G02X180398Y1772500I847J1360D01*
G37*
G36*
G01X641748Y1792234D02*
Y1793634D01*
G02X641778Y1793944I1601J2D01*
G01X641782Y1793963D01*
Y1794182D01*
X641427D01*
X641389Y1794166D01*
G02X640749Y1794032I-641J1468D01*
G01X639349D01*
G02X638709Y1794166I1J1602D01*
G01X638671Y1794182D01*
X636198D01*
X636139Y1794088D01*
G02X633302Y1797990I-2208J1377D01*
G01X633356Y1798003D01*
X633938Y1798586D01*
X638951D01*
X638974Y1798591D01*
G02X639349Y1798636I377J-1557D01*
G01X640749D01*
G02X641124Y1798591I-2J-1602D01*
G01X641147Y1798586D01*
X642951D01*
X642974Y1798591D01*
G02X643349Y1798636I377J-1557D01*
G01X644749D01*
G02X645634Y1798369I0J-1602D01*
G01X645684Y1798336D01*
X647091D01*
X647123Y1798347D01*
G02X647649Y1798436I527J-1513D01*
G01X649049D01*
G02X650049Y1798085I-1J-1602D01*
G02X651049Y1798436I1001J-1251D01*
G01X652449D01*
G02X652975Y1798347I-1J-1602D01*
G01X653007Y1798336D01*
X653584D01*
X653642Y1798391D01*
G02X654749Y1798836I1108J-1157D01*
G01X656349D01*
G02X657163Y1798613I-1J-1602D01*
G01X657210Y1798586D01*
X662212D01*
X662269Y1798689D01*
G02X663920Y1799961I2281J-1253D01*
G01X663974Y1799974D01*
X667444Y1803445D01*
G02X668564Y1804046I1557J-1557D01*
G01X668623Y1804058D01*
X668780Y1804215D01*
G03X668497Y1804897I-283J282D01*
G01X662835D01*
G03X662450Y1804387I-1J-400D01*
G02X658608Y1801440I-2501J-717D01*
G01X658561Y1801468D01*
X656247D01*
X656211Y1801432D01*
X653007D01*
X652975Y1801421D01*
G02X652449Y1801332I-527J1513D01*
G01X651049D01*
G02X650049Y1801683I1J1602D01*
G02X649049Y1801332I-1001J1251D01*
G01X647649D01*
G02X646700Y1801644I1J1602D01*
G01X646648Y1801682D01*
X645147D01*
X645124Y1801677D01*
G02X644749Y1801632I-377J1557D01*
G01X643349D01*
G02X642974Y1801677I2J1602D01*
G01X642951Y1801682D01*
X641147D01*
X641124Y1801677D01*
G02X640749Y1801632I-377J1557D01*
G01X639661D01*
X638877Y1800848D01*
X636387D01*
X636340Y1800820D01*
G02X632826Y1804481I-1341J2230D01*
G03X632671Y1805058I-334J219D01*
G02X635178Y1809614I1166J2326D01*
G01X635225Y1809586D01*
X638951D01*
X638974Y1809591D01*
G02X639349Y1809636I377J-1557D01*
G01X640749D01*
G02X642350Y1808034I-1J-1602D01*
G01Y1806634D01*
G02X642320Y1806324I-1601J-2D01*
G01X642316Y1806305D01*
Y1806086D01*
X642671D01*
X642709Y1806102D01*
G02X643349Y1806236I641J-1468D01*
G01X644749D01*
G02X645389Y1806102I-1J-1602D01*
G01X645427Y1806086D01*
X648961D01*
X649110Y1805936D01*
X649183Y1805930D01*
G02X650049Y1805585I-134J-1596D01*
G02X651049Y1805936I1001J-1251D01*
G01X652449D01*
G02X652975Y1805847I-1J-1602D01*
G01X653007Y1805836D01*
X653584D01*
X653642Y1805891D01*
G02X654749Y1806336I1108J-1157D01*
G01X656349D01*
G02X657148Y1806122I-1J-1602D01*
G03X657748Y1806469I200J347D01*
G01Y1807229D01*
X658962Y1808444D01*
G02X660082Y1809045I1557J-1557D01*
G01X660141Y1809057D01*
X661550Y1810466D01*
X662198D01*
Y1811232D01*
X658245D01*
G03X657846Y1810808I0J-400D01*
G02X652547Y1809373I-2797J-174D01*
G01X652492Y1809482D01*
X651168D01*
X651109Y1809388D01*
G02X649749Y1808632I-1360J845D01*
G01X648349D01*
G02X646748Y1810234I1J1602D01*
G01Y1811634D01*
G02X646752Y1811753I1601J6D01*
G03X646353Y1812182I-399J29D01*
G01X645887D01*
X645214Y1812856D01*
X645152Y1812867D01*
G02X643642Y1816423I397J2267D01*
G03X643466Y1817016I-331J224D01*
G02X645006Y1821347I894J2122D01*
G01X645033Y1821338D01*
X648208D01*
X648610Y1820936D01*
X648683Y1820930D01*
G02X649549Y1820585I-134J-1596D01*
G02X650549Y1820936I1001J-1251D01*
G01X651949D01*
G02X653033Y1820512I-1J-1601D01*
G03X653613Y1820552I271J295D01*
G02X654849Y1821136I1237J-1018D01*
G01X655818D01*
X658718Y1824036D01*
X659354D01*
X659414Y1824121D01*
G02X663684I2135J-1487D01*
G01X663744Y1824036D01*
X665130D01*
X667800Y1821365D01*
Y1816370D01*
X670600D01*
Y1808500D01*
X670730D01*
X672852Y1806379D01*
Y1803191D01*
X671171Y1801510D01*
X671159Y1801451D01*
G02X670558Y1800331I-2158J437D01*
G01X667087Y1796861D01*
X667074Y1796807D01*
G02X665178Y1794911I-2525J629D01*
G01X665124Y1794898D01*
X664409Y1794182D01*
X657027D01*
X656989Y1794166D01*
G02X656389Y1794033I-640J1468D01*
G01X656309Y1794031D01*
X656211Y1793932D01*
X653007D01*
X652975Y1793921D01*
G02X652449Y1793832I-527J1513D01*
G01X651049D01*
G02X650049Y1794183I1J1602D01*
G02X649049Y1793832I-1001J1251D01*
G01X647649D01*
G02X647123Y1793921I1J1602D01*
G01X647091Y1793932D01*
X646348D01*
Y1793722D01*
G02X646350Y1793634I-1599J-80D01*
G01Y1792234D01*
G02X646262Y1791708I-1601J-2D01*
G01X646250Y1791676D01*
Y1787976D01*
X641559Y1783284D01*
G03X641842Y1782602I283J-282D01*
G01X704588D01*
X708348Y1786361D01*
Y1796676D01*
X708336Y1796708D01*
G02X708248Y1797234I1513J524D01*
G01Y1798634D01*
G02X708278Y1798944I1601J2D01*
G01X708282Y1798963D01*
Y1799182D01*
X707927D01*
X707889Y1799166D01*
G02X707249Y1799032I-641J1468D01*
G01X705849D01*
G02X704843Y1799388I1J1602D01*
G01X704788Y1799432D01*
X702007D01*
X701975Y1799421D01*
G02X701449Y1799332I-527J1513D01*
G01X700049D01*
G02X699049Y1799683I1J1602D01*
G02X698049Y1799332I-1001J1251D01*
G01X696649D01*
G02X695700Y1799644I1J1602D01*
G01X695648Y1799682D01*
X695027D01*
X694989Y1799666D01*
G02X694389Y1799533I-640J1468D01*
G01X694309Y1799531D01*
X694161Y1799382D01*
X693134D01*
X690684Y1796932D01*
X686937D01*
X686890Y1796904D01*
G02X683024Y1798505I-1341J2230D01*
G01X683011Y1798559D01*
X680348Y1801222D01*
Y1803634D01*
G02X680472Y1804365I2201J3D01*
G03X680095Y1804898I-377J133D01*
G01X678498D01*
Y1811202D01*
X674159D01*
X671848Y1813514D01*
Y1821254D01*
X677229Y1826636D01*
X679354D01*
X679414Y1826721D01*
G02X683684I2135J-1487D01*
G01X683744Y1826636D01*
X691569D01*
X691611Y1826780D01*
G02X693149Y1827936I1538J-445D01*
G01X694549D01*
G02X695549Y1827585I-1J-1602D01*
G02X696549Y1827936I1001J-1251D01*
G01X697949D01*
G02X699543Y1826484I0J-1601D01*
G01X699561Y1826302D01*
X709685D01*
X709737Y1826423D01*
G02X713444Y1823845I2111J-919D01*
G03X713428Y1823573I138J-145D01*
G02X709445Y1821455I-1776J-1464D01*
G01X709402Y1821598D01*
X699550D01*
Y1820934D01*
G02X697949Y1819332I-1601J-1D01*
G01X696549D01*
G02X695549Y1819683I1J1602D01*
G02X694549Y1819332I-1001J1251D01*
G01X693149D01*
G02X691558Y1820755I0J1601D01*
G01X691538Y1820932D01*
X689244D01*
X689184Y1820847D01*
G02X684914I-2135J1487D01*
G01X684854Y1820932D01*
X678179D01*
X676550Y1819304D01*
Y1816081D01*
X676661Y1815970D01*
X678498D01*
Y1816370D01*
X686900D01*
Y1815091D01*
G03X687583Y1814808I400J0D01*
G01X687620Y1814844D01*
X687646D01*
X688387Y1815586D01*
X692071D01*
X692109Y1815602D01*
G02X692749Y1815736I641J-1468D01*
G01X694349D01*
G02X694989Y1815602I-1J-1602D01*
G01X695027Y1815586D01*
X695556D01*
Y1815628D01*
X698371Y1818444D01*
X705329D01*
X705929Y1817844D01*
X707082D01*
G02Y1813356I518J-2244D01*
G01X704071D01*
X703471Y1813956D01*
X700229D01*
X700150Y1813877D01*
Y1812334D01*
G02X699739Y1811262I-1601J-1D01*
G03X699905Y1810929I149J-134D01*
G02X700049Y1810936I150J-1595D01*
G01X701449D01*
G02X701975Y1810847I-1J-1602D01*
G01X702007Y1810836D01*
X707291D01*
X707323Y1810847D01*
G02X707849Y1810936I527J-1513D01*
G01X709249D01*
G02X709889Y1810802I-1J-1602D01*
G01X709927Y1810786D01*
X710282D01*
Y1811005D01*
X710278Y1811024D01*
G02X710248Y1811334I1571J308D01*
G01Y1812734D01*
G02X711849Y1814336I1601J1D01*
G01X713249D01*
G02X713624Y1814291I-2J-1602D01*
G01X713647Y1814286D01*
X715222D01*
X715279Y1814335D01*
G02X719563Y1811935I1721J-1951D01*
G03X720003Y1811469I394J-69D01*
G02X719609Y1806375I297J-2585D01*
G01X719583Y1806382D01*
X719176D01*
Y1806090D01*
X719246Y1806030D01*
G02X718086Y1801496I-1682J-1985D01*
G03X717818Y1800908I80J-392D01*
G02X713557Y1797960I-2269J-1274D01*
G03X712850Y1797703I-307J-257D01*
G01Y1797234D01*
G02X712762Y1796708I-1601J-2D01*
G01X712750Y1796676D01*
Y1784537D01*
X706412Y1778198D01*
X536776D01*
X522406Y1763828D01*
X350823D01*
G03X350479Y1763224I0J-400D01*
G02X346519I-1980J-1174D01*
G03X346175Y1763828I-344J204D01*
G01X327689D01*
X327642Y1763800D01*
G02Y1768260I-1341J2230D01*
G01X327689Y1768232D01*
X520582D01*
X534952Y1782602D01*
X541783D01*
G03X542119Y1783220I1J400D01*
G02X545641Y1786868I2181J1418D01*
G01X545688Y1786840D01*
X638887D01*
X641848Y1789800D01*
Y1791676D01*
X641836Y1791708D01*
G02X641748Y1792234I1513J524D01*
G37*
G36*
G01X865988Y1526874D02*
X873036D01*
Y1527974D01*
X884838D01*
Y1522972D01*
X873036D01*
Y1524072D01*
X863975D01*
X862800Y1525246D01*
X857340D01*
X856038Y1526548D01*
X820980D01*
X818400Y1523969D01*
Y1521174D01*
X826697D01*
Y1519252D01*
X833497D01*
X833501Y1519248D01*
X833998D01*
Y1519200D01*
X837500D01*
X837766Y1518934D01*
X839329Y1520498D01*
X869325D01*
X871325Y1518498D01*
X884825D01*
X886528Y1516794D01*
Y1508798D01*
X885526Y1507796D01*
X886528Y1506794D01*
Y1503798D01*
X884825Y1502094D01*
X871325D01*
X863860Y1494630D01*
G03X864143Y1493947I283J-283D01*
G01X866914D01*
X869841Y1496874D01*
X873036D01*
Y1497974D01*
X884838D01*
Y1492972D01*
X873036D01*
Y1494072D01*
X871003D01*
X868076Y1491144D01*
X861095D01*
X861038Y1491039D01*
G02X859627Y1490194I-1412J757D01*
G01X858027D01*
G02X857535Y1490272I2J1602D01*
G03X857056Y1490072I-122J-381D01*
G02X856687Y1489596I-1428J726D01*
G03Y1488996I265J-300D01*
G02X857228Y1487796I-1060J-1200D01*
G01Y1485196D01*
G02X856455Y1483825I-1602J0D01*
G03X856351Y1483231I207J-342D01*
G02X856065Y1479659I-2024J-1635D01*
G03X856035Y1479093I267J-298D01*
G02X852619I-1708J-1543D01*
G03X852589Y1479659I-297J268D01*
G02X852053Y1480332I1739J1935D01*
G03X851420Y1480420I-350J-194D01*
G01X850600Y1479600D01*
X847845D01*
G03X847559Y1478920I0J-400D01*
G02X843139Y1477558I-1859J-1820D01*
G01X843157Y1477661D01*
X841218Y1479600D01*
X839602D01*
Y1477600D01*
G02X838420Y1475774I-2001J0D01*
G01X838302Y1475721D01*
Y1473071D01*
X838366Y1473011D01*
G02X835391Y1473404I-1766J-1911D01*
G01X835498Y1473460D01*
Y1475721D01*
X835380Y1475774D01*
G02X834203Y1477462I820J1826D01*
G01X834190Y1477648D01*
X828719D01*
X827969Y1478398D01*
X827000D01*
G02X825669Y1479110I1J1602D01*
G01X825609Y1479198D01*
X825302D01*
Y1476038D01*
X824102D01*
Y1472364D01*
X824144Y1472310D01*
G02Y1469090I-2044J-1610D01*
G01X824102Y1469036D01*
Y1467938D01*
X824126Y1467894D01*
G02X820074I-2026J-1094D01*
G01X820098Y1467938D01*
Y1469036D01*
X820056Y1469090D01*
G02Y1472310I2044J1610D01*
G01X820098Y1472364D01*
Y1476038D01*
X818898D01*
Y1479198D01*
X817902D01*
Y1476038D01*
X811098D01*
X811054Y1476014D01*
G02Y1480066I-1094J2026D01*
G01X811098Y1480042D01*
X811498D01*
Y1485162D01*
X812101D01*
G03X812486Y1485671I0J400D01*
G02X813151Y1488003I2214J629D01*
G03X812882Y1488698I-270J295D01*
G01X810312D01*
X803462Y1481848D01*
X758672D01*
X758645Y1481840D01*
G02Y1486260I-646J2210D01*
G01X758672Y1486252D01*
X801638D01*
X805852Y1490466D01*
G03X805569Y1491148I-283J282D01*
G01X793694D01*
X793634Y1491063D01*
G02X789364I-2135J1487D01*
G01X789304Y1491148D01*
X757418D01*
X739598Y1508969D01*
Y1544631D01*
X756918Y1561952D01*
X768404D01*
X768758Y1561598D01*
X769827D01*
G02X769915Y1561595I-11J-1602D01*
G01X770126D01*
Y1570294D01*
X772829Y1572998D01*
X787325D01*
X789528Y1570794D01*
Y1552298D01*
X787325Y1550094D01*
X783779D01*
Y1546344D01*
X781952D01*
Y1545219D01*
X782046Y1545160D01*
G02X782802Y1543800I-845J-1360D01*
G01Y1542831D01*
X783306Y1542327D01*
Y1540383D01*
X783391Y1540323D01*
G02X779501Y1537190I-1487J-2135D01*
G03X778854Y1537325I-370J-153D01*
G02X775212Y1541042I-1804J1875D01*
G03X775219Y1541319I-141J142D01*
G02X774798Y1542400I1181J1082D01*
G01Y1543369D01*
X773273Y1544894D01*
X772229D01*
Y1544294D01*
X766400D01*
Y1543869D01*
X764829Y1542298D01*
Y1541734D01*
X758490D01*
X758433Y1541630D01*
G02X757027Y1540794I-1407J766D01*
G01X755627D01*
G02X755205Y1540851I2J1602D01*
G03X754699Y1540479I-106J-386D01*
G02X754642Y1540018I-2600J87D01*
G01X754619Y1539912D01*
X755034Y1539498D01*
X757034D01*
X757948Y1538583D01*
X758009Y1538572D01*
G02X759081Y1537851I-282J-1576D01*
G01X759140Y1537758D01*
X759976D01*
Y1538358D01*
X767178D01*
Y1535798D01*
X773439D01*
X773483Y1535822D01*
G02X776812Y1534347I1094J-2026D01*
G01X776850Y1534194D01*
X778181D01*
G02X779003Y1533967I0J-1602D01*
G01X779122Y1533896D01*
X779494Y1534268D01*
X781504D01*
X781577Y1534195D01*
X781631Y1534194D01*
G02X783182Y1532593I-51J-1601D01*
G01Y1532590D01*
X783218Y1532555D01*
Y1531427D01*
G03X783718Y1531216I364J165D01*
G02X785174Y1531251I780J-2166D01*
G03X785692Y1531633I118J382D01*
G01Y1532730D01*
X788251D01*
Y1539230D01*
X788852D01*
Y1542885D01*
X789215Y1543248D01*
X789206Y1543341D01*
G02X793268Y1545023I2293J209D01*
G01X793328Y1544952D01*
X794500D01*
Y1546300D01*
X794567D01*
G03X794708Y1546641I0J200D01*
G01X793798Y1547552D01*
Y1567548D01*
X796001Y1569752D01*
X834448D01*
X837502Y1566698D01*
Y1551502D01*
X837252Y1551253D01*
Y1549752D01*
X882497D01*
X884273Y1547975D01*
X884839D01*
Y1547409D01*
X885200Y1547048D01*
Y1538552D01*
X884839Y1538191D01*
Y1537409D01*
X885200Y1537048D01*
Y1533552D01*
X884839Y1533191D01*
Y1532971D01*
X884619D01*
X883997Y1532348D01*
X870497D01*
X865705Y1527557D01*
G03X865988Y1526874I283J-283D01*
G37*
G36*
G01X888620Y977393D02*
X888677Y977294D01*
X892154D01*
X892374Y977073D01*
X898805D01*
G03X899130Y977706I0J400D01*
G02X903018Y980156I1869J1344D01*
G01X903032Y980131D01*
X906748Y976415D01*
G02X906833Y976352I-915J-1323D01*
G01X906956Y976432D01*
G02X907833Y976694I878J-1340D01*
G01X909233D01*
G02X910834Y975092I-1J-1602D01*
G01Y973802D01*
X918000D01*
Y972502D01*
X927304D01*
X927364Y972587D01*
G02Y969613I2135J-1487D01*
G01X927304Y969698D01*
X925500D01*
Y964524D01*
X923450D01*
Y963245D01*
X923536Y963185D01*
G02X919914Y959563I-1487J-2135D01*
G01X919854Y959648D01*
X917118D01*
X916968Y959798D01*
X915899D01*
G02X914899Y960149I1J1602D01*
G02X913899Y959798I-1001J1251D01*
G01X912830D01*
X910680Y957648D01*
X902968D01*
X900801Y959816D01*
X900708Y959807D01*
G02X902792Y961891I-209J2293D01*
G01X902783Y961798D01*
X903228Y961353D01*
X903440Y961566D01*
X903426Y961666D01*
G02X903661Y963192I2573J385D01*
G01X903682Y963234D01*
Y964273D01*
X903587Y964332D01*
G02X902832Y965692I847J1360D01*
G01Y966661D01*
X900424Y969069D01*
X896900D01*
Y964828D01*
X896950Y964771D01*
G02X893976Y965443I-1952J-1721D01*
G01X894098Y965494D01*
Y969069D01*
X889792D01*
Y970056D01*
X888365D01*
X888308Y970005D01*
G02X888224Y969934I-1075J1187D01*
G03X888222Y969621I123J-157D01*
G02X884382Y968988I-1639J-2021D01*
G03X884002Y969599I-338J213D01*
G02X883833Y969590I-170J1593D01*
G01X882433D01*
G02X881907Y969679I1J1602D01*
G01X881875Y969690D01*
X880381D01*
X880354Y969682D01*
G02Y974102I-646J2210D01*
G01X880381Y974094D01*
X880557D01*
G03X880932Y974633I0J400D01*
G02X880832Y975192I1501J557D01*
G01Y976592D01*
G02X880876Y976967I1601J2D01*
G01X880882Y976990D01*
Y977485D01*
G03X880199Y977768I-400J0D01*
G01X880042Y977611D01*
X880060Y977508D01*
G02X877957Y979611I-2561J-458D01*
G01X878060Y979593D01*
X880918Y982452D01*
X885580D01*
X887984Y980047D01*
Y978011D01*
X888079Y977952D01*
G02X888620Y977393I-846J-1360D01*
G37*
G36*
G01X153998Y244379D02*
X154103Y244435D01*
Y245469D01*
X164007D01*
Y237916D01*
X154103D01*
Y238931D01*
X154062Y238953D01*
G02X153445Y239397I1059J2123D01*
G01X153226Y239616D01*
G03X153199Y239628I-28J-27D01*
G01X152306D01*
X152284Y239453D01*
G02X148352Y241337I-2285J276D01*
G03Y241896I-286J279D01*
G02X152267Y243897I1647J1608D01*
G01X152296Y243732D01*
X153215D01*
X153466Y243982D01*
G02X153998Y244379I1627J-1625D01*
G37*
G36*
G01X361301Y61578D02*
G02X360472Y59781I-2302J-28D01*
G01X360400Y59721D01*
Y56686D01*
X360419Y56646D01*
G02X355498Y56008I-2360J-1096D01*
G01X355516Y56111D01*
X352848Y58779D01*
Y59988D01*
X350648D01*
Y62548D01*
X343980D01*
X343644Y62213D01*
X343628Y62176D01*
G02X340065Y61249I-2129J874D01*
G03X339533Y61219I-249J-313D01*
G02X338399Y60748I-1134J1130D01*
G01X336999D01*
G02X335999Y61099I1J1602D01*
G02X334999Y60748I-1001J1251D01*
G01X333599D01*
G02X331998Y62350I1J1602D01*
G01Y63750D01*
G02X332042Y64125I1601J2D01*
G01X332048Y64148D01*
Y65952D01*
X332042Y65975D01*
G02X331998Y66350I1557J373D01*
G01Y66447D01*
G03X331315Y66730I-400J0D01*
G01X324532Y59946D01*
Y59162D01*
X323747D01*
X322997Y58412D01*
X318501D01*
X317751Y59162D01*
X317628D01*
Y59284D01*
X316798Y60115D01*
Y67684D01*
G03X316115Y67967I-400J0D01*
G01X313370Y65221D01*
Y59162D01*
X306466D01*
Y59348D01*
X296284D01*
X296232Y59311D01*
G02X295299Y59012I-932J1302D01*
G01X292699D01*
G02X291766Y59311I-1J1601D01*
G01X291714Y59348D01*
X290501D01*
X287298Y62552D01*
Y67548D01*
X288916Y69166D01*
G03X288633Y69848I-283J282D01*
G01X287501D01*
X285798Y71552D01*
Y82048D01*
X286872Y83122D01*
G03X286657Y83799I-283J283D01*
G02X284965Y84876I443J2564D01*
G01X284905Y84962D01*
X283356D01*
X283102Y85216D01*
X283009Y85207D01*
G02X284861Y88525I-209J2293D01*
G03X285470Y88391I358J178D01*
G02X289235Y87850I1630J-2028D01*
G01X289295Y87764D01*
X290731D01*
X290788Y87870D01*
G02X292199Y88714I1411J-757D01*
G01X293799D01*
G02X294291Y88637I1J-1601D01*
G03X294770Y88837I122J381D01*
G02X295139Y89313I1428J-726D01*
G03Y89913I-265J300D01*
G02X294598Y91113I1060J1200D01*
G01Y93713D01*
G02X295931Y95292I1602J0D01*
G01X296098Y95320D01*
Y95721D01*
X296026Y95781D01*
G02X295513Y98714I1473J1769D01*
G03X295212Y99314I-345J202D01*
G02X297635Y103387I288J2586D01*
G01X297695Y103302D01*
X300181D01*
X302381Y101102D01*
X303825D01*
G02X305826Y99100I-1J-2002D01*
G01Y96200D01*
G02X304645Y94374I-2002J0D01*
G01X304526Y94321D01*
Y93906D01*
X305431Y93002D01*
X306400D01*
G02X308002Y91400I0J-1602D01*
G01Y90000D01*
G02X307925Y89512I-1602J3D01*
G01X307916Y89483D01*
Y89252D01*
X308291D01*
G02X308403Y89285I710J-2202D01*
G01X313618Y94500D01*
X312198Y95919D01*
Y103231D01*
X312425Y103457D01*
G03X312284Y103798I-141J141D01*
G01X309708D01*
X309699Y103608D01*
G02X307700Y101698I-1999J91D01*
G01X306300D01*
G02X304298Y103700I0J2002D01*
G01Y106600D01*
G02X305753Y108525I2001J0D01*
G01X305898Y108567D01*
Y111105D01*
X305813Y111165D01*
G02X308787I1487J2135D01*
G01X308702Y111105D01*
Y108336D01*
X308792Y108277D01*
G02X309693Y106783I-1092J-1677D01*
G01X309710Y106602D01*
X314056D01*
X314113Y106701D01*
G02X315500Y107502I1387J-800D01*
G01X316900D01*
G02X317900Y107151I-1J-1602D01*
G02X318900Y107502I1001J-1251D01*
G01X320300D01*
G02X320826Y107413I-1J-1602D01*
G01X320858Y107402D01*
X322727D01*
X322754Y107410D01*
G02Y102990I646J-2210D01*
G01X322727Y102998D01*
X320858D01*
X320826Y102987D01*
G02X320300Y102898I-527J1513D01*
G01X318900D01*
G02X317900Y103249I1J1602D01*
G02X317387Y102974I-1001J1251D01*
G03X317256Y102283I122J-381D01*
G02X318006Y101159I-1456J-1783D01*
G01X318020Y101110D01*
X319402Y99729D01*
Y99462D01*
X320602D01*
Y96302D01*
X321598D01*
Y99462D01*
X340531D01*
X341298Y100228D01*
Y116548D01*
X343501Y118752D01*
X363997D01*
X365700Y117048D01*
Y99552D01*
X363497Y97348D01*
X344079D01*
X342189Y95458D01*
X328002D01*
Y90338D01*
X327448D01*
G03X327056Y89858I0J-400D01*
G02X327048Y88903I-2256J-459D01*
G03X327721Y88534I391J-86D01*
G01X332001Y92814D01*
X357334D01*
X358800Y91348D01*
Y91002D01*
X363451D01*
Y88691D01*
G03X364095Y88374I400J0D01*
G02Y84726I1404J-1824D01*
G03X363451Y84409I-244J-317D01*
G01Y82098D01*
X358800D01*
Y79715D01*
X356997Y77912D01*
X342497D01*
X337519Y72934D01*
G03X337802Y72251I283J-283D01*
G01X350298D01*
Y72548D01*
X352501Y74752D01*
X400997D01*
X403200Y72548D01*
Y58349D01*
X403411D01*
G02X403499Y58352I99J-1599D01*
G01X404899D01*
G02X406286Y57551I0J-1601D01*
G01X406343Y57452D01*
X408580D01*
X409438Y56593D01*
X409541Y56611D01*
G02Y51489I458J-2561D01*
G01X409438Y51507D01*
X407580Y49648D01*
X407365D01*
G03X407224Y49307I0J-200D01*
G01X407900Y48631D01*
Y43469D01*
X406235Y41804D01*
G03X406249Y41225I283J-283D01*
G02X402523Y37608I-1750J-1925D01*
G03X401915I-304J-260D01*
G02X400699Y37048I-1216J1040D01*
G01X399299D01*
G02X398106Y37582I1J1602D01*
G01X398046Y37648D01*
X397401D01*
Y37048D01*
X391900D01*
Y29219D01*
X389000Y26319D01*
Y25350D01*
G02X387399Y23748I-1601J-1D01*
G01X385999D01*
G02X385911Y23751I11J1602D01*
G01X385700D01*
Y14552D01*
X382997Y11848D01*
X368501D01*
X366298Y14052D01*
Y32548D01*
X368501Y34752D01*
X372047D01*
Y39002D01*
X373948D01*
Y40181D01*
X373854Y40240D01*
G02X373225Y40976I846J1360D01*
G01X373173Y41098D01*
X372379D01*
X372321Y41041D01*
G02X372851Y44016I-1821J1859D01*
G01X372905Y43902D01*
X373373D01*
X373433Y43979D01*
G02X374700Y44602I1268J-979D01*
G01X376100D01*
G02X376739Y44469I0J-1602D01*
G03X377298Y44835I159J367D01*
G01Y45105D01*
X377213Y45165D01*
G02X380187I1487J2135D01*
G01X380102Y45105D01*
Y44489D01*
X380213Y44434D01*
G02X381102Y43000I-712J-1434D01*
G01Y41718D01*
X382368Y40452D01*
X383597D01*
Y41052D01*
X389098D01*
Y41631D01*
X390478Y43012D01*
X390997D01*
Y43612D01*
X391704D01*
G03X392074Y44166I1J400D01*
G02X396324I2125J884D01*
G03X396694Y43612I369J-154D01*
G01X397697D01*
X397730Y43772D01*
G02X399299Y45052I1569J-322D01*
G01X400205D01*
G03X400577Y45598I0J400D01*
G02X400438Y47008I2422J951D01*
G01X400456Y47111D01*
X399348Y48219D01*
Y48931D01*
X399253Y48990D01*
G02X398745Y49495I846J1360D01*
G01X398686Y49588D01*
X397850D01*
Y48988D01*
X390648D01*
Y51548D01*
X384148D01*
Y52148D01*
X383828D01*
X383768Y52077D01*
G02X380964Y51494I-1769J1473D01*
G03X380710Y51430I-90J-179D01*
G02X379399Y50748I-1311J919D01*
G01X377999D01*
G02X376999Y51099I1J1602D01*
G02X375999Y50748I-1001J1251D01*
G01X374599D01*
G02X372998Y52350I1J1602D01*
G01Y53750D01*
G02X373042Y54125I1601J2D01*
G01X373048Y54148D01*
Y54848D01*
X369001D01*
X361984Y61866D01*
G03X361301Y61578I-283J-283D01*
G37*
G36*
G01X270497Y1172252D02*
X276200Y1166548D01*
Y1148552D01*
X271497Y1143848D01*
X220501D01*
X217798Y1146552D01*
Y1167548D01*
X222501Y1172252D01*
X270497D01*
G37*
G36*
G01X858214Y1877014D02*
X859814D01*
G02X860814Y1876664I1J-1601D01*
G02X861814Y1877014I999J-1251D01*
G01X863414D01*
G02X864487Y1876602I1J-1601D01*
G01X864544Y1876550D01*
X864999D01*
X865999Y1875550D01*
X881916D01*
X881969Y1875589D01*
G02X882160Y1875719I1718J-2319D01*
G01X882180Y1875731D01*
X882449Y1876000D01*
Y1876966D01*
X892353D01*
Y1875196D01*
X892499Y1875050D01*
Y1872050D01*
X892353Y1871904D01*
Y1869413D01*
X882449D01*
Y1870450D01*
X882343Y1870506D01*
G02X882308Y1870525I1234J2315D01*
G01X882263Y1870550D01*
X880999D01*
X880499Y1870050D01*
X865999D01*
X864499Y1868550D01*
X848499D01*
X846999Y1870050D01*
Y1872550D01*
X850999Y1876550D01*
X857084D01*
X857141Y1876602D01*
G02X858213Y1877014I1072J-1189D01*
G01X858214D01*
G37*
G36*
G01X880999Y1861676D02*
X869217D01*
X869191Y1861505D01*
G02X865267Y1863448I-2277J335D01*
G03Y1864007I-286J280D01*
G02X869191Y1865951I1647J1608D01*
G01X869217Y1865778D01*
X881000D01*
G03X881669Y1865886I-1J2131D01*
G01X881723Y1865940D01*
X881727Y1865945D01*
G02X882344Y1866437I1671J-1463D01*
G01X882449Y1866494D01*
Y1867517D01*
X892353D01*
Y1859964D01*
X882449D01*
Y1860983D01*
X882343Y1861040D01*
G02X881772Y1861459I1156J2174D01*
G03X881632Y1861533I-764J-1277D01*
G02X881630Y1861534I626J1254D01*
G03X880999Y1861676I-634J-1346D01*
G37*
G36*
G01X154085Y1859964D02*
X152499Y1861550D01*
X141499D01*
X138999Y1859050D01*
X135499D01*
X133999Y1860550D01*
Y1865550D01*
X132499Y1867050D01*
X122499D01*
X120999Y1868550D01*
Y1875550D01*
X122499Y1877050D01*
X164499D01*
X165499Y1876050D01*
Y1861550D01*
X164007Y1860058D01*
Y1859964D01*
X154085D01*
G37*
G36*
G01X803709Y1825001D02*
X803802Y1824992D01*
X805761Y1826952D01*
X811655D01*
X811712Y1827051D01*
G02X813099Y1827852I1387J-800D01*
G01X814499D01*
G02X815499Y1827501I-1J-1602D01*
G02X816499Y1827852I1001J-1251D01*
G01X817899D01*
G02X819460Y1826607I0J-1601D01*
G01X819496Y1826452D01*
X821304D01*
X821364Y1826537D01*
G02X825634I2135J-1487D01*
G01X825694Y1826452D01*
X827478D01*
X834414Y1819515D01*
Y1819379D01*
X834915D01*
Y1810975D01*
X829294D01*
Y1809862D01*
X827580Y1808148D01*
X817156D01*
X817106Y1808022D01*
G02X816500Y1811011I-2607J1027D01*
G01X816559Y1810952D01*
X825991D01*
Y1819379D01*
X826932D01*
G03X827215Y1820062I0J400D01*
G01X826378Y1820898D01*
X819510D01*
X819495Y1820715D01*
G02X818745Y1819490I-1596J135D01*
G01X818650Y1819431D01*
Y1818219D01*
X818042Y1817611D01*
X818060Y1817508D01*
G02X813675Y1818906I-2561J-458D01*
G01X813735Y1818965D01*
Y1819248D01*
X813099D01*
G02X811712Y1820049I0J1601D01*
G01X811655Y1820148D01*
X807819D01*
X807786Y1820136D01*
G02X805201Y1820864I-786J2164D01*
G03X804921Y1820897I-157J-124D01*
G02X803709Y1825001I-1421J1811D01*
G37*
G36*
G01X878173Y1783967D02*
G03X878179Y1784572I-259J305D01*
G02X880346Y1788510I1521J1728D01*
G01X880373Y1788502D01*
X881642D01*
X881674Y1788513D01*
G02X882200Y1788602I527J-1513D01*
G01X883600D01*
G02X884600Y1788251I-1J-1602D01*
G02X885600Y1788602I1001J-1251D01*
G01X887000D01*
G02X887380Y1788556I-1J-1602D01*
G01X887404Y1788550D01*
X901499D01*
X902216Y1789267D01*
X902222Y1789339D01*
G02X907393Y1788767I2592J-226D01*
G01X907380Y1788669D01*
X908135Y1787914D01*
X908964D01*
G02X910566Y1786313I1J-1601D01*
G01Y1785484D01*
X910999Y1785050D01*
X912999D01*
X913598Y1785648D01*
Y1789305D01*
X913512Y1789365D01*
G02X915604Y1794031I1487J2135D01*
G03X916098Y1794420I94J389D01*
G01Y1794721D01*
X916026Y1794781D01*
G02X918972I1473J1769D01*
G01X918900Y1794721D01*
Y1779826D01*
X925000D01*
Y1774424D01*
X922900D01*
Y1772245D01*
X922986Y1772185D01*
G02X919364Y1768563I-1487J-2135D01*
G01X919304Y1768648D01*
X917218D01*
X916468Y1769398D01*
X915848D01*
X915499Y1769050D01*
X898116D01*
X898084Y1769039D01*
G02X896394I-845J2461D01*
G01X896362Y1769050D01*
X886499D01*
X882999Y1772550D01*
Y1779912D01*
X882164D01*
G02X881638Y1780000I-2J1601D01*
G01X881606Y1780012D01*
X880337D01*
X880310Y1780003D01*
G02X878173Y1783967I-646J2210D01*
G37*
G36*
G01X100635Y1534154D02*
G03X100423Y1533983I-14J-199D01*
G02X98309Y1536605I-2279J326D01*
G03X98521Y1536776I14J199D01*
G02X98803Y1537595I2279J-327D01*
G03X98731Y1537866I-174J99D01*
G02X101896Y1538705I1168J1984D01*
G03X101968Y1538434I174J-99D01*
G02X100635Y1534154I-1168J-1984D01*
G37*
G36*
G01X850696Y1464683D02*
G03X850424Y1464688I-139J-144D01*
G02X849390Y1468649I-1536J1714D01*
G02X852798Y1469623I3409J-5479D01*
G01X854626D01*
Y1470096D01*
G02X856227Y1471698I1601J1D01*
G01X857827D01*
G02X858827Y1471347I-1J-1602D01*
G02X859827Y1471698I1001J-1251D01*
G01X861427D01*
G02X863028Y1470096I-1J-1602D01*
G01Y1469716D01*
X881560D01*
X881618Y1469770D01*
G02X882341Y1470282I2197J-2337D01*
G01X882449Y1470338D01*
Y1471454D01*
X892353D01*
Y1463901D01*
X882449D01*
Y1464924D01*
X882343Y1464981D01*
G02X881761Y1465413I1167J2181D01*
G03X881279Y1465612I-481J-482D01*
G01X863399D01*
G03X863028Y1465585I-7J-2471D01*
G01Y1464996D01*
G02X861427Y1463394I-1601J-1D01*
G01X859827D01*
G02X858827Y1463745I1J1602D01*
G02X857827Y1463394I-1001J1251D01*
G01X856227D01*
G02X854626Y1464996I1J1602D01*
G01Y1465246D01*
X854313D01*
X854255Y1465150D01*
G02X850696Y1464683I-1967J1196D01*
G37*
G36*
G01X876803Y1454518D02*
X876753Y1454550D01*
X876499D01*
X875499Y1455550D01*
Y1461050D01*
X876499Y1462050D01*
X876823D01*
X876863Y1462069D01*
G02X878843I990J-2078D01*
G01X878883Y1462050D01*
X892499D01*
X892999Y1461550D01*
Y1455050D01*
X892499Y1454550D01*
X892353D01*
Y1454452D01*
X882449D01*
Y1454550D01*
X879355D01*
X879305Y1454518D01*
G02X876803I-1251J1932D01*
G37*
G36*
G01X872611Y1353604D02*
G03X872090Y1353338I-137J-376D01*
G02X868250Y1356282I-2503J712D01*
G01X868348Y1356341D01*
Y1357431D01*
X868253Y1357490D01*
G02X867498Y1358850I847J1360D01*
G01Y1360098D01*
X860498D01*
Y1363100D01*
X850100D01*
Y1365274D01*
X849449D01*
X849389Y1365211D01*
G02X849407Y1368770I-1889J1789D01*
G03X850100Y1369042I293J272D01*
G01Y1372200D01*
X856098D01*
Y1372900D01*
G02X857699Y1374502I1601J1D01*
G01X859099D01*
G02X859352Y1374481I-6J-1602D01*
G03X859776Y1375050I63J395D01*
G02X863930Y1377035I2073J1000D01*
G03X864632Y1376997I361J171D01*
G02X865094Y1377540I1963J-1202D01*
G03X865109Y1378132I-261J303D01*
G02X867346Y1382006I1591J1664D01*
G01X867373Y1381998D01*
X868869D01*
X868901Y1382009D01*
G02X869427Y1382098I527J-1513D01*
G01X870827D01*
G02X871827Y1381747I-1J-1602D01*
G02X872827Y1382098I1001J-1251D01*
G01X874227D01*
G02X875358Y1381630I0J-1601D01*
G01X875417Y1381572D01*
X877804D01*
X877864Y1381657D01*
G02X882126Y1381669I2135J-1487D01*
G01X882185Y1381584D01*
X889792D01*
Y1382585D01*
X901546D01*
Y1381584D01*
X901827D01*
X905400Y1378011D01*
Y1366469D01*
X901080Y1362148D01*
X894194D01*
X894134Y1362063D01*
G02X889864I-2135J1487D01*
G01X889804Y1362148D01*
X875343D01*
X875286Y1362049D01*
G02X875117Y1361810I-1387J801D01*
G03Y1361290I304J-260D01*
G02X875500Y1360250I-1218J-1039D01*
G01Y1358850D01*
G02X875456Y1358475I-1601J-2D01*
G01X875450Y1358452D01*
Y1357773D01*
X875497Y1357717D01*
G02X875643Y1357524I-2000J-1665D01*
G01X875654Y1357509D01*
X875700Y1357462D01*
Y1357438D01*
X875729Y1357391D01*
G02X872611Y1353604I-2230J-1341D01*
G37*
G36*
G01X144384Y1336735D02*
X144394Y1336670D01*
X145902Y1335162D01*
Y1334926D01*
X146195D01*
X146255Y1334998D01*
G02X149959Y1332279I1769J-1473D01*
G03X150296Y1331662I336J-217D01*
G01X150602D01*
Y1328502D01*
X151621D01*
X151679Y1328559D01*
G02X151149Y1325584I1821J-1859D01*
G01X151095Y1325698D01*
X150602D01*
Y1322538D01*
X150048D01*
G03X149656Y1322058I0J-400D01*
G02X145144I-2256J-458D01*
G03X144752Y1322538I-392J80D01*
G01X144198D01*
Y1325698D01*
X143202D01*
Y1322538D01*
X138969D01*
X138070Y1321640D01*
X138056Y1321591D01*
G02X135191Y1324456I-2206J659D01*
G01X135240Y1324470D01*
X136694Y1325924D01*
X135398Y1327219D01*
Y1333181D01*
X135934Y1333716D01*
G03X135651Y1334398I-283J282D01*
G01X132302D01*
Y1332800D01*
G02X130300Y1330798I-2002J0D01*
G01X128900D01*
G02X126898Y1332800I0J2002D01*
G01Y1335700D01*
G02X128900Y1337702I2002J0D01*
G01X130300D01*
G02X131570Y1337247I-1J-2002D01*
G01X131625Y1337202D01*
X136556D01*
X136613Y1337301D01*
G02X138000Y1338102I1387J-800D01*
G01X139400D01*
G02X140400Y1337751I-1J-1602D01*
G02X141400Y1338102I1001J-1251D01*
G01X142800D01*
G02X144384Y1336735I0J-1601D01*
G37*
G36*
G01X882449Y1059051D02*
X881500Y1060000D01*
X878500D01*
X876500Y1058000D01*
X852500D01*
X851500Y1059000D01*
X845000D01*
X844000Y1060000D01*
Y1064500D01*
X846500Y1067000D01*
X861000D01*
X862500Y1065500D01*
X882449D01*
Y1065942D01*
X892353D01*
Y1065147D01*
X893000Y1064500D01*
Y1059500D01*
X892500Y1059000D01*
X892353D01*
Y1058389D01*
X882449D01*
Y1059051D01*
G37*
G36*
G01X880899Y1054452D02*
X881918D01*
X882159Y1054692D01*
X882358Y1054891D01*
G02X882388Y1054921I1919J-1889D01*
G01X882449Y1054980D01*
Y1056493D01*
X892353D01*
Y1048940D01*
X882449D01*
Y1050348D01*
X880415D01*
X880364Y1050224D01*
G02X876426Y1052521I-2131J871D01*
G03X876404Y1052792I-157J124D01*
G02X880265Y1054544I1560J1693D01*
G03X880899Y1054452I632J2127D01*
G37*
G36*
G01X750870Y681673D02*
X750924Y681686D01*
X753489Y684252D01*
X813284D01*
G03X813567Y684934I0J400D01*
G01X812198Y686302D01*
Y689550D01*
X809032D01*
X808131Y688648D01*
X779194D01*
X779134Y688563D01*
G02X774864I-2135J1487D01*
G01X774804Y688648D01*
X751418D01*
X741198Y698869D01*
Y742063D01*
X753418Y754284D01*
X764232D01*
X767494Y757546D01*
Y764880D01*
X770198Y767584D01*
X784694D01*
X784727Y767550D01*
X784999D01*
X786999Y765550D01*
Y745550D01*
X779799Y738350D01*
X779878Y738216D01*
G02X780102Y737400I-1378J-817D01*
G01Y736000D01*
G02X780015Y735481I-1592J0D01*
G03X780132Y735229I189J-65D01*
G02X781054Y730975I-932J-2429D01*
G01X780915Y730833D01*
X781700Y730048D01*
Y728848D01*
X782866Y727683D01*
X782902Y727668D01*
G02X784019Y726654I-903J-2117D01*
G01X784076Y726550D01*
X785497D01*
Y732402D01*
X786098D01*
Y735131D01*
X786715Y735748D01*
X786706Y735841D01*
G02X789585Y738276I2293J209D01*
G01X789696Y738247D01*
X790499Y739050D01*
Y741351D01*
X790298Y741552D01*
Y760548D01*
X793501Y763752D01*
X798197D01*
X798239Y763772D01*
G02X800531I1146J-2336D01*
G01X800573Y763752D01*
X832348D01*
X835002Y761098D01*
Y744802D01*
X834552Y744353D01*
Y744050D01*
X878499D01*
X885499Y737050D01*
Y722050D01*
X884499Y721050D01*
X869499D01*
X868999Y720550D01*
Y718050D01*
X869499Y717550D01*
X884999D01*
X885499Y717050D01*
Y712050D01*
X884999Y711550D01*
X869499D01*
X868999Y711050D01*
Y708778D01*
X869694Y708084D01*
X883194D01*
X883227Y708050D01*
X884499D01*
X885499Y707050D01*
Y692550D01*
X884499Y691550D01*
X869999D01*
X868999Y690550D01*
Y688050D01*
X869999Y687050D01*
X884999D01*
X885999Y686050D01*
Y682050D01*
X884999Y681050D01*
X863481D01*
X863162Y680730D01*
X859464D01*
X859407Y680625D01*
G02X857996Y679780I-1412J757D01*
G01X856396D01*
G02X855904Y679858I2J1602D01*
G03X855425Y679658I-122J-381D01*
G02X855056Y679182I-1428J726D01*
G03Y678582I265J-300D01*
G02X855598Y677382I-1060J-1201D01*
G01Y674782D01*
G02X854612Y673304I-1601J0D01*
G03X854459Y672677I153J-370D01*
G02X854441Y669696I-1763J-1480D01*
G03X854458Y669418I152J-130D01*
G02X850941Y669411I-1755J-1921D01*
G03X850956Y669689I-136J147D01*
G02X850933Y672677I1740J1507D01*
G03X850780Y673304I-306J257D01*
G02X849794Y674782I615J1478D01*
G01Y675698D01*
X849534D01*
X849484Y675665D01*
G02X849401Y675613I-891J1330D01*
G01X849302Y675556D01*
Y673536D01*
X849337Y673484D01*
G02X846595Y669469I-2137J-1484D01*
G03X846102Y669080I-93J-389D01*
G01Y668500D01*
G03X846488Y668101I400J0D01*
G02X843839Y665958I-88J-2601D01*
G01X843857Y666061D01*
X843298Y666619D01*
Y675473D01*
X843176Y675525D01*
G02X842440Y676154I624J1475D01*
G01X842381Y676248D01*
X841885D01*
X841872Y676062D01*
G02X839875Y674198I-1997J138D01*
G01X838475D01*
G02X836474Y676200I1J2002D01*
G01Y679100D01*
G02X836495Y679390I2001J1D01*
G03X836099Y679848I-396J58D01*
G01X822602D01*
Y674662D01*
X823802D01*
Y672403D01*
G03X824441Y672083I400J1D01*
G02X825400Y672402I959J-1282D01*
G01X826800D01*
G02X828160Y671646I0J-1601D01*
G01X828219Y671552D01*
X832590D01*
X832603Y671738D01*
G02X834600Y673602I1997J-138D01*
G01X836000D01*
G02X838002Y671600I0J-2002D01*
G01Y668700D01*
G02X836820Y666874I-2001J0D01*
G01X836702Y666821D01*
Y665395D01*
X836787Y665335D01*
G02X833813I-1487J-2135D01*
G01X833898Y665395D01*
Y666821D01*
X833780Y666874D01*
G02X832603Y668562I820J1826D01*
G01X832590Y668748D01*
X831901D01*
G03X831590Y668097I0J-400D01*
G02X829154Y664440I-1790J-1447D01*
G01X829127Y664448D01*
X827198D01*
X827175Y664443D01*
G02X826800Y664398I-377J1557D01*
G01X825400D01*
G02X823911Y665411I0J1601D01*
G01X823861Y665538D01*
X823169D01*
G03X822788Y665014I-1J-400D01*
G02X818412I-2188J-714D01*
G03X818031Y665538I-380J124D01*
G01X817398D01*
Y668698D01*
X816402D01*
Y665538D01*
X809797D01*
X809753Y665514D01*
G02X809459Y669699I-1093J2026D01*
G03X809998Y670074I139J375D01*
G01Y674662D01*
X810631D01*
G03X811012Y675186I1J400D01*
G02X815388I2188J714D01*
G03X815769Y674662I380J-124D01*
G01X816402D01*
Y671502D01*
X817398D01*
Y674662D01*
X818598D01*
Y679848D01*
X755313D01*
X754037Y678573D01*
X754024Y678519D01*
G02X750870Y681673I-2525J629D01*
G37*
G36*
G01X849367Y653710D02*
G02X848073Y657652I-1595J1660D01*
G02X850676Y658708I2603J-2680D01*
G01X853494D01*
Y659182D01*
G02X855096Y660784I1602J0D01*
G01X856696D01*
G02X857696Y660433I-1J-1602D01*
G02X858696Y660784I1001J-1251D01*
G01X860296D01*
G02X861898Y659182I0J-1602D01*
G01Y658752D01*
X881963D01*
X882019Y658802D01*
G02X882361Y659068I2131J-2387D01*
G01X882449Y659128D01*
Y660430D01*
X892353D01*
Y652877D01*
X882449D01*
Y654438D01*
X882380Y654498D01*
G02X882275Y654594I2238J2554D01*
G01X882217Y654648D01*
X861898D01*
Y654082D01*
G02X860296Y652480I-1602J0D01*
G01X858696D01*
G02X857696Y652831I1J1602D01*
G02X856696Y652480I-1001J1251D01*
G01X855096D01*
G02X853494Y654082I0J1602D01*
G01Y654307D01*
X853184D01*
X853125Y654213D01*
G02X849639Y653715I-1953J1219D01*
G03X849367Y653710I-133J-149D01*
G37*
G36*
G01X876949Y647181D02*
G03Y647740I-286J279D01*
G02X880881Y649627I1647J1608D01*
G01X880902Y649452D01*
X881924D01*
X881979Y649499D01*
G02X882352Y649766I1823J-2153D01*
G01X882449Y649824D01*
Y650981D01*
X892353D01*
Y643428D01*
X882449D01*
Y644851D01*
X882376Y644911D01*
G02X882158Y645109I1940J2354D01*
G01X881918Y645348D01*
X880893D01*
X880865Y645182D01*
G02X876949Y647181I-2269J391D01*
G37*
G36*
G01X153199Y645148D02*
X146537D01*
X146509Y644981D01*
G02X142591Y646964I-2271J375D01*
G03Y647523I-286J280D01*
G02X146521Y649426I1647J1608D01*
G01X146544Y649252D01*
X153617D01*
X153675Y649306D01*
G02X154018Y649587I2171J-2301D01*
G01X154103Y649647D01*
Y650981D01*
X164007D01*
Y643428D01*
X154103D01*
Y644580D01*
X154011Y644639D01*
G02X153573Y644993I1440J2230D01*
G03X153199Y645148I-374J-374D01*
G37*
G36*
G01X901464Y554334D02*
G03X900942Y554344I-267J-298D01*
G02X900687Y554252I-255J308D01*
G01X888411D01*
X887951Y554712D01*
Y557854D01*
G02Y557874I400J10D01*
G01X887680Y558070D01*
G02X885235Y562616I-931J2430D01*
G03X885216Y562953I-117J162D01*
G02X884999Y563099I783J1397D01*
G02X883999Y562748I-1001J1251D01*
G01X882599D01*
G02X882073Y562837I1J1602D01*
G01X882041Y562848D01*
X880623D01*
X880596Y562840D01*
G02X877660Y564819I-646J2210D01*
G03X877198Y565174I-398J-40D01*
G02X877019Y570335I-411J2569D01*
G03X877453Y570706I35J398D01*
G02X880396Y572760I2297J-156D01*
G01X880423Y572752D01*
X882041D01*
X882073Y572763D01*
G02X882599Y572852I527J-1513D01*
G01X883999D01*
G02X884999Y572501I-1J-1602D01*
G02X885999Y572852I1001J-1251D01*
G01X887399D01*
G02X888085Y572697I-1J-1602D01*
G01X888125Y572678D01*
X901798D01*
Y572990D01*
X901769Y573037D01*
G02X906574Y574005I2230J1341D01*
G01X906560Y573906D01*
X907380Y573085D01*
X907494Y573118D01*
G02X907946Y573184I455J-1536D01*
G01X909346D01*
G02X910948Y571582I0J-1602D01*
G01Y570182D01*
G02X910941Y570038I-1602J6D01*
G03X911339Y569602I398J-36D01*
G01X918000D01*
Y568952D01*
X925423D01*
X925458Y569109D01*
G02X927032Y566134I2541J-559D01*
G01X926997Y566148D01*
X925600D01*
Y558400D01*
X924847D01*
G03X924467Y557873I-1J-400D01*
G02X921038Y554632I-2468J-823D01*
G03X920542Y554456I-147J-372D01*
G02X920194Y554252I-349J196D01*
G01X908804D01*
G02X908456Y554456I1J400D01*
G03X907960Y554632I-349J-196D01*
G02X906032Y554634I-961J2418D01*
G01X905997Y554648D01*
X904828D01*
X904768Y554577D01*
G02X901464Y554334I-1769J1473D01*
G37*
G36*
G01X875981Y241053D02*
X875999Y241092D01*
Y242889D01*
X875981Y242928D01*
G02Y244828I2097J950D01*
G01X875999Y244867D01*
Y247050D01*
X875049Y248000D01*
X861558D01*
X861502Y247891D01*
G02X860078Y247022I-1424J732D01*
G01X858478D01*
G02X857478Y247373I1J1602D01*
G02X856478Y247022I-1001J1251D01*
G01X854878D01*
G02X853454Y247891I0J1601D01*
G01X853398Y248000D01*
X852463D01*
X852417Y247974D01*
G02X850139I-1139J2000D01*
G01X850093Y248000D01*
X848946D01*
X848904Y247979D01*
G02X846852I-1026J2061D01*
G01X846810Y248000D01*
X846500D01*
X845000Y249500D01*
Y250049D01*
X844999Y250050D01*
Y253050D01*
X847499Y255550D01*
X891999D01*
X893499Y254050D01*
Y254001D01*
X893500Y254000D01*
Y249500D01*
X893499Y249499D01*
Y239050D01*
X891999Y237550D01*
X880999D01*
X880499Y238050D01*
X879120D01*
X879079Y238030D01*
G02X875981Y241053I-1001J2073D01*
G37*
G36*
G01X827015Y206282D02*
G03X827373Y206279I180J88D01*
G02X827548Y206550I1426J-729D01*
G02X827198Y207550I1251J999D01*
G01Y208950D01*
G02X827565Y209971I1601J1D01*
G03X827326Y210620I-308J255D01*
G02X827440Y215763I449J2563D01*
G01X827507Y215772D01*
X827633Y215898D01*
X827624Y215991D01*
G02X831817Y217500I2293J209D01*
G03X832359Y217386I330J225D01*
G02X835833Y215885I1217J-1954D01*
G03X836063Y215727I196J39D01*
G02X836041Y210601I437J-2565D01*
G01X835938Y210619D01*
X835614Y210295D01*
X835760Y210150D01*
X835764Y210146D01*
G02X836300Y208950I-1066J-1196D01*
G01Y207550D01*
G02X836291Y207377I-1601J-3D01*
G03X836903Y206996I398J-43D01*
G02X836408Y203013I1396J-2196D01*
G03X835834Y203020I-290J-275D01*
G02X834699Y202548I-1135J1129D01*
G01X834414D01*
Y197331D01*
X834915D01*
Y188927D01*
X825991D01*
Y197076D01*
X824098Y198969D01*
Y202272D01*
X823938Y202305D01*
G02X827015Y206282I561J2745D01*
G37*
G36*
G01X230265Y176110D02*
G03X229733I-266J-299D01*
G02X226276Y180000I-1734J1940D01*
G03Y180600I-264J300D01*
G02Y184500I1723J1950D01*
G03Y185100I-264J300D01*
G02X226365Y189075I1723J1950D01*
G03X226299Y189741I-251J311D01*
G02X229449Y193773I1200J2309D01*
G03X230049I300J264D01*
G02X233439Y189883I1950J-1723D01*
G03Y189217I222J-333D01*
G02X233722Y185100I-1440J-2167D01*
G03Y184500I264J-300D01*
G02Y180600I-1723J-1950D01*
G03Y180000I264J-300D01*
G02X230265Y176110I-1723J-1950D01*
G37*
G36*
G01X180898Y151300D02*
Y152700D01*
G02X181110Y153498I1601J2D01*
G01X181187Y153630D01*
X180568Y154248D01*
X179499D01*
G02X178499Y154599I1J1602D01*
G02X177499Y154248I-1001J1251D01*
G01X176430D01*
X173830Y151648D01*
X173277D01*
X173220Y151599D01*
G02X168944Y153057I-1721J1951D01*
G03X168345Y153323I-393J-76D01*
G02X165211Y153659I-1346J2227D01*
G03X164569Y153526I-275J-291D01*
G02X159616Y155008I-2392J1025D01*
G01X159634Y155111D01*
X159598Y155147D01*
Y157719D01*
X158568Y158748D01*
X157499D01*
G02X156499Y159099I1J1602D01*
G02X155499Y158748I-1001J1251D01*
G01X154099D01*
G02X153573Y158837I1J1602D01*
G01X153541Y158848D01*
X150538D01*
X147198Y162188D01*
Y165727D01*
X147190Y165754D01*
G02X151607Y167055I2210J646D01*
G01X151649Y166912D01*
X151998D01*
Y167827D01*
X151990Y167854D01*
G02X156410I2210J646D01*
G01X156402Y167827D01*
Y167626D01*
G03X156941Y167251I400J0D01*
G02X157499Y167352I558J-1491D01*
G01X158899D01*
G02X160500Y165750I-1J-1602D01*
G01Y165048D01*
X161446D01*
Y166049D01*
X170801D01*
G03X171201Y166429I0J400D01*
G02X174619Y168327I2299J-114D01*
G01X174664Y168302D01*
X175949D01*
G02X177506Y167657I0J-2202D01*
G01X177849Y167314D01*
X177901Y167300D01*
G02X178499Y167001I-401J-1550D01*
G02X179499Y167352I1001J-1251D01*
G01X180899D01*
G02X182500Y165750I-1J-1602D01*
G01Y164350D01*
G02Y164311I-1601J-19D01*
G03X182900Y163902I400J-9D01*
G01X189500D01*
Y162602D01*
X197568D01*
X199006Y164039D01*
X198990Y164139D01*
G02X202336Y162057I2571J402D01*
G03X202261Y161325I119J-382D01*
G02X199278Y157099I-1261J-2276D01*
G01X199221Y157148D01*
X197000D01*
Y154624D01*
X194950D01*
Y153519D01*
X193992Y152561D01*
X194010Y152458D01*
G02X193957Y151308I-2561J-458D01*
G03X194343Y150802I386J-106D01*
G01X210768D01*
X217098Y157131D01*
Y180855D01*
X217012Y180915D01*
G02Y185185I1487J2135D01*
G01X217098Y185245D01*
Y188721D01*
X217026Y188781D01*
G02X219972I1473J1769D01*
G01X219900Y188721D01*
Y185245D01*
X219986Y185185D01*
G02Y180915I-1487J-2135D01*
G01X219900Y180855D01*
Y155969D01*
X211930Y147998D01*
X184068D01*
X182364Y149703D01*
X182296Y149711D01*
G02X180898Y151300I204J1589D01*
G37*
G36*
G01X336365Y37252D02*
X350501D01*
X352047Y38797D01*
Y39002D01*
X352252D01*
X353001Y39752D01*
X361997D01*
X364200Y37548D01*
Y18552D01*
X361997Y16348D01*
X320652D01*
X318603Y18398D01*
X318448D01*
Y18553D01*
X318398Y18602D01*
Y25198D01*
X318448Y25247D01*
Y25898D01*
X310499D01*
Y25050D01*
X288999D01*
X288150Y25898D01*
X287202D01*
X285898Y27202D01*
Y28150D01*
X282499Y31550D01*
Y34851D01*
X282298Y35052D01*
Y46548D01*
X286501Y50752D01*
X296997D01*
X297198Y50550D01*
X310499D01*
Y50314D01*
X317200D01*
Y50252D01*
X325501D01*
X326798Y51548D01*
Y54048D01*
X327898Y55148D01*
Y57002D01*
X329751D01*
X330501Y57752D01*
X350997D01*
X352700Y56048D01*
Y43552D01*
X350497Y41348D01*
X339497D01*
X336082Y37934D01*
G03X336365Y37252I283J-282D01*
G37*
G36*
G01X352068Y1582709D02*
G02X351080Y1584795I-2294J191D01*
G03X351706Y1585091I227J329D01*
G02X352694Y1583005I2294J-191D01*
G03X352068Y1582709I-227J-329D01*
G37*
G36*
G01X820674Y1872194D02*
X820698Y1872238D01*
Y1873436D01*
X820656Y1873490D01*
G02Y1876710I2044J1610D01*
G01X820698Y1876764D01*
Y1880438D01*
X819498D01*
Y1883598D01*
X818502D01*
Y1880438D01*
X812037D01*
X811993Y1880414D01*
G02X809493Y1884262I-1093J2026D01*
G03X809295Y1884976I-244J317D01*
G02X807990Y1885516I305J2584D01*
G01X807936Y1885558D01*
X807038D01*
X806994Y1885534D01*
G02Y1889586I-1094J2026D01*
G01X807038Y1889562D01*
X807936D01*
X807990Y1889604D01*
G02X811210I1610J-2044D01*
G01X811264Y1889562D01*
X818142D01*
G03X818425Y1890245I0J400D01*
G01X815871Y1892798D01*
X760861D01*
X760532Y1892469D01*
X760518Y1892444D01*
G02X757393Y1895569I-2019J1106D01*
G01X757418Y1895583D01*
X759037Y1897202D01*
X788215D01*
G03X788520Y1897861I0J400D01*
G02X788364Y1898063I1979J1689D01*
G01X788304Y1898148D01*
X764481D01*
X747418Y1915212D01*
X747355D01*
X738598Y1923969D01*
Y1953631D01*
X753418Y1968452D01*
X765308D01*
X766245Y1967514D01*
X767314D01*
G02X767402Y1967512I8J-1601D01*
G01X767612D01*
Y1976211D01*
X770316Y1978914D01*
X784812D01*
X787016Y1976711D01*
Y1958215D01*
X784812Y1956012D01*
X781266D01*
Y1952261D01*
X781150D01*
Y1951169D01*
X781245Y1951110D01*
G02X782000Y1949750I-847J-1360D01*
G01Y1948350D01*
G02X780399Y1946748I-1601J-1D01*
G01X778999D01*
G02X777999Y1947099I1J1602D01*
G02X777624Y1946875I-1001J1250D01*
G01X777502Y1946824D01*
Y1946395D01*
X777587Y1946335D01*
G02X776212Y1941600I-1487J-2135D01*
G01X776141Y1941217D01*
G02X776499Y1941001I-641J-1467D01*
G02X777499Y1941352I1001J-1251D01*
G01X778899D01*
G02X779425Y1941263I-1J-1602D01*
G01X779457Y1941252D01*
X779497D01*
X779523Y1941226D01*
X779556Y1941210D01*
G02X780359Y1940407I-657J-1460D01*
G01X780375Y1940374D01*
X780700Y1940048D01*
Y1938973D01*
G03X781382Y1938688I400J-1D01*
G02X783678Y1939249I1617J-1638D01*
G01X783707Y1939241D01*
X783938D01*
Y1939402D01*
X786497D01*
Y1945902D01*
X787098D01*
Y1949131D01*
X788418Y1950452D01*
X790670D01*
X790730Y1950523D01*
G02X792131Y1951322I1769J-1473D01*
G03X792350Y1952000I-64J395D01*
G01X791298Y1953052D01*
Y1973048D01*
X794001Y1975752D01*
X833948D01*
X836102Y1973598D01*
Y1961902D01*
X836052Y1961853D01*
Y1959752D01*
X866497D01*
X872497Y1953752D01*
X883497D01*
X883761Y1953487D01*
X884839D01*
Y1952409D01*
X885200Y1952048D01*
Y1944552D01*
X884839Y1944191D01*
Y1942409D01*
X885200Y1942048D01*
Y1939552D01*
X884839Y1939191D01*
Y1938483D01*
X884131D01*
X883997Y1938348D01*
X867997D01*
X865282Y1935634D01*
G03X865565Y1934952I283J-282D01*
G01X866580D01*
X869145Y1932386D01*
X873036D01*
Y1933486D01*
X884838D01*
Y1928484D01*
X873036D01*
Y1929584D01*
X867983D01*
X865418Y1932148D01*
X821080D01*
X817431Y1928500D01*
G03X817714Y1927817I283J-283D01*
G01X825888D01*
Y1925252D01*
X827042D01*
Y1925564D01*
X833944D01*
Y1924804D01*
X834700Y1924048D01*
Y1915165D01*
G03X835383Y1914882I400J0D01*
G01X837612Y1917111D01*
Y1924611D01*
X838204Y1925202D01*
Y1925564D01*
X838566D01*
X839316Y1926314D01*
X869312D01*
X871312Y1924314D01*
X884812D01*
X886516Y1922611D01*
Y1914615D01*
X885513Y1913613D01*
X886516Y1912611D01*
Y1909615D01*
X884812Y1907912D01*
X871312D01*
X865197Y1901797D01*
G03X865480Y1901114I283J-283D01*
G01X866659D01*
X867931Y1902386D01*
X873036D01*
Y1903486D01*
X884838D01*
Y1898484D01*
X873036D01*
Y1899584D01*
X869093D01*
X867821Y1898312D01*
X861716D01*
Y1897613D01*
G02X860114Y1896012I-1602J1D01*
G01X858514D01*
G02X858022Y1896089I-1J1601D01*
G03X857543Y1895889I-122J-381D01*
G02X857174Y1895413I-1428J726D01*
G03Y1894813I265J-300D01*
G02X857716Y1893613I-1060J-1201D01*
G01Y1891013D01*
G02X856867Y1889600I-1602J1D01*
G03X856757Y1888981I189J-353D01*
G02X856573Y1885332I-1943J-1731D01*
G03X856557Y1885054I135J-147D01*
G02X853071I-1743J-1504D01*
G03X853055Y1885332I-151J131D01*
G02X852363Y1886377I1760J1917D01*
G03X851695Y1886517I-377J-134D01*
G02X849541Y1885711I-1895J1783D01*
G03X849102Y1885313I-39J-398D01*
G01Y1884095D01*
X849187Y1884035D01*
G02X846213I-1487J-2135D01*
G01X846298Y1884095D01*
Y1884319D01*
X841769Y1888848D01*
X840674D01*
G02X838672Y1890850I0J2002D01*
G01Y1893750D01*
G02X838772Y1894374I2002J-1D01*
G03X838392Y1894898I-380J124D01*
G01X820398D01*
X819915Y1894416D01*
X824769Y1889562D01*
X825902D01*
Y1887135D01*
G03X826501Y1886788I400J0D01*
G02X827300Y1887002I800J-1388D01*
G01X828700D01*
G02X830060Y1886246I0J-1601D01*
G01X830119Y1886152D01*
X834791D01*
X834800Y1886342D01*
G02X836799Y1888252I1999J-91D01*
G01X838199D01*
G02X840200Y1886250I-1J-2002D01*
G01Y1883350D01*
G02X839019Y1881524I-2002J0D01*
G01X838900Y1881471D01*
Y1879095D01*
X838986Y1879035D01*
G02X836012I-1487J-2135D01*
G01X836098Y1879095D01*
Y1881471D01*
X835979Y1881524D01*
G02X834806Y1883167I820J1826D01*
G01X834789Y1883348D01*
X830168D01*
X830111Y1883243D01*
G02X829951Y1883000I-1412J756D01*
G02X830296Y1882134I-1251J-1000D01*
G01X830302Y1882061D01*
X830702Y1881662D01*
Y1878473D01*
X830710Y1878446D01*
G02X826290I-2210J-646D01*
G01X826298Y1878473D01*
Y1879347D01*
X826232Y1879407D01*
G02X825731Y1880278I1068J1194D01*
G01X825698Y1880438D01*
X824702D01*
Y1876764D01*
X824744Y1876710D01*
G02Y1873490I-2044J-1610D01*
G01X824702Y1873436D01*
Y1872238D01*
X824726Y1872194D01*
G02X820674I-2026J-1094D01*
G37*
G36*
G01X736147Y1795660D02*
G03X735855Y1796332I-293J272D01*
G01X735649D01*
G02X735123Y1796421I1J1602D01*
G01X735091Y1796432D01*
X733822D01*
X733795Y1796424D01*
G02X731360Y1800082I-646J2210D01*
G03X731249Y1800680I-311J252D01*
G02X730790Y1804852I1300J2254D01*
G03X730806Y1805130I-135J147D01*
G02X733195Y1808844I1743J1504D01*
G01X733222Y1808836D01*
X735091D01*
X735123Y1808847D01*
G02X735649Y1808936I527J-1513D01*
G01X737049D01*
G02X738049Y1808585I-1J-1602D01*
G02X739049Y1808936I1001J-1251D01*
G01X740449D01*
G02X741722Y1808306I0J-1601D01*
G03X742302Y1808246I318J242D01*
G02X743349Y1808636I1048J-1212D01*
G01X744749D01*
G02X746092Y1807907I0J-1602D01*
G01X746151Y1807816D01*
X749747D01*
Y1809454D01*
X747968Y1811232D01*
X744718D01*
X744418Y1811532D01*
X743349D01*
G02X742076Y1812162I0J1601D01*
G03X741496Y1812222I-318J-242D01*
G02X740449Y1811832I-1048J1212D01*
G01X739049D01*
G02X738049Y1812183I1J1602D01*
G02X737049Y1811832I-1001J1251D01*
G01X735649D01*
G02X735123Y1811921I1J1602D01*
G01X735091Y1811932D01*
X733722D01*
X733695Y1811924D01*
G02Y1816344I-646J2210D01*
G01X733722Y1816336D01*
X735091D01*
X735123Y1816347D01*
G02X735649Y1816436I527J-1513D01*
G01X737049D01*
G02X738049Y1816085I-1J-1602D01*
G02X738292Y1816245I999J-1252D01*
G01X738398Y1816302D01*
Y1817215D01*
X739006Y1817823D01*
X738988Y1817926D01*
G02X744143Y1818590I2561J459D01*
G01X744149Y1818516D01*
X745450Y1817215D01*
Y1815978D01*
X745550Y1815921D01*
G02X746350Y1814534I-802J-1387D01*
G01Y1814036D01*
X749130D01*
X752289Y1810876D01*
X758151D01*
Y1801952D01*
X749450D01*
Y1799553D01*
X747380Y1797482D01*
X746217D01*
X746160Y1797377D01*
G02X744749Y1796532I-1412J757D01*
G01X743680D01*
X740619Y1793472D01*
X740608Y1793411D01*
G02X736147Y1795660I-2559J473D01*
G37*
G36*
G01X868870Y1691641D02*
X868898Y1691688D01*
Y1693012D01*
X873798Y1697912D01*
Y1700698D01*
X873648D01*
Y1701698D01*
X872289D01*
X869343Y1704643D01*
X868500Y1703800D01*
X841600D01*
X836500Y1708900D01*
Y1719098D01*
X831802D01*
X829698Y1721202D01*
Y1729998D01*
X821802D01*
X819998Y1731802D01*
Y1756202D01*
X815202Y1760998D01*
X753302D01*
X749298Y1765003D01*
Y1780048D01*
X752001Y1782752D01*
X798966D01*
X800874Y1784660D01*
Y1801795D01*
G03X800475Y1802195I-400J0D01*
G02X800192Y1802312I0J400D01*
G01X798315Y1804190D01*
G03X797709Y1804143I-283J-283D01*
G02X797322Y1803731I-1859J1358D01*
G01X797250Y1803671D01*
Y1803080D01*
X794153Y1799982D01*
X791560D01*
X791545Y1799799D01*
G02X789949Y1798332I-1596J135D01*
G01X788549D01*
G02X787549Y1798683I1J1602D01*
G02X787306Y1798523I-999J1252D01*
G01X787200Y1798466D01*
Y1797829D01*
X787286Y1797769D01*
G02X784312I-1487J-2135D01*
G01X784398Y1797829D01*
Y1798515D01*
X784303Y1798574D01*
G02X783562Y1799719I846J1360D01*
G01X783539Y1799892D01*
X780351D01*
Y1799392D01*
X771947D01*
Y1805012D01*
X770688D01*
X767148Y1808553D01*
Y1814439D01*
X767062Y1814499D01*
G02X769516Y1819050I1487J2135D01*
G01X769551Y1819036D01*
X772205D01*
X772262Y1819135D01*
G02X773649Y1819936I1387J-800D01*
G01X775049D01*
G02X776650Y1818334I-1J-1602D01*
G01Y1816934D01*
G02X775049Y1815332I-1601J-1D01*
G01X773649D01*
G02X772262Y1816133I0J1601D01*
G01X772205Y1816232D01*
X771125D01*
X771090Y1816075D01*
G02X770036Y1814499I-2541J559D01*
G01X769950Y1814439D01*
Y1809715D01*
X771264Y1808401D01*
G03X771947Y1808684I283J283D01*
G01Y1810876D01*
X773948D01*
Y1811546D01*
X778237Y1815836D01*
X780305D01*
X780362Y1815935D01*
G02X781749Y1816736I1387J-800D01*
G01X782255D01*
X782278Y1816741D01*
G02X783049Y1816836I774J-3107D01*
G01X800641D01*
X807278Y1810199D01*
Y1782752D01*
X812700D01*
Y1782962D01*
G02X812698Y1783050I1599J80D01*
G01Y1784450D01*
G02X814299Y1786052I1601J1D01*
G01X814711D01*
G03X815068Y1786631I0J400D01*
G02X814898Y1787350I1431J718D01*
G01Y1788750D01*
G02X815742Y1790161I1601J0D01*
G01X815848Y1790218D01*
Y1790855D01*
X815762Y1790915D01*
G02Y1795185I1487J2135D01*
G01X815848Y1795245D01*
Y1797380D01*
X817833Y1799367D01*
X818864Y1800398D01*
X823431D01*
Y1803199D01*
X834915D01*
Y1794795D01*
X834914D01*
Y1793375D01*
X838150Y1790138D01*
Y1789966D01*
X838200Y1789909D01*
G02X838600Y1788850I-1202J-1059D01*
G01Y1787785D01*
X839700Y1786685D01*
Y1781899D01*
X840702Y1780898D01*
Y1773802D01*
X833902Y1767002D01*
Y1739566D01*
G03X834584Y1739283I400J0D01*
G01X834702Y1739402D01*
X862088D01*
X866288Y1743602D01*
X891712D01*
X901702Y1733612D01*
Y1722088D01*
X901730Y1722041D01*
G02Y1719359I-2230J-1341D01*
G01X901702Y1719312D01*
Y1718388D01*
X899102Y1715788D01*
Y1714900D01*
G02X898124Y1713425I-1601J0D01*
G01X898002Y1713373D01*
Y1710088D01*
X897702Y1709788D01*
Y1708500D01*
G02X897210Y1707346I-1602J1D01*
G01X897149Y1707287D01*
Y1707002D01*
X897398D01*
X898502Y1705898D01*
Y1691902D01*
X896598Y1689998D01*
X882402D01*
X881098Y1691302D01*
Y1705598D01*
X881148Y1705648D01*
Y1707100D01*
X885852D01*
Y1707002D01*
X887409D01*
Y1707213D01*
X887408Y1707224D01*
G02X887398Y1707400I1592J179D01*
G01Y1708800D01*
G02X887576Y1709533I1602J-1D01*
G01X887598Y1709576D01*
Y1710827D01*
X887590Y1710854D01*
G02Y1712146I2210J646D01*
G01X887598Y1712173D01*
Y1712718D01*
G03X886916Y1713001I-400J0D01*
G01X886212Y1712298D01*
X885852D01*
Y1711297D01*
X881396D01*
X881098Y1710998D01*
X878102D01*
X877804Y1711297D01*
X877696D01*
X877198Y1710798D01*
X872602D01*
Y1709050D01*
G02X872425Y1708317I-1601J-1D01*
G01X872402Y1708274D01*
Y1707811D01*
X873307Y1706906D01*
G03X873648Y1707048I141J142D01*
G01Y1707100D01*
X878352D01*
Y1700698D01*
X878202D01*
Y1696088D01*
X873478Y1691364D01*
X873525Y1691243D01*
G02X868870Y1691641I-2425J-943D01*
G37*
G36*
G01X218098Y1496450D02*
Y1499050D01*
G02X218639Y1500250I1601J0D01*
G03Y1500850I-265J300D01*
G02X218196Y1501498I1060J1200D01*
G02X217799Y1501448I-397J1551D01*
G01X216199D01*
G02X214788Y1502293I1J1602D01*
G01X214731Y1502398D01*
X213955D01*
X213895Y1502328D01*
G02X210789Y1501669I-1981J1687D01*
G01X210661Y1501730D01*
X202990Y1494058D01*
X156492D01*
Y1492972D01*
X144690D01*
Y1497974D01*
X156492D01*
Y1496862D01*
X201828D01*
X209335Y1504368D01*
X209346Y1504432D01*
G02X209972Y1505746I2568J-417D01*
G03X209673Y1506412I-299J266D01*
G01X200496D01*
X196496Y1502412D01*
X145000D01*
X143796Y1503616D01*
Y1507112D01*
X144549Y1507864D01*
X143796Y1508616D01*
Y1517612D01*
X145000Y1518816D01*
X176500D01*
X190000Y1532316D01*
X236496D01*
X238211Y1530600D01*
X239798D01*
Y1531048D01*
X241001Y1532252D01*
X256118D01*
G03X256475Y1532831I0J400D01*
G02X261325Y1534629I2325J1168D01*
G01X261338Y1534575D01*
X262402Y1533512D01*
Y1530798D01*
X262702Y1530498D01*
Y1530100D01*
X264298D01*
Y1530548D01*
X266501Y1532752D01*
X280497D01*
X282700Y1530548D01*
Y1507052D01*
X281832Y1506184D01*
G03X282115Y1505501I283J-283D01*
G01X316587D01*
X323298Y1512212D01*
Y1534348D01*
X284501D01*
X280742Y1538108D01*
G03X280400Y1537967I-142J-141D01*
G01Y1537582D01*
X296402Y1521581D01*
Y1514829D01*
X296473Y1514769D01*
G02X293527I-1473J-1769D01*
G01X293598Y1514829D01*
Y1520419D01*
X277598Y1536420D01*
Y1541198D01*
X276938D01*
Y1548402D01*
X279497D01*
Y1553798D01*
X279353Y1553840D01*
G02X277706Y1556259I646J2210D01*
G01X277715Y1556352D01*
X277098Y1556969D01*
Y1557206D01*
X276998Y1557263D01*
G02X276198Y1558650I802J1387D01*
G01Y1560050D01*
G02X276548Y1561050I1601J1D01*
G02X276198Y1562050I1251J999D01*
G01Y1563450D01*
G02X276737Y1564649I1601J1D01*
G03X276472Y1565348I-265J299D01*
G01X275698D01*
X274548Y1564198D01*
X273515D01*
G03X273232Y1563516I0J-400D01*
G01X274700Y1562048D01*
Y1541552D01*
X270647Y1537498D01*
X251202D01*
X249288Y1539412D01*
X241200D01*
Y1539348D01*
X234298D01*
Y1539412D01*
X226500D01*
X224498Y1541415D01*
X222700Y1539617D01*
Y1539348D01*
X215798D01*
Y1539412D01*
X189996D01*
X182996Y1532412D01*
X145500D01*
X144942Y1532971D01*
X144689D01*
Y1533224D01*
X143796Y1534116D01*
Y1536612D01*
X144689Y1537504D01*
Y1538224D01*
X143796Y1539116D01*
Y1551612D01*
X145500Y1553316D01*
X154715D01*
G03X154971Y1554023I0J400D01*
G02X162798Y1556659I3100J3733D01*
G03X163470Y1556285I390J-91D01*
G01X172000Y1564816D01*
X241703D01*
G03X241844Y1565157I-1J200D01*
G01X241698Y1565302D01*
Y1583298D01*
X247652Y1589252D01*
X283497D01*
X285002Y1587745D01*
Y1566353D01*
X284332Y1565684D01*
G03X284615Y1565001I283J-283D01*
G01X286661D01*
X289000Y1562662D01*
Y1548752D01*
X291001D01*
X294501Y1552252D01*
X300996D01*
G03X301316Y1552891I0J400D01*
G02X300998Y1553850I1283J958D01*
G01Y1555250D01*
G02X301381Y1556290I1601J1D01*
G03Y1556810I-304J260D01*
G02X300998Y1557850I1218J1039D01*
G01Y1559250D01*
G02X301381Y1560290I1601J1D01*
G03Y1560810I-304J260D01*
G02X300998Y1561850I1218J1039D01*
G01Y1563250D01*
G02X301356Y1564260I1601J1D01*
G03X301046Y1564912I-310J252D01*
G01X289500D01*
X287296Y1567116D01*
Y1579612D01*
X289000Y1581316D01*
X295547D01*
Y1586002D01*
X304451D01*
Y1584952D01*
X305736D01*
X305796Y1585019D01*
G02X310310Y1582842I1953J-1719D01*
G01X310292Y1582739D01*
X311650Y1581381D01*
Y1579169D01*
X311745Y1579110D01*
G02X312286Y1578551I-846J-1360D01*
G01X312343Y1578452D01*
X313937D01*
Y1580333D01*
X313800Y1580379D01*
G02X312698Y1581900I499J1521D01*
G01Y1583300D01*
G02X314300Y1584902I1602J0D01*
G01X315700D01*
G02X316700Y1584551I-1J-1602D01*
G02X317700Y1584902I1001J-1251D01*
G01X319100D01*
G02X320487Y1584101I0J-1601D01*
G01X320544Y1584002D01*
X326905D01*
X326965Y1584087D01*
G02Y1581113I2135J-1487D01*
G01X326905Y1581198D01*
X320544D01*
X320487Y1581099D01*
G02X320255Y1580791I-1386J803D01*
G01X320199Y1580732D01*
Y1580452D01*
X320501D01*
Y1574892D01*
X321240D01*
X322460Y1573671D01*
Y1573052D01*
X323061D01*
Y1567502D01*
X326405D01*
X326465Y1567587D01*
G02X330354Y1564178I2135J-1487D01*
G03X330576Y1563485I269J-296D01*
G02X332388Y1560230I-276J-2285D01*
G03X332580Y1559699I363J-169D01*
G02X333500Y1558250I-681J-1449D01*
G01Y1556850D01*
G02X333456Y1556475I-1601J-2D01*
G01X333450Y1556452D01*
Y1554648D01*
X333456Y1554625D01*
G02X333500Y1554250I-1557J-373D01*
G01Y1552850D01*
G02X333456Y1552475I-1601J-2D01*
G01X333450Y1552452D01*
Y1550752D01*
X361997D01*
X403497Y1509252D01*
X566997D01*
X570200Y1506048D01*
Y1486052D01*
X564497Y1480348D01*
X398001D01*
X344001Y1534348D01*
X327700D01*
Y1510388D01*
X318411Y1501098D01*
X277135D01*
G03X277009Y1500319I1J-400D01*
G02X266305I-5352J-16085D01*
G03X266188Y1501098I-127J379D01*
G01X264192Y1503095D01*
G03X263521Y1502910I-283J-283D01*
G02X258479Y1504199I-2522J640D01*
G03X258092Y1504698I-387J99D01*
G01X254412D01*
X253002Y1503288D01*
Y1494271D01*
X246000Y1487269D01*
Y1466052D01*
X282118D01*
X293418Y1477352D01*
X341504D01*
X341564Y1477437D01*
G02X345834I2135J-1487D01*
G01X345894Y1477352D01*
X400247D01*
X400289Y1477495D01*
G02X402290Y1474557I2210J-645D01*
G01X402197Y1474566D01*
X402180Y1474548D01*
X345894D01*
X345834Y1474463D01*
G02X341564I-2135J1487D01*
G01X341504Y1474548D01*
X294580D01*
X283280Y1463248D01*
X229268D01*
X219298Y1473218D01*
Y1485149D01*
X218798Y1485649D01*
Y1488551D01*
X219598Y1489350D01*
Y1494843D01*
X219431Y1494871D01*
G02X218098Y1496450I269J1579D01*
G37*
G36*
G01X833477Y1069993D02*
X833598Y1070044D01*
Y1072421D01*
X833480Y1072474D01*
G02X832303Y1074162I820J1826D01*
G01X832290Y1074348D01*
X827819D01*
X827760Y1074254D01*
G02X827585Y1074023I-1359J848D01*
G03X827579Y1073761I148J-134D01*
G02X826459Y1070094I-1779J-1461D01*
G01X826410Y1070080D01*
X824669Y1068338D01*
X817098D01*
Y1068400D01*
X816102D01*
Y1068338D01*
X808731D01*
X806390Y1070680D01*
X806341Y1070694D01*
G02X809206Y1073559I659J2206D01*
G01X809220Y1073510D01*
X809357Y1073374D01*
G03X809698Y1073515I141J142D01*
G01Y1077348D01*
X758172D01*
X758145Y1077340D01*
G02Y1081760I-646J2210D01*
G01X758172Y1081752D01*
X810711D01*
X811925Y1082966D01*
G03X811642Y1083648I-283J282D01*
G01X784194D01*
X784134Y1083563D01*
G02X779864I-2135J1487D01*
G01X779804Y1083648D01*
X760438D01*
X742098Y1101989D01*
Y1145631D01*
X754760Y1158294D01*
X764489D01*
X764546Y1158393D01*
G02X765933Y1159194I1387J-800D01*
G01X767333D01*
G02X767421Y1159191I-11J-1602D01*
G01X767632D01*
Y1166390D01*
X770335Y1169094D01*
X784831D01*
X787034Y1166890D01*
Y1148394D01*
X784831Y1146190D01*
X781285D01*
Y1141440D01*
X779352D01*
Y1140319D01*
X779446Y1140260D01*
G02X780202Y1138900I-845J-1360D01*
G01Y1137500D01*
G02X778600Y1135898I-1602J0D01*
G01X777200D01*
G02X776200Y1136249I1J1602D01*
G02X776089Y1136168I-999J1252D01*
G03X776029Y1135550I221J-333D01*
G02X774967Y1131214I-1829J-1850D01*
G03X774703Y1130716I119J-382D01*
G02X774801Y1130051I-2204J-665D01*
G01Y1129852D01*
X775999D01*
G02X776999Y1129501I-1J-1602D01*
G02X777210Y1129644I1001J-1250D01*
G03X777381Y1130148I-197J348D01*
G02X781792Y1130841I2118J902D01*
G01X781783Y1130748D01*
X783630Y1128902D01*
X784997D01*
Y1135402D01*
X785598D01*
Y1136131D01*
X787215Y1137748D01*
X787206Y1137841D01*
G02X791268Y1139523I2293J209D01*
G01X791328Y1139452D01*
X795330D01*
X795430Y1139352D01*
X796499D01*
G02X797499Y1139001I-1J-1602D01*
G02X798499Y1139352I1001J-1251D01*
G01X799899D01*
G02X801098Y1138812I0J-1601D01*
G03X801798Y1139077I300J265D01*
G01Y1140684D01*
G03X801115Y1140967I-400J0D01*
G01X800997Y1140848D01*
X792501D01*
X790298Y1143052D01*
Y1163548D01*
X793501Y1166752D01*
X832848D01*
X835002Y1164598D01*
Y1149402D01*
X834552Y1148953D01*
Y1148300D01*
X835100D01*
Y1146752D01*
X880497D01*
X884785Y1142463D01*
X884839D01*
Y1142409D01*
X885200Y1142048D01*
Y1134552D01*
X884839Y1134191D01*
Y1131909D01*
X885200Y1131548D01*
Y1128552D01*
X884839Y1128191D01*
Y1127459D01*
X884107D01*
X883997Y1127348D01*
X871997D01*
X868089Y1123441D01*
X870181Y1121350D01*
X873036D01*
Y1122462D01*
X884838D01*
Y1117460D01*
X873036D01*
Y1118546D01*
X869021D01*
X866868Y1120698D01*
X834179D01*
X833479Y1121398D01*
X827519D01*
X827319Y1121198D01*
X820080D01*
X818232Y1119351D01*
G03X818515Y1118668I283J-283D01*
G01X825293D01*
Y1114844D01*
X832464D01*
Y1113285D01*
X832700Y1113048D01*
Y1105165D01*
G03X833383Y1104882I400J0D01*
G01X835632Y1107131D01*
Y1113890D01*
X837335Y1115594D01*
X867331D01*
X869331Y1113594D01*
X882831D01*
X883961Y1112463D01*
X884839D01*
Y1097459D01*
X883099D01*
X882831Y1097190D01*
X869331D01*
X862274Y1090134D01*
G03X862557Y1089452I283J-282D01*
G01X863918D01*
X865816Y1091350D01*
X873036D01*
Y1092462D01*
X884838D01*
Y1087460D01*
X873036D01*
Y1088546D01*
X866978D01*
X865080Y1086648D01*
X859224D01*
X859185Y1086498D01*
G02X857633Y1085290I-1552J393D01*
G01X856033D01*
G02X855541Y1085368I2J1602D01*
G03X855062Y1085168I-122J-381D01*
G02X854693Y1084692I-1428J726D01*
G03Y1084092I265J-300D01*
G02X855234Y1082892I-1060J-1200D01*
G01Y1080292D01*
G02X854493Y1078941I-1602J0D01*
G03X854420Y1078688I108J-168D01*
G02X853776Y1075923I-2087J-971D01*
G01X853702Y1075862D01*
Y1074836D01*
X853737Y1074784D01*
G02X849336Y1072017I-2137J-1484D01*
G03X848657Y1072044I-348J-197D01*
G02X844041Y1072648I-2157J1456D01*
G01X844026Y1072692D01*
X842648Y1074069D01*
Y1081081D01*
X842554Y1081140D01*
G02X842013Y1081699I846J1360D01*
G01X841956Y1081798D01*
X841585D01*
X841568Y1081617D01*
G02X839575Y1079798I-1993J182D01*
G01X838175D01*
G02X836174Y1081800I1J2002D01*
G01Y1084700D01*
G02X836175Y1084775I2001J11D01*
G03X835775Y1085190I-400J15D01*
G01X827808D01*
G03X827496Y1084540I0J-400D01*
G02X827910Y1082454I-1796J-1440D01*
G01X827902Y1082427D01*
Y1080458D01*
X827913Y1080426D01*
G02X828002Y1079900I-1513J-527D01*
G01Y1078500D01*
G02X827651Y1077500I-1602J1D01*
G02X827811Y1077257I-1252J-999D01*
G01X827868Y1077152D01*
X832290D01*
X832303Y1077338D01*
G02X834300Y1079202I1997J-138D01*
G01X835700D01*
G02X837702Y1077200I0J-2002D01*
G01Y1074300D01*
G02X836520Y1072474I-2001J0D01*
G01X836402Y1072421D01*
Y1069378D01*
X836451Y1069321D01*
G02X833477Y1069993I-1952J-1721D01*
G37*
G36*
G01X275847Y284125D02*
G02X267467I-4190J-16426D01*
G03X267368Y284912I-100J387D01*
G01X252703D01*
G03X252362Y284303I0J-400D01*
G02X251059Y280894I-1962J-1203D01*
G01X251010Y280880D01*
X250629Y280498D01*
X249162D01*
Y279298D01*
X246002D01*
Y278302D01*
X249162D01*
Y277699D01*
G03X249671Y277314I400J0D01*
G02Y272886I629J-2214D01*
G03X249162Y272501I-109J-385D01*
G01Y271558D01*
X249237Y271498D01*
G02X247154Y267490I-1437J-1798D01*
G01X247127Y267498D01*
X245258D01*
X245226Y267487D01*
G02X244700Y267398I-527J1513D01*
G01X243300D01*
G02X242300Y267749I1J1602D01*
G02X241300Y267398I-1001J1251D01*
G01X239900D01*
G02X238748Y267887I0J1601D01*
G01X238689Y267948D01*
X234210D01*
X234197Y267762D01*
G02X232929Y266036I-1997J138D01*
G01X232802Y265986D01*
Y264995D01*
X232887Y264935D01*
G02X229913I-1487J-2135D01*
G01X229998Y264995D01*
Y266062D01*
X229889Y266118D01*
G02X228798Y267900I910J1782D01*
G01Y270800D01*
G02X230800Y272802I2002J0D01*
G01X232200D01*
G02X234197Y270938I0J-2002D01*
G01X234210Y270752D01*
X238331D01*
X238375Y270890D01*
G02X239845Y272001I1525J-490D01*
G03X240038Y272200I-7J200D01*
G01Y275331D01*
X238990Y276380D01*
X238941Y276394D01*
G02X238643Y276506I659J2206D01*
G03X238076Y276143I-167J-364D01*
G01Y275400D01*
G02X236075Y273398I-2001J-1D01*
G01X234675D01*
G02X232674Y275400I1J2002D01*
G01Y278300D01*
G02X233219Y279674I2001J1D01*
G01X233353Y279815D01*
X232742Y280426D01*
X227499D01*
X227450Y280297D01*
G02X226771Y279345I-2152J817D01*
G01X226700Y279285D01*
Y276968D01*
X224480Y274748D01*
X223994D01*
X223934Y274663D01*
G02X219305Y275407I-2135J1487D01*
G01X219263Y275550D01*
X143499D01*
X142499Y276550D01*
Y337550D01*
X143499Y338550D01*
X153334D01*
G03X153695Y339123I0J400D01*
G02X162815Y342239I4376J2097D01*
G03X163489Y342040I391J84D01*
G01X170091Y348642D01*
X169885Y348849D01*
X169793Y348842D01*
G02X169473Y348830I-317J4189D01*
G01X165173D01*
G02Y357232I0J4201D01*
G01X169473D01*
G02X171414Y349305I0J-4201D01*
G03X171599Y348550I185J-355D01*
G01X241568D01*
G03X241709Y348891I0J200D01*
G01X241698Y348902D01*
Y361949D01*
X247999Y368249D01*
Y370550D01*
X250499Y373050D01*
X280999D01*
X281298Y372752D01*
X281497D01*
X284198Y370050D01*
X306999D01*
X310499Y366550D01*
Y364282D01*
X311650Y363131D01*
Y362169D01*
X311745Y362110D01*
G02X312286Y361551I-846J-1360D01*
G01X312343Y361452D01*
X313937D01*
Y362933D01*
X313800Y362979D01*
G02X312698Y364500I499J1521D01*
G01Y365900D01*
G02X312965Y366785I1602J0D01*
G01X312998Y366835D01*
Y367905D01*
X312913Y367965D01*
G02X315887I1487J2135D01*
G01X315802Y367905D01*
Y367507D01*
X315968Y367479D01*
G02X316700Y367151I-268J-1579D01*
G02X317700Y367502I1001J-1251D01*
G01X318419D01*
X319657Y368739D01*
X319639Y368842D01*
G02X321742Y366739I2561J458D01*
G01X321639Y366757D01*
X320702Y365819D01*
Y364500D01*
G02X320162Y363302I-1601J1D01*
G01X320095Y363242D01*
Y362952D01*
X320501D01*
Y357530D01*
X322479Y355552D01*
X323061D01*
Y349148D01*
X319900D01*
Y348780D01*
X320029Y348731D01*
G02X318681Y343732I-927J-2431D01*
G01X318580Y343749D01*
X316650Y341818D01*
Y341176D01*
X318850D01*
Y338616D01*
X324509D01*
X324568Y338707D01*
G02X328124Y339085I1931J-1253D01*
G02X329098Y339416I975J-1271D01*
G01X330498D01*
G02X331498Y339065I-1J-1602D01*
G02X332070Y339357I999J-1251D01*
G01X332121Y339371D01*
X333001Y340252D01*
X564497D01*
X567700Y337048D01*
Y322052D01*
X564497Y318848D01*
X329700D01*
Y303638D01*
X310975Y284912D01*
X275946D01*
G03X275847Y284125I1J-400D01*
G37*
G36*
G01X814200Y161752D02*
Y161962D01*
G02X814198Y162050I1599J80D01*
G01Y163450D01*
G02X814781Y164686I1602J0D01*
G03X814821Y165266I-255J309D01*
G02X814398Y166350I1177J1084D01*
G01Y167750D01*
G02X815242Y169161I1601J0D01*
G01X815348Y169218D01*
Y172381D01*
X815470Y172503D01*
X815452Y172606D01*
G02X818471Y175625I2561J458D01*
G01X818574Y175607D01*
X821304Y178338D01*
X823431D01*
Y180648D01*
X820194D01*
X820134Y180563D01*
G02Y183537I-2135J1487D01*
G01X820194Y183452D01*
X827080D01*
X828999Y181532D01*
X831418Y183952D01*
X838304D01*
X838364Y184037D01*
G02Y181063I2135J-1487D01*
G01X838304Y181148D01*
X834915D01*
Y172747D01*
X834714D01*
Y170992D01*
X835754Y169952D01*
X836499D01*
G02X838100Y168350I-1J-1602D01*
G01Y166750D01*
G02X837967Y166110I-1601J-1D01*
G01X837950Y166072D01*
Y161752D01*
X838497D01*
X841200Y159048D01*
Y153052D01*
X838997Y150848D01*
X753001D01*
X750798Y153052D01*
Y160048D01*
X752501Y161752D01*
X814200D01*
G37*
G36*
G01X896115Y35467D02*
X895997Y35348D01*
X839001D01*
X834798Y39552D01*
Y76548D01*
X836550Y78300D01*
X834298Y80552D01*
Y126548D01*
X838501Y130752D01*
X901200D01*
Y130962D01*
G02X901198Y131050I1599J80D01*
G01Y132450D01*
G02X902799Y134052I1601J1D01*
G01X904199D01*
G02X904574Y134007I-2J-1602D01*
G01X904597Y134002D01*
X906826D01*
X906853Y134010D01*
G02X907159Y129523I645J-2210D01*
G03X906700Y129128I-59J-396D01*
G01Y126952D01*
X908099D01*
G02X908832Y126774I-1J-1602D01*
G01X908875Y126752D01*
X910326D01*
X910353Y126760D01*
G02X913250Y125030I646J-2210D01*
G03X913924Y124831I391J84D01*
G01X919845Y130752D01*
X948204D01*
X960200Y118755D01*
Y110345D01*
X957540Y107684D01*
G03X957822Y107002I283J-282D01*
G01X960773D01*
X965744Y102031D01*
Y98021D01*
X965808Y97961D01*
G02Y94139I-1766J-1911D01*
G01X965744Y94079D01*
Y90888D01*
X962704Y87848D01*
X961156D01*
X961109Y87715D01*
G02X959599Y86648I-1510J535D01*
G01X956999D01*
G02X956280Y86819I1J1602D01*
G03X955700Y86462I-180J-357D01*
G01Y33552D01*
X951497Y29348D01*
X926501D01*
X924383Y31467D01*
G03X923701Y31184I-282J-283D01*
G01X923700Y17052D01*
X920497Y13848D01*
X900001D01*
X896798Y17052D01*
Y35184D01*
G03X896115Y35467I-400J0D01*
G37*
G54D105*
X68898Y422559D03*
Y190275D03*
Y17047D03*
Y1001299D03*
X895669Y1975079D03*
Y1801851D03*
Y1569567D03*
Y1396339D03*
Y1164055D03*
Y990827D03*
Y758543D03*
Y585315D03*
Y353031D03*
Y179803D03*
X167323Y1975079D03*
Y1569567D03*
Y1396339D03*
Y1164055D03*
Y758543D03*
Y585315D03*
Y179803D03*
X68898Y595787D03*
Y1639095D03*
G54D114*
X155999Y181050D03*
X161999Y768050D03*
X767159Y1792364D03*
X168499Y65550D03*
X191999Y68050D03*
G54D111*
X49799Y559150D03*
X90324Y1538800D03*
X99999Y1753575D03*
X141999Y1764550D03*
X164700Y1085400D03*
X329499Y801550D03*
X330540Y795509D03*
X320499Y798050D03*
X344520Y406329D03*
X345499Y1096550D03*
X345424Y1310050D03*
X347324Y1524000D03*
X354500Y1559500D03*
X353499Y1710450D03*
X371999Y549300D03*
X371500Y880600D03*
X364499Y1099050D03*
X370149Y1320050D03*
X366149Y1554050D03*
X377900Y1703800D03*
X400499Y406329D03*
X394649Y630600D03*
X385499Y1735050D03*
X967600Y1651100D03*
X971558Y1646500D03*
X74800Y1584700D03*
G54D108*
X78150Y28858D03*
Y178464D03*
Y434370D03*
Y989488D03*
X158071Y191614D03*
Y597126D03*
Y1152244D03*
Y1408150D03*
Y1963268D03*
X886417Y341220D03*
Y597126D03*
Y746732D03*
Y1002638D03*
Y1152244D03*
Y1408150D03*
Y1557756D03*
Y1813662D03*
Y1963268D03*
G54D112*
X41600Y407800D03*
X287399Y21613D03*
X290799D03*
X292299Y54613D03*
X295699D03*
X388300Y77000D03*
X390700D03*
X368100Y77100D03*
X370500D03*
X291799Y91113D03*
X812199Y165950D03*
X840499Y166350D03*
X812199Y168150D03*
X840499Y168750D03*
X863200Y346600D03*
X866600D03*
X211898Y352614D03*
X215298D03*
X193300Y504000D03*
X195700D03*
X183199Y526050D03*
X858396Y677382D03*
X861196Y748082D03*
X864596D03*
X212899Y759550D03*
X216299D03*
X858033Y1082892D03*
X853633Y1119392D03*
X857033D03*
X215900Y1129500D03*
X219300D03*
X861233Y1150892D03*
X864633D03*
X134900Y1181900D03*
X138300D03*
X102299Y1233550D03*
X105699D03*
X141467Y1311260D03*
X143867D03*
X131799Y1311613D03*
X134199D03*
X99449Y1477150D03*
X120049D03*
X121599Y1480550D03*
X123999D03*
X860027Y1487796D03*
X215799Y1499050D03*
X856127Y1524296D03*
X308099Y1531950D03*
X310499D03*
X216299Y1536550D03*
X219699D03*
X864000Y1554100D03*
X867400D03*
X295800Y1554600D03*
X298200D03*
X963700Y1658800D03*
Y1662200D03*
Y1663800D03*
Y1667200D03*
X876901Y1692150D03*
X122799Y1739613D03*
X125199D03*
X136304Y1740323D03*
X138704D03*
X840999Y1786850D03*
X812699Y1786950D03*
Y1789150D03*
X840999Y1789250D03*
X654349Y1791634D03*
X656749D03*
X638949Y1791834D03*
X745149Y1794334D03*
X705449Y1796834D03*
X694749Y1797134D03*
X645149Y1808434D03*
X702549Y1811934D03*
X692349Y1818134D03*
X694749D03*
X778849Y1818734D03*
X781349Y1821134D03*
X784749D03*
X786349D03*
X789749D03*
X860514Y1893613D03*
X312299Y1927050D03*
X314699D03*
X855614Y1930113D03*
X859014D03*
X862800Y1963900D03*
X866200D03*
X211900Y1964100D03*
X215300D03*
X48399Y1906350D03*
X50599D03*
X103800Y1637000D03*
X100400D03*
X56799Y1895950D03*
Y1898150D03*
X58499Y1900350D03*
X48299Y1964550D03*
X51699D03*
X112499Y1159800D03*
X123499D03*
X112499Y1164300D03*
X123499D03*
X134900Y1172900D03*
X102299Y1242550D03*
X105699D03*
X121999Y1249613D03*
X126499D03*
X121999Y1283113D03*
X106199Y1275113D03*
X102799D03*
X100400Y1646000D03*
X103800D03*
X122999Y1654113D03*
X127499D03*
X127999Y1687613D03*
X123499D03*
X107199Y1680613D03*
X103799D03*
X96399Y1091350D03*
X89500Y1096300D03*
Y1098700D03*
Y1110300D03*
Y1112700D03*
X101800Y1116500D03*
X117699Y1123950D03*
Y1126150D03*
X106199Y1266113D03*
X107199Y1671613D03*
X103799D03*
X177799Y70050D03*
X183699D03*
X173899Y70250D03*
X176099D03*
X178499Y100250D03*
X184399Y116250D03*
X161499Y469050D03*
X156999D03*
X136000Y462300D03*
X132600D03*
X117299Y1299213D03*
X141467Y1305260D03*
X143867D03*
X131799Y1305613D03*
X134199D03*
X122799Y1733613D03*
X125199D03*
X136304Y1734323D03*
X138704D03*
X140399Y439313D03*
X128500Y434800D03*
Y432400D03*
X133199Y428213D03*
Y426013D03*
Y424213D03*
Y422013D03*
X136000Y453300D03*
X132600D03*
X138499Y480050D03*
X141199Y487113D03*
X137799D03*
X157249Y502613D03*
X141199Y496113D03*
X137799D03*
X235999Y697550D03*
X240499D03*
X235999Y708550D03*
X216799Y717550D03*
X220199D03*
X216299Y750550D03*
X212899D03*
X239999Y742550D03*
X235499D03*
X240434Y1901187D03*
X235934Y1912187D03*
X240434D03*
X217114Y1918613D03*
X220514D03*
X215300Y1955100D03*
X211900D03*
X238934Y1948487D03*
X234434D03*
X165399Y807813D03*
X167599D03*
X169399D03*
X171599D03*
X158300Y823000D03*
X160700D03*
X166399Y832313D03*
X161299Y851113D03*
X164699D03*
X166499Y867613D03*
X161999D03*
X184999D03*
X180499D03*
X164699Y860113D03*
X161299D03*
X160799Y884613D03*
X164199D03*
X184999Y912113D03*
X180499D03*
Y901113D03*
X164199Y893613D03*
X160799D03*
X161999Y901113D03*
X235500Y1097600D03*
X240000D03*
X235500Y1108600D03*
X240000D03*
X215900Y1120500D03*
X219300D03*
X221500Y1108600D03*
X217000D03*
X220514Y1927613D03*
X217114D03*
X193300Y498000D03*
X195700D03*
X194249Y1629513D03*
Y1631713D03*
Y1634013D03*
Y1636213D03*
X217100Y895700D03*
X234999Y74850D03*
X217100Y901700D03*
X307799Y723550D03*
X310199D03*
X307799Y729550D03*
X310199D03*
X296800Y734500D03*
X299200D03*
X311299Y740950D03*
X306699Y761450D03*
Y763650D03*
Y765950D03*
X312299Y1933050D03*
X314699D03*
X295658Y1942828D03*
X298058D03*
X315021Y1943809D03*
X308977Y1961091D03*
Y1963291D03*
Y1965091D03*
Y1967291D03*
X778778Y303424D03*
X781178D03*
X763300Y303500D03*
X765700D03*
X755778Y322824D03*
X765700Y309500D03*
X763300D03*
X781178Y309424D03*
X778778D03*
X772778Y346824D03*
Y349024D03*
Y351324D03*
Y353524D03*
X860699Y313550D03*
X857299D03*
X866600Y337600D03*
X863200D03*
X843728Y329424D03*
X839228D03*
X860699Y304550D03*
X857299D03*
X840228Y295624D03*
Y284624D03*
X835728D03*
G54D116*
X180749Y70050D03*
G54D115*
X40999Y1919800D03*
G54D109*
X85630Y511653D03*
Y917165D03*
X878937Y1885985D03*
X150591Y263937D03*
X878937Y1480473D03*
Y1074961D03*
Y669449D03*
Y263937D03*
X150591Y1885985D03*
Y1480473D03*
Y669449D03*
G54D107*
X9843Y353144D03*
G54D113*
X1019291Y1416024D03*
G54D106*
X21499Y17050D03*
X1010999Y18550D03*
X1008999Y1968550D03*
G54D110*
X29531Y309549D03*
Y1029510D03*
X271657Y1889746D03*
X994098Y149588D03*
Y673210D03*
Y1068880D03*
X994093Y1889751D03*
%LPD*%
G75*
G36*
G01X73499Y710050D02*
X37499D01*
X32499Y715050D01*
Y739550D01*
X38499Y745550D01*
X82150D01*
X83400Y744300D01*
Y719951D01*
X73499Y710050D01*
G37*
G36*
G01X82050Y750550D02*
X45499D01*
X44499Y751550D01*
Y778550D01*
X47999Y782050D01*
X81150D01*
X84200Y779000D01*
Y752700D01*
X82050Y750550D01*
G37*
G36*
G01X81999Y849550D02*
X80999Y850550D01*
Y858550D01*
X81499Y859050D01*
X90300D01*
X91001Y858348D01*
X98497D01*
X98599Y858450D01*
X99499Y857550D01*
Y851050D01*
X97999Y849550D01*
X81999D01*
G37*
G36*
G01X91532Y859550D02*
Y859666D01*
X91382D01*
X89999Y861050D01*
X81499D01*
X80999Y861550D01*
Y862550D01*
X81999Y863550D01*
X91999D01*
X93499Y865050D01*
X97999D01*
X98999Y864050D01*
Y860550D01*
X98002Y859553D01*
X97923Y859551D01*
G03X97903Y859550I120J-2599D01*
G01X97899D01*
X91532D01*
G37*
G36*
G01X81499Y880050D02*
X80499Y881050D01*
Y889050D01*
X80999Y889550D01*
X89800D01*
X91001Y888348D01*
X98497D01*
X98599Y888450D01*
X98999Y888050D01*
Y881550D01*
X97499Y880050D01*
X81499D01*
G37*
G36*
G01X91532Y889550D02*
Y889666D01*
X91382D01*
X89999Y891050D01*
X81499D01*
X80999Y891550D01*
Y892550D01*
X81999Y893550D01*
X91999D01*
X93038Y894589D01*
X93137Y894575D01*
G03X94982Y895014I362J2577D01*
G01X95034Y895050D01*
X97999D01*
X98999Y894050D01*
Y890550D01*
X98367Y889918D01*
X98260Y889941D01*
G03X96283Y889582I-560J-2541D01*
G01X96233Y889550D01*
X94669D01*
X94634Y889564D01*
G03X92746I-944J-2425D01*
G01X92711Y889550D01*
X91532D01*
G37*
G36*
G01X199998Y291114D02*
X195998Y287114D01*
X145498D01*
X144998Y287614D01*
Y290114D01*
X145498Y290614D01*
X186498D01*
X198498Y302614D01*
X222998D01*
X223998Y301614D01*
Y292114D01*
X222998Y291114D01*
X199998D01*
G37*
G36*
G01X232600Y289400D02*
X230900Y291100D01*
Y291114D01*
X227498D01*
X225998Y292614D01*
Y302614D01*
X224498Y304114D01*
X197498D01*
X185498Y292114D01*
X145498D01*
X144998Y292614D01*
Y300614D01*
X145498Y301114D01*
X176998D01*
X190498Y314614D01*
X235998D01*
X236998Y313614D01*
Y305614D01*
X240498Y302114D01*
Y297700D01*
X241848Y296350D01*
Y295498D01*
X248702D01*
X248900Y295300D01*
Y290300D01*
X248000Y289400D01*
X232600D01*
G37*
G36*
G01X189498Y324114D02*
X182498Y317114D01*
X145998D01*
X144998Y318114D01*
Y319614D01*
X145998Y320614D01*
X169498D01*
X183998Y335114D01*
X221998D01*
X223498Y333614D01*
Y325614D01*
X221998Y324114D01*
X189498D01*
G37*
G36*
G01X258063Y320050D02*
X253999Y324114D01*
X226998D01*
X225498Y325614D01*
Y335114D01*
X223998Y336614D01*
X182498D01*
X167998Y322114D01*
X145998D01*
X144998Y323114D01*
Y334614D01*
X145998Y335614D01*
X160998D01*
X172498Y347114D01*
X241948D01*
Y344798D01*
X250852D01*
Y347114D01*
X271435D01*
X273499Y345050D01*
Y321550D01*
X271999Y320050D01*
X258063D01*
G37*
G36*
G01X247200Y1505400D02*
X227500D01*
X225998Y1506902D01*
Y1519114D01*
X224498Y1520614D01*
X197498D01*
X185498Y1508614D01*
X145498D01*
X144998Y1509114D01*
Y1517114D01*
X145498Y1517614D01*
X176998D01*
X190498Y1531114D01*
X235998D01*
X236998Y1530114D01*
Y1522114D01*
X239706Y1519406D01*
Y1514594D01*
X240848Y1513452D01*
Y1511898D01*
X248100D01*
Y1506300D01*
X247200Y1505400D01*
G37*
G36*
G01X222998Y1507614D02*
X199998D01*
X195998Y1503614D01*
X145498D01*
X144998Y1504114D01*
Y1506614D01*
X145498Y1507114D01*
X186498D01*
X198498Y1519114D01*
X222998D01*
X223998Y1518114D01*
Y1508614D01*
X222998Y1507614D01*
G37*
G36*
G01X167998Y1538614D02*
X145998D01*
X144998Y1539614D01*
Y1551114D01*
X145998Y1552114D01*
X160998D01*
X172498Y1563614D01*
X241948D01*
Y1561298D01*
X250852D01*
Y1563614D01*
X271435D01*
X273499Y1561550D01*
Y1542050D01*
X270149Y1538700D01*
X251700D01*
X249786Y1540614D01*
X226998D01*
X225498Y1542114D01*
Y1551614D01*
X223998Y1553114D01*
X182498D01*
X167998Y1538614D01*
G37*
G36*
G01X221998Y1540614D02*
X189498D01*
X182498Y1533614D01*
X145998D01*
X144998Y1534614D01*
Y1536114D01*
X145998Y1537114D01*
X169498D01*
X183998Y1551614D01*
X221998D01*
X223498Y1550114D01*
Y1542114D01*
X221998Y1540614D01*
G37*
G36*
G01X274999Y1166050D02*
Y1149050D01*
X270999Y1145050D01*
X220999D01*
X218999Y1147050D01*
Y1167050D01*
X222999Y1171050D01*
X269999D01*
X274999Y1166050D01*
G37*
G36*
G01X249752Y297900D02*
Y298102D01*
X243198D01*
X242998Y298302D01*
Y304114D01*
X241998Y305114D01*
Y313114D01*
X242498Y313614D01*
X249600D01*
X252800Y316814D01*
X252886Y316813D01*
G03X254520Y317445I49J2301D01*
G01X254578Y317500D01*
X255962D01*
X256313Y317148D01*
X259252D01*
X260498Y315902D01*
Y300114D01*
X258284Y297900D01*
X249752D01*
G37*
G36*
G01X282849Y348900D02*
X243400D01*
X242900Y349400D01*
Y361451D01*
X252999Y371550D01*
X280999D01*
X284999Y367550D01*
Y351050D01*
X282849Y348900D01*
G37*
G36*
G01X246000Y1493896D02*
Y1499500D01*
X245584Y1499916D01*
G02X245867Y1500598I283J282D01*
G01X248998D01*
Y1495929D01*
X246683Y1493613D01*
G02X246000Y1493896I-283J283D01*
G37*
G36*
G01X259701Y1516201D02*
X259524Y1516024D01*
X256524D01*
X256499Y1516050D01*
X249300D01*
X248752Y1515502D01*
X248548D01*
Y1515298D01*
X247950Y1514700D01*
X241900D01*
X240999Y1515601D01*
Y1530550D01*
X241499Y1531050D01*
X256999D01*
X257024Y1531024D01*
X260476D01*
X261500Y1530000D01*
Y1518302D01*
X261356Y1518260D01*
G03X259708Y1516272I643J-2210D01*
G01X259701Y1516201D01*
G37*
G36*
G01X275200Y1566550D02*
X274050Y1565400D01*
X243300D01*
X242900Y1565800D01*
Y1582800D01*
X248150Y1588050D01*
X282999D01*
X283800Y1587248D01*
Y1566851D01*
X283499Y1566550D01*
X275200D01*
G37*
G36*
G01X281031Y293050D02*
X266999D01*
X265498Y294551D01*
Y312550D01*
X265499D01*
Y316050D01*
X266499Y317050D01*
X281499D01*
X282531Y316018D01*
Y294550D01*
X281031Y293050D01*
G37*
G36*
G01X281499Y1507550D02*
X280499Y1506550D01*
X267499D01*
X265499Y1508550D01*
Y1530050D01*
X266999Y1531550D01*
X279999D01*
X281499Y1530050D01*
Y1507550D01*
G37*
G36*
G01X301499Y44550D02*
X305999Y49050D01*
X325999D01*
X327999Y51050D01*
Y53550D01*
X330999Y56550D01*
X350499D01*
X351499Y55550D01*
Y44050D01*
X349999Y42550D01*
X338999D01*
X325350Y28902D01*
X318448D01*
Y27100D01*
X287700D01*
X287100Y27700D01*
Y31000D01*
X288200Y32100D01*
X290049D01*
X294298Y36348D01*
X297497D01*
X297698Y36550D01*
X300499D01*
X301499Y37550D01*
Y44550D01*
G37*
G36*
G01X284999Y34050D02*
X283499Y35550D01*
Y46050D01*
X286999Y49550D01*
X296499D01*
X298499Y47550D01*
Y39050D01*
X296999Y37550D01*
X292999D01*
X292264Y36814D01*
X291648D01*
Y36198D01*
X289499Y34050D01*
X284999D01*
G37*
G36*
G01X296499Y71050D02*
X287999D01*
X286999Y72050D01*
Y81550D01*
X288499Y83050D01*
X297499D01*
X297999Y82550D01*
Y72550D01*
X296499Y71050D01*
G37*
G36*
G01X310999Y60550D02*
X290999D01*
X288499Y63050D01*
Y67050D01*
X290499Y69050D01*
X297999D01*
X301499Y72550D01*
Y81550D01*
X302999Y83050D01*
X322950D01*
X323800Y82200D01*
Y77351D01*
X311999Y65550D01*
Y61550D01*
X310999Y60550D01*
G37*
G36*
G01X307562Y335113D02*
X307999Y335550D01*
X317499D01*
X317999Y335050D01*
Y332050D01*
X318999Y331050D01*
X328258D01*
X328304Y331024D01*
G03X329098Y330812I796J1389D01*
G01X330498D01*
G03X332062Y332069I0J1601D01*
G01X332075Y332126D01*
X332499Y332550D01*
Y338050D01*
X333499Y339050D01*
X563999D01*
X566499Y336550D01*
Y322550D01*
X563999Y320050D01*
X302499D01*
X301999Y320550D01*
Y323050D01*
X301499Y323550D01*
X288481D01*
X288480Y323552D01*
X282498D01*
X281999Y324050D01*
Y329050D01*
X282999Y330050D01*
X305999D01*
X307499Y331550D01*
Y332789D01*
X307510Y332821D01*
G03X307600Y333350I-1511J529D01*
G01Y334750D01*
G03X307579Y335012I-1601J3D01*
G01X307562Y335113D01*
G37*
G36*
G01X289998Y349114D02*
X288498Y350614D01*
Y362114D01*
X289498Y363114D01*
X306998D01*
X307998Y362114D01*
Y361309D01*
X307987Y361277D01*
G03X307898Y360750I1512J-526D01*
G01Y359350D01*
G03X307987Y358823I1601J-1D01*
G01X307998Y358791D01*
Y357309D01*
X307987Y357277D01*
G03X307898Y356750I1512J-526D01*
G01Y355350D01*
G03X307986Y354826I1601J-1D01*
G01X307996Y354795D01*
Y351694D01*
X305418Y349116D01*
X302332D01*
X302331Y349114D01*
X289998D01*
G37*
G36*
G01X398499Y1481550D02*
X344499Y1535550D01*
X310164D01*
X310159D01*
G03X310099Y1535552I-83J-1599D01*
G01X308499D01*
G03X308439Y1535550I23J-1601D01*
G01X308434D01*
X284999D01*
X281999Y1538550D01*
Y1547050D01*
X282499Y1547550D01*
X291499D01*
X294999Y1551050D01*
X295796D01*
X295820Y1551044D01*
G03X296200Y1550998I381J1556D01*
G01X297800D01*
G03X298180Y1551044I-1J1602D01*
G01X298204Y1551050D01*
X301848D01*
Y1550219D01*
X301956Y1550111D01*
X301938Y1550008D01*
G03X305609Y1551903I2561J-458D01*
G02X305497Y1552548I171J362D01*
G01X305499Y1552550D01*
Y1553289D01*
X305510Y1553321D01*
G03X305600Y1553850I-1511J529D01*
G01Y1555250D01*
G03X305510Y1555779I-1601J0D01*
G01X305499Y1555811D01*
Y1555851D01*
G02X305919Y1556251I400J0D01*
G03X305999Y1556248I100J1598D01*
G01X307399D01*
G03X308285Y1556516I-1J1602D01*
G01X308336Y1556550D01*
X315017D01*
X315098Y1556469D01*
Y1550054D01*
X315084Y1550019D01*
G03X320052Y1548550I2414J-970D01*
G01X324893D01*
X324950Y1548498D01*
G03X328665Y1549418I1550J1702D01*
G01X328713Y1549550D01*
X361499D01*
X390411Y1520638D01*
G02X390257Y1519977I-283J-282D01*
G03X389310Y1516234I742J-2179D01*
G02Y1515962I-147J-136D01*
G03X392688I1689J-1564D01*
G02Y1516234I147J136D01*
G03X393178Y1517056I-1689J1564D01*
G02X393839Y1517210I379J-129D01*
G01X402999Y1508050D01*
X566499D01*
X568999Y1505550D01*
Y1486550D01*
X563999Y1481550D01*
X398499D01*
G37*
G36*
G01X289998Y1566114D02*
X288498Y1567614D01*
Y1579114D01*
X289498Y1580114D01*
X306998D01*
X307998Y1579114D01*
Y1578309D01*
X307987Y1578277D01*
G03X307898Y1577750I1512J-526D01*
G01Y1576350D01*
G03X307987Y1575823I1601J-1D01*
G01X307998Y1575791D01*
Y1574309D01*
X307987Y1574277D01*
G03X307898Y1573750I1512J-526D01*
G01Y1572350D01*
G03X307987Y1571823I1601J-1D01*
G01X307998Y1571791D01*
Y1570282D01*
X307994Y1570262D01*
G03Y1569338I2255J-462D01*
G01X307998Y1569318D01*
Y1567114D01*
X306998Y1566114D01*
X289998D01*
G37*
G36*
G01X295999Y289316D02*
Y292409D01*
X296023Y292454D01*
G03Y294646I-2024J1096D01*
G01X295999Y294691D01*
Y316550D01*
X297499Y318050D01*
X308499D01*
X309298Y318848D01*
X311322D01*
X311360Y318832D01*
G03X312000Y318698I641J1468D01*
G01X313600D01*
G03X314240Y318832I-1J1602D01*
G01X314278Y318848D01*
X325298D01*
Y305462D01*
X309151Y289316D01*
X295999D01*
G37*
G36*
G01X314701Y347834D02*
X314561Y347949D01*
G03X311167Y347866I-1649J-2013D01*
G02X310499Y348163I-268J297D01*
G01Y350232D01*
X310800Y350532D01*
Y353551D01*
G02X310988Y353751I200J1D01*
G03X312286Y354549I-89J1599D01*
G01X312343Y354648D01*
X316497D01*
Y349630D01*
X314701Y347834D01*
G37*
G36*
G01X316497Y1566579D02*
X315169Y1565252D01*
X308800D01*
G02X308517Y1565934I0J400D01*
G01X309200Y1566616D01*
Y1567177D01*
G02X309696Y1567566I400J1D01*
G03X312049Y1571235I553J2234D01*
G03X312447Y1571940I-1150J1114D01*
G01X312486Y1572088D01*
X316497D01*
Y1566579D01*
G37*
G36*
G01X362999Y19050D02*
X361499Y17550D01*
X321150D01*
X319600Y19100D01*
Y24700D01*
X320500Y25600D01*
X325549D01*
X326248Y26298D01*
X327352D01*
Y27402D01*
X335999Y36050D01*
X350999D01*
X353499Y38550D01*
X361499D01*
X362999Y37050D01*
Y19050D01*
G37*
G36*
G01X341999Y79113D02*
X322499Y59613D01*
X318999D01*
X317999Y60613D01*
Y68599D01*
X324948Y75548D01*
X326502D01*
Y83452D01*
X325943D01*
Y85057D01*
X332499Y91613D01*
X356836D01*
X357599Y90850D01*
Y80213D01*
X356499Y79113D01*
X341999D01*
G37*
G36*
G01X323350Y1558452D02*
Y1559052D01*
X317000D01*
Y1563118D01*
X318850Y1564968D01*
X319119Y1564698D01*
X326405D01*
X326465Y1564613D01*
G03X328413Y1563505I2135J1487D01*
G02X328668Y1562824I-29J-399D01*
G03X328007Y1560991I1632J-1624D01*
G01X328016Y1560898D01*
X326965Y1559847D01*
X326897Y1559839D01*
G03X325538Y1558607I202J-1589D01*
G01X325502Y1558452D01*
X323350D01*
G37*
G36*
G01X391999Y54550D02*
X391499Y55050D01*
Y57550D01*
X391350Y57698D01*
Y58112D01*
X390938D01*
X389499Y59550D01*
X377499D01*
X376499Y58550D01*
Y58312D01*
X376488Y58280D01*
G03X376398Y57750I1511J-529D01*
G01Y56448D01*
X375999Y56050D01*
X369499D01*
X361499Y64050D01*
X352499D01*
X351499Y65050D01*
Y72050D01*
X352999Y73550D01*
X368096D01*
X368120Y73544D01*
G03X368500Y73498I381J1556D01*
G01X370100D01*
G03X370480Y73544I-1J1602D01*
G01X370504Y73550D01*
X388019D01*
X388057Y73533D01*
G03X388700Y73398I644J1467D01*
G01X390300D01*
G03X390943Y73533I-1J1602D01*
G01X390981Y73550D01*
X400499D01*
X401999Y72050D01*
Y57312D01*
X401988Y57280D01*
G03X401898Y56750I1511J-529D01*
G01Y55350D01*
G03X401919Y55088I1601J-3D01*
G01X401936Y54987D01*
X401499Y54550D01*
X391999D01*
G37*
G36*
G01X362999Y98550D02*
X343499D01*
X342499Y99550D01*
Y116050D01*
X343999Y117550D01*
X363499D01*
X364499Y116550D01*
Y100050D01*
X362999Y98550D01*
G37*
G36*
G01X368999Y13050D02*
X367499Y14550D01*
Y32050D01*
X368999Y33550D01*
X383499D01*
X384499Y32550D01*
Y31812D01*
X384488Y31780D01*
G03X384398Y31250I1511J-529D01*
G01Y29850D01*
G03X384488Y29320I1601J-1D01*
G01X384499Y29288D01*
Y27312D01*
X384488Y27280D01*
G03X384398Y26750I1511J-529D01*
G01Y25350D01*
G03X384488Y24820I1601J-1D01*
G01X384499Y24788D01*
Y15050D01*
X382499Y13050D01*
X368999D01*
G37*
G36*
G01X657851Y1819203D02*
X659575Y1820928D01*
X659716Y1820787D01*
G03X663684Y1821147I1833J1847D01*
G01X663744Y1821232D01*
X663968D01*
X664998Y1820203D01*
Y1816370D01*
X662198D01*
Y1814036D01*
X656468D01*
X655775Y1813342D01*
X655668Y1813367D01*
G03X652843Y1812362I-619J-2733D01*
G01X652783Y1812286D01*
X651217D01*
X651160Y1812391D01*
G03X651000Y1812634I-1412J-756D01*
G03X651350Y1813634I-1251J999D01*
G01Y1815034D01*
G03X651180Y1815753I-1601J1D01*
G02X651537Y1816332I357J179D01*
G01X651949D01*
G03X653185Y1816916I-1J1602D01*
G02X653765Y1816956I309J-255D01*
G03X654849Y1816532I1085J1177D01*
G01X656249D01*
G03X657850Y1818134I0J1601D01*
G01X657851Y1819203D01*
G37*
G36*
G01X695096Y1806697D02*
X697024Y1804768D01*
G02X696741Y1804086I-283J-282D01*
G01X695210D01*
X695163Y1804113D01*
G03X694349Y1804336I-815J-1379D01*
G01X692749D01*
G03X691597Y1803847I0J-1601D01*
G01X691538Y1803786D01*
X691310D01*
X688860Y1801336D01*
X686937D01*
X686890Y1801364D01*
G03X686178Y1801659I-1341J-2230D01*
G01X686124Y1801672D01*
X684750Y1803046D01*
Y1803634D01*
G03X684626Y1804365I-2201J3D01*
G02X685003Y1804898I377J133D01*
G01X686900D01*
Y1806862D01*
X688464D01*
X688514Y1806829D01*
G03X691288Y1807107I1217J1835D01*
G01X691363Y1807182D01*
X692071D01*
X692109Y1807166D01*
G03X692749Y1807032I641J1468D01*
G01X694349D01*
G03X694628Y1807057I-3J1602D01*
G02X695096Y1806697I69J-394D01*
G37*
G36*
G01X736680Y1801532D02*
X739480Y1804332D01*
X740449D01*
G03X741496Y1804722I-1J1602D01*
G02X742076Y1804662I262J-302D01*
G03X743349Y1804032I1273J971D01*
G01X744749D01*
G03X746174Y1804904I-1J1602D01*
G01X746230Y1805012D01*
X747480D01*
G02X747763Y1804330I0J-400D01*
G01X746648Y1803215D01*
Y1800715D01*
X746521Y1800588D01*
G02X745941Y1800604I-282J283D01*
G03X744749Y1801136I-1192J-1069D01*
G01X743349D01*
G03X742113Y1800552I1J-1602D01*
G02X741533Y1800512I-309J255D01*
G03X740449Y1800936I-1085J-1177D01*
G01X739049D01*
G03X738049Y1800585I1J-1602D01*
G03X737049Y1800936I-1001J-1251D01*
G01X735649D01*
G03X735123Y1800847I1J-1602D01*
G01X735091Y1800836D01*
X734410D01*
Y1801114D01*
X734463Y1801171D01*
G03X734684Y1801447I-1916J1761D01*
G01X734744Y1801532D01*
X736680D01*
G37*
G36*
G01X753499Y152050D02*
X751999Y153550D01*
Y159550D01*
X752999Y160550D01*
X815237D01*
X815269Y160539D01*
G03X815799Y160448I532J1511D01*
G01X817199D01*
G03X817729Y160539I-2J1602D01*
G01X817761Y160550D01*
X822737D01*
X822769Y160539D01*
G03X823299Y160448I532J1511D01*
G01X824699D01*
G03X825229Y160539I-2J1602D01*
G01X825261Y160550D01*
X830237D01*
X830269Y160539D01*
G03X830799Y160448I532J1511D01*
G01X832199D01*
G03X832729Y160539I-2J1602D01*
G01X832761Y160550D01*
X837999D01*
X839999Y158550D01*
Y153550D01*
X838499Y152050D01*
X753499D01*
G37*
G36*
G01X756300Y707398D02*
G03X756943Y707533I-1J1602D01*
G01X756982Y707550D01*
X776018D01*
X776057Y707533D01*
G03X776700Y707398I644J1467D01*
G01X778300D01*
G03X778943Y707533I-1J1602D01*
G01X778982Y707550D01*
X784999D01*
X787499Y705050D01*
Y698050D01*
X786499Y697050D01*
X747999D01*
X746499Y698550D01*
Y706550D01*
X747499Y707550D01*
X754018D01*
X754057Y707533D01*
G03X754700Y707398I644J1467D01*
G01X756300D01*
G37*
G36*
G01X780499Y727298D02*
X780435Y727239D01*
G03Y723861I1564J-1689D01*
G01X780499Y723802D01*
Y719050D01*
X780999Y718550D01*
X787499D01*
X788999Y720050D01*
Y724050D01*
X789499Y724550D01*
X794999D01*
X795999Y723550D01*
Y718050D01*
X794504Y716554D01*
X790333D01*
X790329Y716550D01*
X789499D01*
X787499Y714550D01*
Y710050D01*
X786499Y709050D01*
X744999D01*
X744000Y710048D01*
Y720552D01*
X745499Y722050D01*
X750999D01*
X752499Y723550D01*
Y726550D01*
X761999D01*
X762999Y725550D01*
Y721550D01*
X763999Y720550D01*
X770570D01*
X770592Y720545D01*
G03X771618I513J2244D01*
G01X771640Y720550D01*
X775499D01*
X776499Y721550D01*
Y722789D01*
X776510Y722821D01*
G03X776600Y723350I-1511J529D01*
G01Y724750D01*
G03X776510Y725279I-1601J0D01*
G01X776499Y725311D01*
Y727289D01*
X776510Y727321D01*
G03X776600Y727850I-1511J529D01*
G01Y729250D01*
G03X776579Y729512I-1601J3D01*
G01X776562Y729613D01*
X776999Y730050D01*
X779999D01*
X780499Y729550D01*
Y727298D01*
G37*
G36*
G01X755666Y741884D02*
X751499Y746050D01*
Y748400D01*
X753649Y750550D01*
X759999D01*
X761499Y749050D01*
Y742050D01*
X761332Y741884D01*
X755666D01*
G37*
G36*
G01X775999Y1121248D02*
G03X776885Y1121516I-1J1602D01*
G01X776936Y1121550D01*
X776999D01*
X777499Y1122050D01*
Y1122289D01*
X777510Y1122321D01*
G03X777600Y1122850I-1511J529D01*
G01Y1124250D01*
G03X777510Y1124779I-1601J0D01*
G01X777499Y1124811D01*
Y1126289D01*
X777510Y1126321D01*
G03X777600Y1126850I-1511J529D01*
G01Y1127652D01*
X778499Y1128550D01*
X779499D01*
X780499Y1127550D01*
Y1123550D01*
X783499Y1120550D01*
X791499D01*
X791999Y1121050D01*
X792999D01*
X793999Y1120050D01*
Y1111550D01*
X791999Y1109550D01*
X779704D01*
X779680Y1109556D01*
G03X779300Y1109602I-381J-1556D01*
G01X777700D01*
G03X777320Y1109556I1J-1602D01*
G01X777296Y1109550D01*
X761704D01*
X761680Y1109556D01*
G03X761300Y1109602I-381J-1556D01*
G01X759700D01*
G03X759320Y1109556I1J-1602D01*
G01X759296Y1109550D01*
X747499D01*
X746499Y1110550D01*
Y1121050D01*
X747999Y1122550D01*
X750999D01*
X752999Y1124550D01*
Y1127050D01*
X753999Y1128050D01*
X761999D01*
X762999Y1127050D01*
Y1124050D01*
X765499Y1121550D01*
X773662D01*
X773713Y1121516D01*
G03X774599Y1121248I887J1334D01*
G01X775999D01*
G37*
G36*
G01X761600Y1086452D02*
X744900Y1103151D01*
Y1109484D01*
G02X745583Y1109767I400J0D01*
G01X747001Y1108348D01*
X792497D01*
X793615Y1109467D01*
G02X794298Y1109184I283J-283D01*
G01Y1094052D01*
X796501Y1091848D01*
X804921D01*
G02X805243Y1091211I0J-400D01*
G03X805991Y1087189I2256J-1661D01*
G02X805775Y1086452I-215J-337D01*
G01X784194D01*
X784134Y1086537D01*
G03X779864I-2135J-1487D01*
G01X779804Y1086452D01*
X761600D01*
G37*
G36*
G01X744900Y1132037D02*
Y1144469D01*
X755922Y1155490D01*
X759873D01*
G02X760156Y1154808I0J-400D01*
G01X759396Y1154049D01*
Y1150751D01*
X759398Y1150749D01*
Y1150518D01*
X762598Y1147319D01*
Y1146052D01*
X757574D01*
G02X756998Y1145838I-377J133D01*
G03X756199Y1146052I-800J-1388D01*
G01X754799D01*
G03X753198Y1144450I0J-1601D01*
G01Y1143952D01*
X751694D01*
X751634Y1144037D01*
G03Y1141063I-2135J-1487D01*
G01X751694Y1141148D01*
X753198D01*
Y1139981D01*
X749182Y1135965D01*
Y1133511D01*
X749087Y1133452D01*
G03X748546Y1132893I846J-1360D01*
G01X748489Y1132794D01*
X747360D01*
X746160Y1131593D01*
X746057Y1131611D01*
G03X745340Y1131639I-459J-2561D01*
G02X744900Y1132037I-40J398D01*
G37*
G36*
G01X764184Y1130894D02*
Y1133454D01*
X761984D01*
Y1135047D01*
X759648Y1137384D01*
X756346D01*
X756286Y1137469D01*
G03X756091Y1137716I-2136J-1486D01*
G02X756236Y1138049I149J133D01*
G03X757768Y1139328I-37J1601D01*
G01X757801Y1139488D01*
X764001D01*
Y1140070D01*
X765400Y1141469D01*
Y1142048D01*
X770870D01*
X772773Y1140145D01*
X772639Y1140003D01*
G03X772198Y1138900I1161J-1104D01*
G01Y1137500D01*
G03X772732Y1136307I1602J1D01*
G01X772798Y1136247D01*
Y1135895D01*
X772713Y1135835D01*
G03X771803Y1132689I1487J-2135D01*
G02X771592Y1132166I-369J-155D01*
G03X770407Y1131010I907J-2116D01*
G01X770353Y1130894D01*
X764184D01*
G37*
G36*
G01X758580Y1493952D02*
X742400Y1510131D01*
Y1543469D01*
X758080Y1559148D01*
X766826D01*
Y1558596D01*
G03X766924Y1558043I1601J-1D01*
G01X766968Y1557923D01*
X763598Y1554553D01*
Y1548298D01*
X758192D01*
X758134Y1548353D01*
G03X757411Y1548751I-1108J-1157D01*
G02X757173Y1549359I96J388D01*
G03X753512Y1548653I-2174J1429D01*
G01X753598Y1548593D01*
Y1547293D01*
X754026Y1546865D01*
Y1545796D01*
G03X754376Y1544796I1601J-1D01*
G03X754216Y1544553I1252J-999D01*
G01X754159Y1544448D01*
X750914D01*
X748598Y1542131D01*
Y1538469D01*
X751326Y1535741D01*
Y1535596D01*
G03X752081Y1534236I1602J0D01*
G01X752176Y1534177D01*
Y1533415D01*
X752081Y1533356D01*
G03X751540Y1532797I846J-1360D01*
G01X751483Y1532698D01*
X747795D01*
X747735Y1532783D01*
G03Y1529809I-2135J-1487D01*
G01X747795Y1529894D01*
X751483D01*
X751540Y1529795D01*
G03X751818Y1529440I1387J800D01*
G02X751542Y1528752I-277J-288D01*
G01X747501D01*
X745298Y1526548D01*
Y1519052D01*
X748942Y1515408D01*
X748949Y1515398D01*
G03X749398Y1514949I2051J1602D01*
G01X749408Y1514942D01*
X750501Y1513848D01*
X789997D01*
X790361Y1514213D01*
G02X791043Y1513930I282J-283D01*
G01X791044Y1501224D01*
X793247Y1499021D01*
X801590D01*
G02X801828Y1498299I0J-400D01*
G03X801124Y1494564I1671J-2249D01*
G02X800785Y1493952I-339J-212D01*
G01X793694D01*
X793634Y1494037D01*
G03X789364I-2135J-1487D01*
G01X789304Y1493952D01*
X758580D01*
G37*
G36*
G01X779782Y1528593D02*
G03X779531Y1529454I-1600J1D01*
G01X779530Y1529455D01*
X779499Y1529505D01*
Y1530281D01*
X779530Y1530331D01*
X779531Y1530332D01*
G03X779782Y1531193I-1349J860D01*
G01Y1532593D01*
G03X779777Y1532729I-1601J9D01*
G01X779770Y1532821D01*
X779999Y1533050D01*
X780999D01*
X781999Y1532050D01*
Y1527550D01*
X783999Y1525550D01*
X785692D01*
Y1525526D01*
X789694D01*
Y1525550D01*
X790999D01*
X791999Y1526550D01*
Y1531050D01*
X792499Y1531550D01*
X793499D01*
X794999Y1530050D01*
Y1526050D01*
X790999Y1522050D01*
Y1516550D01*
X789499Y1515050D01*
X784863D01*
X784816Y1515078D01*
G03X784000Y1515302I-817J-1378D01*
G01X782400D01*
G03X781584Y1515078I1J-1602D01*
G01X781537Y1515050D01*
X764012D01*
X763953Y1515111D01*
G03X762800Y1515602I-1154J-1111D01*
G01X761200D01*
G03X760047Y1515111I1J-1602D01*
G01X759988Y1515050D01*
X750999D01*
X746499Y1519550D01*
Y1526050D01*
X747999Y1527550D01*
X754499D01*
X755999Y1529050D01*
Y1531550D01*
X756999Y1532550D01*
X765499D01*
X766476Y1531574D01*
Y1529234D01*
X766499D01*
Y1525550D01*
X767499Y1524550D01*
X778499D01*
X779499Y1525550D01*
Y1526281D01*
X779530Y1526331D01*
X779531Y1526332D01*
G03X779782Y1527193I-1349J860D01*
G01Y1528593D01*
G37*
G36*
G01X820889Y1781550D02*
X823239D01*
X823271Y1781539D01*
G03X823799Y1781448I532J1510D01*
G01X825199D01*
G03X825727Y1781539I-4J1601D01*
G01X825759Y1781550D01*
X827808D01*
X827856Y1781521D01*
G03X830542I1343J2229D01*
G01X830590Y1781550D01*
X832239D01*
X832271Y1781539D01*
G03X832799Y1781448I532J1510D01*
G01X834199D01*
G03X834727Y1781539I-4J1601D01*
G01X834759Y1781550D01*
X838350D01*
X839500Y1780400D01*
Y1774300D01*
X832700Y1767500D01*
Y1738452D01*
X830798D01*
Y1731200D01*
X822300D01*
X821200Y1732300D01*
Y1756700D01*
X815700Y1762200D01*
X753800D01*
X750499Y1765501D01*
Y1779550D01*
X752499Y1781550D01*
X813739D01*
X813771Y1781539D01*
G03X814299Y1781448I532J1510D01*
G01X815699D01*
G03X816227Y1781539I-4J1601D01*
G01X816259Y1781550D01*
X818297D01*
X818342Y1781525D01*
G03X820844I1251J2282D01*
G01X820889Y1781550D01*
G37*
G36*
G01X765643Y1900952D02*
X748580Y1918014D01*
X748517D01*
X741400Y1925131D01*
Y1952469D01*
X754580Y1965649D01*
X759201D01*
G02X759484Y1964966I0J-400D01*
G01X758498Y1963981D01*
Y1960119D01*
X759098Y1959519D01*
Y1959518D01*
X761098Y1957519D01*
Y1954215D01*
X755912D01*
Y1953614D01*
X755267D01*
X755207Y1953681D01*
G03X754014Y1954214I-1193J-1069D01*
G01X753571D01*
Y1954445D01*
X753580Y1954474D01*
G03X750570Y1952702I-2484J776D01*
G01X750628Y1952690D01*
X751012Y1952305D01*
Y1951213D01*
G03X751363Y1950213I1602J1D01*
G03X751203Y1949970I1252J-999D01*
G01X751146Y1949864D01*
X746131D01*
X744798Y1948531D01*
Y1943069D01*
X746518Y1941348D01*
X747813D01*
X747846Y1941189D01*
G03X748568Y1940153I1568J323D01*
G01X748662Y1940094D01*
Y1939832D01*
X748568Y1939773D01*
G03X747812Y1938413I845J-1360D01*
G01Y1937013D01*
G03X748255Y1935907I1602J0D01*
G02X748170Y1935287I-289J-276D01*
G03X750711Y1930748I1329J-2237D01*
G02X751298Y1930394I187J-354D01*
G01Y1922803D01*
X753602Y1920498D01*
X758142D01*
X758174Y1920487D01*
G03X758700Y1920398I527J1513D01*
G01X760300D01*
G03X760826Y1920487I-1J1602D01*
G01X760858Y1920498D01*
X767488D01*
X767507Y1920495D01*
G03X768491I492J2555D01*
G01X768510Y1920498D01*
X783142D01*
X783174Y1920487D01*
G03X783700Y1920398I527J1513D01*
G01X785300D01*
G03X785826Y1920487I-1J1602D01*
G01X785858Y1920498D01*
X791297D01*
X791552Y1920754D01*
G02X792235Y1920471I283J-283D01*
G01X792234Y1907867D01*
X794438Y1905664D01*
X795033D01*
G02X795433Y1905264I0J-400D01*
G03X795550Y1904981I400J0D01*
G01X798897Y1901634D01*
G02X798615Y1900952I-283J-282D01*
G01X792694D01*
X792634Y1901037D01*
G03X788364I-2135J-1487D01*
G01X788304Y1900952D01*
X765643D01*
G37*
G36*
G01X777100Y1935750D02*
G03X777010Y1936279I-1601J0D01*
G01X776999Y1936311D01*
Y1937789D01*
X777010Y1937821D01*
G03X777100Y1938350I-1511J529D01*
G01Y1939652D01*
X777499Y1940050D01*
X778999D01*
X779499Y1939550D01*
Y1936050D01*
X784999Y1930550D01*
X787499D01*
X789999Y1933050D01*
Y1937550D01*
X790499Y1938050D01*
X791499D01*
X791999Y1937550D01*
Y1922900D01*
X790799Y1921700D01*
X754100D01*
X752499Y1923301D01*
Y1938550D01*
X752999Y1939050D01*
X761999D01*
X762962Y1938086D01*
Y1935152D01*
X762999D01*
Y1934550D01*
X764999Y1932550D01*
X776499D01*
X776999Y1933050D01*
Y1933789D01*
X777010Y1933821D01*
G03X777100Y1934350I-1511J529D01*
G01Y1935750D01*
G37*
G36*
G01X773478Y1941226D02*
G03X769964Y1941765I-1979J-1176D01*
G01X769907Y1941714D01*
X763666D01*
Y1944274D01*
X756462D01*
Y1943614D01*
X755658D01*
X755601Y1943714D01*
G03X754214Y1944514I-1387J-802D01*
G01X753316D01*
X752301Y1945529D01*
G02X752590Y1946212I283J283D01*
G03X752614I12J1601D01*
G01X754014D01*
G03X755583Y1947491I0J1602D01*
G01X755616Y1947651D01*
X762316D01*
Y1948252D01*
X762683D01*
X763900Y1949469D01*
Y1950211D01*
X769106D01*
X771668Y1947648D01*
X774155D01*
X774212Y1947549D01*
G03X774621Y1947082I1386J802D01*
G01X774698Y1947022D01*
Y1946395D01*
X774613Y1946335D01*
G03X774595Y1942078I1487J-2135D01*
G02X774363Y1941352I-232J-326D01*
G01X774099D01*
G03X773478Y1941226I2J-1602D01*
G37*
G36*
G01X769696Y745882D02*
X768696Y746882D01*
Y747120D01*
X768707Y747152D01*
G03X768798Y747682I-1511J532D01*
G01Y749082D01*
G03X768707Y749612I-1602J-2D01*
G01X768696Y749644D01*
Y751620D01*
X768707Y751652D01*
G03X768798Y752182I-1511J532D01*
G01Y753582D01*
G03X768707Y754112I-1602J-2D01*
G01X768696Y754144D01*
Y764382D01*
X770696Y766382D01*
X784196D01*
X785696Y764882D01*
Y747382D01*
X784196Y745882D01*
X769696D01*
G37*
G36*
G01X764499Y729384D02*
Y730550D01*
X764048Y731002D01*
Y731944D01*
X763106D01*
X761499Y733550D01*
Y735320D01*
X762198D01*
Y736248D01*
X763830Y737880D01*
X768668D01*
X769499Y737050D01*
Y735550D01*
X769132Y735183D01*
X769096Y735168D01*
G03Y730932I903J-2118D01*
G01X769132Y730917D01*
X769499Y730550D01*
Y729550D01*
X769332Y729384D01*
X764499D01*
G37*
G36*
G01X773090Y1147392D02*
X772471Y1148012D01*
X771400D01*
Y1148612D01*
X768833D01*
Y1151130D01*
X768844Y1151162D01*
G03X768934Y1151692I-1511J529D01*
G01Y1153092D01*
G03X768844Y1153622I-1601J1D01*
G01X768833Y1153654D01*
Y1155630D01*
X768844Y1155662D01*
G03X768934Y1156192I-1511J529D01*
G01Y1157592D01*
G03X768844Y1158122I-1601J1D01*
G01X768833Y1158154D01*
Y1165892D01*
X770833Y1167892D01*
X784333D01*
X785833Y1166392D01*
Y1148892D01*
X784333Y1147392D01*
X773090D01*
G37*
G36*
G01X772327Y1551296D02*
X771327Y1552296D01*
Y1553534D01*
X771338Y1553566D01*
G03X771428Y1554096I-1511J529D01*
G01Y1555496D01*
G03X771338Y1556026I-1601J1D01*
G01X771327Y1556058D01*
Y1558034D01*
X771338Y1558066D01*
G03X771428Y1558596I-1511J529D01*
G01Y1559996D01*
G03X771338Y1560526I-1601J1D01*
G01X771327Y1560558D01*
Y1569796D01*
X773327Y1571796D01*
X786827D01*
X788327Y1570296D01*
Y1552796D01*
X786827Y1551296D01*
X772327D01*
G37*
G36*
G01X769814Y1957213D02*
X768814Y1958213D01*
Y1959451D01*
X768825Y1959483D01*
G03X768916Y1960013I-1511J532D01*
G01Y1961413D01*
G03X768825Y1961943I-1602J-2D01*
G01X768814Y1961975D01*
Y1963951D01*
X768825Y1963983D01*
G03X768916Y1964513I-1511J532D01*
G01Y1965913D01*
G03X768825Y1966443I-1602J-2D01*
G01X768814Y1966475D01*
Y1975713D01*
X770814Y1977713D01*
X784314D01*
X785814Y1976213D01*
Y1958713D01*
X784314Y1957213D01*
X769814D01*
G37*
G36*
G01X807831Y693353D02*
X791331D01*
X789831Y694853D01*
Y714353D01*
X790831Y715353D01*
X807331D01*
X808831Y713853D01*
Y694353D01*
X807831Y693353D01*
G37*
G36*
G01X805750Y744750D02*
X801550Y740550D01*
X792999D01*
X791499Y742050D01*
Y760050D01*
X793999Y762550D01*
X831850D01*
X833800Y760600D01*
Y745300D01*
X833250Y744750D01*
X805750D01*
G37*
G36*
G01X809499Y1093050D02*
X796999D01*
X795499Y1094550D01*
Y1118550D01*
X796499Y1119550D01*
X807999D01*
X808003Y1119554D01*
X810995D01*
X812999Y1117550D01*
Y1096550D01*
X809499Y1093050D01*
G37*
G36*
G01X801798Y1143348D02*
X800499Y1142050D01*
X792999D01*
X791499Y1143550D01*
Y1163050D01*
X793999Y1165550D01*
X832350D01*
X833800Y1164100D01*
Y1149900D01*
X832900Y1149000D01*
X807449D01*
X805200Y1146752D01*
X805001D01*
X801798Y1143548D01*
Y1143348D01*
G37*
G36*
G01X810245Y1500222D02*
X793745D01*
X792245Y1501722D01*
Y1521222D01*
X793245Y1522222D01*
X809745D01*
X811245Y1520722D01*
Y1501222D01*
X810245Y1500222D01*
G37*
G36*
G01X807649Y1550700D02*
X803999Y1547050D01*
X795999D01*
X794999Y1548050D01*
Y1567050D01*
X796499Y1568550D01*
X833950D01*
X836300Y1566200D01*
Y1552102D01*
X828348D01*
Y1550700D01*
X807649D01*
G37*
G36*
G01X794936Y1906865D02*
X793436Y1908365D01*
Y1927865D01*
X794436Y1928865D01*
X810936D01*
X812434Y1927366D01*
Y1907866D01*
X811434Y1906865D01*
X794936D01*
G37*
G36*
G01X800466Y1952631D02*
X800386Y1952550D01*
X793499D01*
X792499Y1953550D01*
Y1972550D01*
X794499Y1974550D01*
X833450D01*
X834900Y1973100D01*
Y1962400D01*
X833550Y1961050D01*
X803999D01*
X801499Y1958550D01*
Y1953623D01*
G03X800480Y1952657I999J-2074D01*
G01Y1952656D01*
X800466Y1952631D01*
G37*
G36*
G01X825531Y172064D02*
X822848Y169381D01*
Y169218D01*
X822742Y169161D01*
G03X821898Y167750I757J-1411D01*
G01Y166350D01*
G03X822321Y165266I1600J0D01*
G02X822281Y164686I-295J-271D01*
G03X821698Y163450I1019J-1236D01*
G01Y162050D01*
G03X821700Y161962I1601J-8D01*
G01Y161957D01*
Y161752D01*
X818798D01*
Y161957D01*
Y161962D01*
G03X818800Y162050I-1599J80D01*
G01Y163450D01*
G03X818377Y164534I-1600J0D01*
G02X818417Y165114I295J271D01*
G03X819000Y166350I-1019J1236D01*
G01Y167750D01*
G03X818245Y169110I-1602J0D01*
G01X818150Y169169D01*
Y170460D01*
X818326Y170481D01*
G03X820574Y173522I-313J2583D01*
G01X820556Y173625D01*
X822466Y175534D01*
X823431D01*
Y172747D01*
X825248D01*
G02X825531Y172064I0J-400D01*
G37*
G36*
G01X823500Y684900D02*
X815300D01*
X813400Y686800D01*
Y692300D01*
X815999Y694899D01*
Y696517D01*
X816000Y696518D01*
Y707052D01*
X817999Y709050D01*
X829999D01*
X831499Y707550D01*
Y699099D01*
X824552Y692152D01*
X823698D01*
Y685098D01*
X823500Y684900D01*
G37*
G36*
G01X845999Y719050D02*
X837999D01*
X833999Y723050D01*
X805499D01*
X801999Y726550D01*
Y739050D01*
X805499Y742550D01*
X825648D01*
Y740798D01*
X834552D01*
Y742550D01*
X876999D01*
X883999Y735550D01*
Y728550D01*
X883499Y728050D01*
X874499D01*
X870499Y732050D01*
X851999D01*
X848999Y729050D01*
Y722050D01*
X845999Y719050D01*
G37*
G36*
G01X823700Y1090700D02*
X818400D01*
X817500Y1091600D01*
Y1113049D01*
X818001Y1113550D01*
X830499D01*
X831499Y1112550D01*
Y1103799D01*
X825352Y1097652D01*
X823898D01*
Y1090898D01*
X823700Y1090700D01*
G37*
G36*
G01X826206Y1124050D02*
X803999D01*
X802999Y1125050D01*
Y1143050D01*
X805499Y1145550D01*
X879999D01*
X883999Y1141550D01*
Y1135050D01*
X882999Y1134050D01*
X872499D01*
X868999Y1137550D01*
X848999D01*
X847499Y1136050D01*
Y1128550D01*
X842999Y1124050D01*
X834792D01*
X834641Y1124202D01*
X826357D01*
X826206Y1124050D01*
G37*
G36*
G01X825500Y1493400D02*
X818900D01*
X817999Y1494301D01*
Y1516270D01*
X826696D01*
Y1518050D01*
X832999D01*
X833999Y1517050D01*
Y1507900D01*
X826800Y1500701D01*
Y1500152D01*
X825698D01*
Y1493598D01*
X825500Y1493400D01*
G37*
G36*
G01X845700Y1529550D02*
X808499D01*
X804999Y1533050D01*
Y1545550D01*
X807999Y1548550D01*
X881999D01*
X883999Y1546550D01*
Y1539050D01*
X883499Y1538550D01*
X869499D01*
X866499Y1541550D01*
X866198D01*
X865997Y1541752D01*
X858001D01*
X857800Y1541550D01*
X857700D01*
X845700Y1529550D01*
G37*
G36*
G01X818650Y1796220D02*
X819815Y1797385D01*
X820026Y1797596D01*
X823431D01*
Y1794795D01*
X823796D01*
G02X824079Y1794112I0J-400D01*
G01X823348Y1793381D01*
Y1790218D01*
X823242Y1790161D01*
G03X822398Y1788750I757J-1411D01*
G01Y1787786D01*
X821663Y1787052D01*
X820518D01*
X819863Y1786397D01*
X819773Y1786403D01*
G03X819545Y1786409I-182J-2596D01*
G02X819359Y1786691I-4J200D01*
G03X819500Y1787350I-1460J657D01*
G01Y1788750D01*
G03X818745Y1790110I-1602J0D01*
G01X818650Y1790169D01*
Y1790855D01*
X818736Y1790915D01*
G03Y1795185I-1487J2135D01*
G01X818650Y1795245D01*
Y1796220D01*
G37*
G36*
G01X819300Y1900100D02*
X818000Y1901400D01*
Y1907600D01*
X817999D01*
Y1921550D01*
X819362Y1922914D01*
X825888D01*
Y1924050D01*
X832999D01*
X833499Y1923550D01*
Y1913499D01*
X826852Y1906852D01*
X825898D01*
Y1900298D01*
X825700Y1900100D01*
X819300D01*
G37*
G36*
G01X804358Y1952909D02*
X809999Y1958550D01*
X827148D01*
Y1958198D01*
X836052D01*
Y1958550D01*
X865999D01*
X871999Y1952550D01*
X882999D01*
X883999Y1951550D01*
Y1945050D01*
X883499Y1944550D01*
X866499D01*
X862499Y1948550D01*
X847999D01*
X843999Y1944550D01*
Y1936050D01*
X843499Y1935550D01*
X804999D01*
X803999Y1936550D01*
Y1949802D01*
X804063Y1949861D01*
G03X804358Y1952909I-1564J1690D01*
G37*
G36*
G01X913553Y85818D02*
X915454D01*
Y85718D01*
X920332D01*
X920499Y85550D01*
Y61550D01*
X895499Y36550D01*
X839499D01*
X835999Y40050D01*
Y76050D01*
X837249Y77300D01*
X886749D01*
X895249Y85800D01*
X911281D01*
X911321Y85782D01*
G03X913512Y85798I1078J2368D01*
G01X913553Y85818D01*
G37*
G36*
G01X895521Y91572D02*
X883499Y79550D01*
X836999D01*
X835499Y81050D01*
Y126050D01*
X838999Y129550D01*
X902237D01*
X902269Y129539D01*
G03X902799Y129448I532J1511D01*
G01X904199D01*
G03X904729Y129539I-2J1602D01*
G01X904761Y129550D01*
X904999D01*
X905499Y129050D01*
Y126604D01*
X905432Y126544D01*
G03X904898Y125350I1068J-1194D01*
G01Y123750D01*
G03X904908Y123566I1601J-5D01*
G01X904919Y123470D01*
X904499Y123050D01*
X900499D01*
X895499Y118050D01*
X896499Y117050D01*
Y92543D01*
X896399Y92485D01*
G03X895534Y91597I1156J-1991D01*
G01X895521Y91572D01*
G37*
G36*
G01X826169Y168738D02*
X828368Y170937D01*
G02X829050Y170654I282J-283D01*
G01Y167766D01*
X829398Y167419D01*
Y166350D01*
G03X829821Y165266I1600J0D01*
G02X829781Y164686I-295J-271D01*
G03X829198Y163450I1019J-1236D01*
G01Y162050D01*
G03X829200Y161962I1601J-8D01*
G01Y161957D01*
Y161752D01*
X826298D01*
Y161957D01*
Y161962D01*
G03X826300Y162050I-1599J80D01*
G01Y163450D01*
G03X825877Y164534I-1600J0D01*
G02X825917Y165114I295J271D01*
G03X826500Y166350I-1019J1236D01*
G01Y167750D01*
G03X826254Y168603I-1602J0D01*
G01X826169Y168738D01*
G37*
G36*
G01X843636Y708882D02*
X844769Y707748D01*
X862660D01*
X863793Y708882D01*
X867196D01*
X869196Y706882D01*
X871688D01*
X871692D01*
G03X871880I94J2600D01*
G01X871884D01*
X882696D01*
X883696Y705882D01*
Y698882D01*
X882898Y698084D01*
X851698D01*
X851499Y697884D01*
X851244D01*
Y697882D01*
X850196D01*
X848696Y696382D01*
Y685882D01*
X847696Y684882D01*
X827018D01*
X826302Y685598D01*
Y691302D01*
X837196Y702196D01*
Y707882D01*
X838196Y708882D01*
X843636D01*
G37*
G36*
G01X826999Y710550D02*
X825499Y712050D01*
Y718050D01*
X826999Y719550D01*
X832499D01*
X835999Y716050D01*
X839703D01*
G02X839927Y715319I0J-400D01*
G03X839348Y711206I1573J-2319D01*
G02X839040Y710550I-308J-256D01*
G01X826999D01*
G37*
G36*
G01X845931Y710552D02*
X844208Y712274D01*
X844233Y712381D01*
G03X843073Y715319I-2733J619D01*
G02X843297Y716050I224J331D01*
G01X861499D01*
X862499Y715050D01*
Y711552D01*
X861498Y710552D01*
X845931D01*
G37*
G36*
G01X847333Y1090392D02*
X827208D01*
X826502Y1091098D01*
Y1096302D01*
X836833Y1106633D01*
Y1113392D01*
X837833Y1114392D01*
X866833D01*
X868833Y1112392D01*
X882333D01*
X883333Y1111392D01*
Y1104392D01*
X882534Y1103594D01*
X851335D01*
X851134Y1103392D01*
X849833D01*
X848333Y1101892D01*
Y1091392D01*
X847333Y1090392D01*
G37*
G36*
G01X842704Y1493200D02*
X828800D01*
X828400Y1493600D01*
Y1500369D01*
X838827Y1510796D01*
Y1518296D01*
X839827Y1519296D01*
X868827D01*
X870827Y1517296D01*
X884327D01*
X885327Y1516296D01*
Y1509296D01*
X884528Y1508498D01*
X853329D01*
X853129Y1508298D01*
X853126D01*
Y1508296D01*
X851827D01*
X850327Y1506796D01*
Y1496296D01*
X849327Y1495296D01*
X844800D01*
X842704Y1493200D01*
G37*
G36*
G01X832300Y1720300D02*
X831381Y1721219D01*
X831370Y1721236D01*
G03X830964Y1721712I-2168J-1438D01*
G01X830900Y1721772D01*
Y1729500D01*
X831700Y1730300D01*
X833400D01*
X834100Y1731000D01*
Y1737100D01*
X835200Y1738200D01*
X865100D01*
X865700Y1737600D01*
Y1725500D01*
X860500Y1720300D01*
X832300D01*
G37*
G36*
G01X829898Y1787681D02*
X828463Y1786246D01*
X828417Y1786232D01*
G03X827151Y1785355I782J-2482D01*
G02X826509Y1785371I-315J247D01*
G03X826377Y1785534I-1308J-924D01*
G02X826417Y1786114I295J271D01*
G03X827000Y1787350I-1019J1236D01*
G01Y1788750D01*
G03X826245Y1790110I-1602J0D01*
G01X826150Y1790169D01*
Y1792219D01*
X828726Y1794795D01*
X829050D01*
Y1793516D01*
X829210Y1793356D01*
Y1791011D01*
X830346Y1789876D01*
X830237Y1789736D01*
G03X829898Y1788750I1262J-985D01*
G01Y1787681D01*
G37*
G36*
G01X842000Y1901113D02*
X840887Y1900000D01*
X828900D01*
X828502Y1900398D01*
Y1906302D01*
X834850Y1912650D01*
X838814Y1916613D01*
Y1924113D01*
X839814Y1925113D01*
X868814D01*
X870814Y1923113D01*
X884314D01*
X885314Y1922113D01*
Y1915113D01*
X884516Y1914314D01*
X853316D01*
X853115Y1914113D01*
X851814D01*
X850314Y1912613D01*
Y1902113D01*
X849314Y1901113D01*
X842000D01*
G37*
G36*
G01X861196Y684882D02*
X852196D01*
X851196Y685882D01*
Y695882D01*
X852196Y696882D01*
X882696D01*
X883696Y695882D01*
Y693882D01*
X882696Y692882D01*
X869196D01*
X861196Y684882D01*
G37*
G36*
G01X859499Y719050D02*
X855499D01*
X854999Y719550D01*
Y730050D01*
X855499Y730550D01*
X869399D01*
X873899Y726050D01*
X883499D01*
X883999Y725550D01*
Y723550D01*
X883499Y723050D01*
X863499D01*
X859499Y719050D01*
G37*
G36*
G01X860833Y1090392D02*
X851833D01*
X850833Y1091392D01*
Y1101392D01*
X851833Y1102392D01*
X882333D01*
X883333Y1101392D01*
Y1099392D01*
X882333Y1098392D01*
X868833D01*
X860833Y1090392D01*
G37*
G36*
G01X883499Y1128550D02*
X871499D01*
X866499Y1123550D01*
X856499D01*
X855499Y1124550D01*
Y1135050D01*
X855999Y1135550D01*
X862999D01*
X866999Y1131550D01*
X883499D01*
X883999Y1131050D01*
Y1129050D01*
X883499Y1128550D01*
G37*
G36*
G01X884327Y1503296D02*
X870827D01*
X862827Y1495296D01*
X853827D01*
X852827Y1496296D01*
Y1506296D01*
X853827Y1507296D01*
X884327D01*
X885327Y1506296D01*
Y1504296D01*
X884327Y1503296D01*
G37*
G36*
G01X864499Y1528050D02*
X858501D01*
X857499Y1529052D01*
Y1539550D01*
X858499Y1540550D01*
X865499D01*
X868999Y1537050D01*
X883499D01*
X883999Y1536550D01*
Y1534050D01*
X883499Y1533550D01*
X869999D01*
X864499Y1528050D01*
G37*
G36*
G01X869401Y1712252D02*
G03X868585Y1712028I1J-1602D01*
G01X868538Y1712000D01*
X867800D01*
X862000Y1706200D01*
X845400D01*
X844100Y1707500D01*
Y1716800D01*
X845400Y1718100D01*
X872301D01*
X872602Y1717798D01*
X876502D01*
X876798Y1717502D01*
Y1712302D01*
X876888Y1712212D01*
X876676Y1712000D01*
X876626D01*
X876555Y1712018D01*
G03X875205Y1712007I-655J-2518D01*
G01X875179Y1712000D01*
X871864D01*
X871817Y1712028D01*
G03X871001Y1712252I-817J-1378D01*
G01X869401D01*
G37*
G36*
G01X860083Y1901114D02*
X860082Y1901113D01*
X853814D01*
X852814Y1902113D01*
Y1912113D01*
X853814Y1913113D01*
X884314D01*
X885314Y1912113D01*
Y1910113D01*
X884314Y1909113D01*
X870814D01*
X862816Y1901114D01*
X860083D01*
G37*
G36*
G01X865999Y1942550D02*
X882999D01*
X883999Y1941550D01*
Y1940050D01*
X883499Y1939550D01*
X867499D01*
X862999Y1935050D01*
X856999D01*
X856499Y1935550D01*
Y1946050D01*
X856999Y1946550D01*
X861999D01*
X865999Y1942550D01*
G37*
G36*
G01X890400Y1705798D02*
G03X890460Y1705800I-23J1601D01*
G01X890465D01*
X896900D01*
X897300Y1705400D01*
Y1692400D01*
X896100Y1691200D01*
X882900D01*
X882300Y1691800D01*
Y1705100D01*
X883000Y1705800D01*
X888935D01*
X888940D01*
G03X889000Y1705798I83J1599D01*
G01X890400D01*
G37*
G36*
G01X879098Y1735500D02*
Y1732900D01*
G03X879633Y1731706I1602J1D01*
G01X879700Y1731646D01*
Y1722427D01*
X879678Y1722384D01*
G03X879500Y1721650I1424J-734D01*
G01Y1720250D01*
G03X879678Y1719516I1602J0D01*
G01X879700Y1719473D01*
Y1718800D01*
X881000Y1717500D01*
Y1712600D01*
X880600Y1712200D01*
X878600D01*
X878352Y1712448D01*
Y1717700D01*
X878000D01*
Y1718000D01*
X877000Y1719000D01*
X873100D01*
X872000Y1720100D01*
Y1735700D01*
X872600Y1736300D01*
X878739D01*
G02X879131Y1735820I0J-400D01*
G03X879098Y1735500I1569J-323D01*
G37*
G36*
G01X881700Y1731800D02*
X881460Y1732040D01*
X881526Y1732170D01*
G03X881702Y1732900I-1426J730D01*
G01Y1735500D01*
G03X881000Y1736824I-1602J-1D01*
G01Y1738900D01*
X881298Y1739198D01*
X888202D01*
X888400Y1739000D01*
Y1734600D01*
X887002Y1733202D01*
X886802D01*
X885401Y1731800D01*
X881700D01*
G37*
G36*
G01X892462Y1719000D02*
X892430Y1719011D01*
G03X891900Y1719102I-532J-1511D01*
G01X889300D01*
G03X889038Y1719080I3J-1602D01*
G01X888937Y1719063D01*
X888154Y1719846D01*
X888174Y1719950D01*
G03X888202Y1720250I-1573J298D01*
G01Y1721650D01*
G03X886721Y1723247I-1602J0D01*
G01X886647Y1723253D01*
X885400Y1724500D01*
Y1730100D01*
X887300Y1732000D01*
X892800D01*
X894300Y1730500D01*
Y1719500D01*
X893800Y1719000D01*
X892462D01*
G37*
G36*
G01X919999Y15050D02*
X900499D01*
X897999Y17550D01*
Y37050D01*
X910999Y50050D01*
X920999D01*
X922499Y48550D01*
Y17550D01*
X919999Y15050D01*
G37*
G36*
G01X898711Y92485D02*
G03X897873Y92774I-1156J-1991D01*
G01X897700Y92798D01*
Y100848D01*
X901041D01*
X901073Y100837D01*
G03X901599Y100748I527J1513D01*
G01X902999D01*
G03X903072Y100750I-7J1602D01*
G02X903471Y100231I18J-399D01*
G03X903398Y99750I1528J-478D01*
G01Y98350D01*
G03X903753Y97344I1601J-1D01*
G01X903798Y97289D01*
Y96521D01*
X903733Y96461D01*
G03X902897Y94559I1766J-1911D01*
G02X902349Y94189I-400J2D01*
G03X899295Y92715I-850J-2139D01*
G02X898711Y92485I-383J116D01*
G37*
G36*
G01X926999Y30550D02*
X924999Y32550D01*
Y66050D01*
X927999Y69050D01*
X933499D01*
X935999Y71550D01*
Y73398D01*
X936250D01*
Y85718D01*
X941544D01*
Y85818D01*
X946973D01*
X947205Y86050D01*
X947499D01*
X949999Y88550D01*
Y88844D01*
X951700Y90545D01*
Y91050D01*
X953999D01*
X954499Y90550D01*
Y34050D01*
X950999Y30550D01*
X926999D01*
G37*
G36*
G01X923115Y49633D02*
X921497Y51252D01*
X912865D01*
G02X912582Y51934I0J400D01*
G01X921700Y61052D01*
Y73905D01*
X922258D01*
Y87352D01*
Y96848D01*
X924204D01*
X928200Y100845D01*
Y101079D01*
X928265Y101139D01*
G03X927453Y105471I-1766J1911D01*
G01X927546Y105856D01*
G03X927699Y105848I160J1594D01*
G01X929299D01*
G03X930113Y106071I-1J1602D01*
G01X930160Y106098D01*
X931401D01*
X931424Y106093D01*
G03X931799Y106048I377J1557D01*
G01X933199D01*
G03X933416Y106063I-2J1602D01*
G02X933807Y105451I54J-396D01*
G03X934233Y102139I2192J-1401D01*
G01X934298Y102079D01*
Y101845D01*
X936440Y99702D01*
Y97195D01*
X934740D01*
Y91622D01*
Y85383D01*
Y73905D01*
X934798D01*
Y72048D01*
X933001Y70252D01*
X927501D01*
X923798Y66548D01*
Y49916D01*
G02X923115Y49633I-400J0D01*
G37*
G36*
G01X914700Y114638D02*
X917615Y117552D01*
G02X918298Y117269I283J-283D01*
G01Y113008D01*
X918286Y112976D01*
G03X918198Y112450I1513J-524D01*
G01Y111050D01*
G03X918228Y110740I1601J-2D01*
G01X918232Y110721D01*
Y110502D01*
X917877D01*
X917839Y110518D01*
G03X917199Y110652I-641J-1468D01*
G01X915799D01*
G03X915318Y110578I0J-1602D01*
G02X914799Y110977I-120J381D01*
G03X914800Y111050I-1600J58D01*
G01Y112450D01*
G03X914712Y112976I-1601J2D01*
G01X914700Y113008D01*
Y114638D01*
G37*
G36*
G01X946794Y127349D02*
X954341Y119802D01*
G02X954116Y119124I-283J-282D01*
G03X952269Y115209I383J-2574D01*
G01X952298Y115162D01*
Y114712D01*
X951867Y114281D01*
X948700Y117448D01*
Y118852D01*
X945298D01*
Y118609D01*
G02X944615Y118326I-400J0D01*
G01X941989Y120952D01*
X940609D01*
G02X940223Y121455I0J400D01*
G03X939105Y124069I-2224J595D01*
G01X939080Y124083D01*
X936497Y126666D01*
G02X936780Y127349I283J283D01*
G01X946794D01*
G37*
G36*
G01X954404Y95052D02*
X953750Y95705D01*
Y95955D01*
X953600Y96105D01*
Y96850D01*
G03X952756Y98261I-1601J0D01*
G01X952650Y98318D01*
Y103295D01*
X952954Y103598D01*
X959363D01*
X962340Y100621D01*
Y98021D01*
X962276Y97961D01*
G03X961447Y95854I1766J-1911D01*
G02X961268Y95640I-199J-15D01*
G03X960003Y95099I231J-2290D01*
G01X959947Y95052D01*
X954404D01*
G37*
%LPC*%
G75*
G54D112*
X235498Y291114D03*
X239998D03*
X235498Y302114D03*
X217298Y310614D03*
X220698D03*
X235498Y335114D03*
X239998D03*
X211898Y343614D03*
X215298D03*
X219699Y1527550D03*
X216299D03*
X234300Y1518900D03*
X238800Y1507900D03*
X234300D03*
X239999Y1551550D03*
X235499D03*
X254900Y1542200D03*
X251500D03*
X290799Y30613D03*
X311499Y38113D03*
X315999D03*
Y71613D03*
X311499D03*
X295699Y63613D03*
X292299D03*
X311600Y322300D03*
X314000D03*
X294300Y328000D03*
X296700D03*
X334298Y332014D03*
X309799Y332950D03*
X334298Y334214D03*
Y336014D03*
X305699Y354950D03*
Y357150D03*
Y358950D03*
Y361150D03*
X308099Y1537950D03*
X310499D03*
X295800Y1548600D03*
X298200D03*
X307799Y1553450D03*
X305699Y1571950D03*
Y1574150D03*
Y1575950D03*
Y1578150D03*
X311600Y316300D03*
X314000D03*
X399699Y57150D03*
X374199Y58150D03*
X388300Y71000D03*
X390700D03*
X368100Y71100D03*
X370500D03*
X382199Y24950D03*
Y27150D03*
Y29450D03*
Y31650D03*
X815399Y158250D03*
X817599D03*
X822899D03*
X825099D03*
X830399D03*
X832599D03*
X778700Y705000D03*
X776300D03*
X756700D03*
X754300D03*
X778799Y727450D03*
X754496Y723782D03*
X778799Y722950D03*
X778700Y711000D03*
X776300D03*
X756700D03*
X754300D03*
X755133Y1125292D03*
X779700Y1112000D03*
X777300D03*
X761700D03*
X759300D03*
Y1106000D03*
X761700D03*
X777300D03*
X779700D03*
X782000Y1511700D03*
X784400D03*
X760800Y1512000D03*
X763200D03*
X758127Y1530196D03*
X763200Y1518000D03*
X760800D03*
X784400Y1517700D03*
X782000D03*
X834599Y1779250D03*
X832399D03*
X825599D03*
X823399D03*
X816099D03*
X813899D03*
X758300Y1918000D03*
X760700D03*
X783300D03*
X785700D03*
X754614Y1936613D03*
X779299Y1933950D03*
X785700Y1924000D03*
X783300D03*
X760700D03*
X758300D03*
X770996Y747282D03*
Y749482D03*
Y751782D03*
Y753982D03*
X771133Y1151292D03*
Y1153492D03*
Y1155792D03*
Y1157992D03*
X773627Y1553696D03*
Y1555896D03*
Y1558196D03*
Y1560396D03*
X771114Y1959613D03*
Y1961813D03*
Y1964113D03*
Y1966313D03*
X864596Y739082D03*
X861196D03*
X841499Y730050D03*
X836999D03*
X841999Y1135050D03*
X837499D03*
X844827Y1539796D03*
X840327D03*
X864000Y1545100D03*
X838999Y1946050D03*
X843499D03*
X862800Y1954900D03*
X866200D03*
X901599Y83750D03*
X899399D03*
X909199Y83550D03*
X903299D03*
X902499Y125750D03*
X902399Y127250D03*
X857396Y704882D03*
X853996D03*
X838446Y696682D03*
X833946D03*
X853996Y713882D03*
X857396D03*
X857033Y1110392D03*
X853633D03*
X838583Y1102192D03*
X859527Y1515296D03*
X856127D03*
X840327Y1507096D03*
Y1496096D03*
X835827D03*
X836064Y1901813D03*
X840564D03*
Y1912813D03*
X859014Y1921113D03*
X855614D03*
X869001Y1714650D03*
X871401D03*
X885901Y1695550D03*
X893100Y1702500D03*
X888600Y1703600D03*
X890800D03*
X877301Y1722050D03*
X884900Y1735900D03*
X890401Y1722050D03*
X901199Y97950D03*
X955999Y97250D03*
G54D116*
X906249Y83550D03*
%LPD*%
G75*
G54D100*
G01X77166Y934685D02*
X83331D01*
X83988Y934028D01*
G01X77166Y1736260D02*
X83209D01*
X84099Y1737150D01*
G01X159055Y1462953D02*
X152512D01*
X152499Y1462940D01*
G01X167200Y1868000D02*
X166735Y1868465D01*
G01D02*
X159055D01*
G01X887401Y246417D02*
X881185D01*
X879878Y247724D01*
G01X887401Y246417D02*
X893917D01*
G54D101*
G01X106999Y1114960D02*
Y1114550D01*
X106099Y1113650D01*
Y1111760D01*
G01X117249Y1714990D02*
Y1712090D01*
G01X140940Y557700D02*
Y561800D01*
G01X156500Y554000D02*
X152500D01*
X148800Y550300D01*
X146060D01*
G01X141300Y565900D02*
X142100D01*
X146060Y561940D01*
Y557700D01*
G01X138416Y553500D02*
Y551884D01*
X140000Y550300D01*
X140940D01*
G01X135850Y1322250D02*
X138140Y1324540D01*
X140000D01*
G01Y1329660D02*
Y1332600D01*
G01X141500Y1715500D02*
X140800Y1714800D01*
X138059D01*
G01X181340Y944500D02*
X170900D01*
X163500Y937100D01*
G01X147400Y1324540D02*
Y1321600D01*
G01X148024Y1333525D02*
X147400Y1332901D01*
Y1329660D01*
G01X176999Y485793D02*
X175793D01*
X173100Y483100D01*
G01X172660Y815731D02*
X172559Y815832D01*
Y820363D01*
G01X212486Y937100D02*
X186460D01*
G01X171000Y939500D02*
X173400Y937100D01*
X181340D01*
G01X170250Y948500D02*
X171250Y949500D01*
X185500D01*
X186500Y948500D01*
Y944540D01*
X186460Y944500D01*
G01X179999Y1652987D02*
Y1655887D01*
G01X187399Y1647867D02*
X192633D01*
X193500Y1647000D01*
G01X181100Y1682700D02*
Y1680100D01*
X179400Y1678400D01*
X177360D01*
G01X172240D02*
Y1679660D01*
X169600Y1682300D01*
G01X172240Y1685800D02*
X169100D01*
G01X177900Y1690400D02*
X177360Y1689860D01*
Y1685800D01*
G01X189199Y831553D02*
Y825101D01*
X195400Y818900D01*
X199100D01*
X200000Y818000D01*
G01X203439Y891800D02*
X202039D01*
X200539Y890300D01*
G01X214999Y939613D02*
X212486Y937100D01*
G01X229800Y1073600D02*
X230320Y1074120D01*
X234600D01*
G01X229025Y1471576D02*
X230689Y1473240D01*
X233600D01*
G01X249600Y1896800D02*
Y1879781D01*
X241919Y1872100D01*
X220400D01*
X218100Y1874400D01*
Y1877840D01*
G01X223436Y1890465D02*
Y1887964D01*
X225500Y1885900D01*
Y1882960D01*
G01X229800Y1875700D02*
X227660Y1877840D01*
X225500D01*
G01X218100Y1882960D02*
Y1886400D01*
G01X242040Y282500D02*
Y287074D01*
X242000Y287114D01*
G01X247160Y275100D02*
X250300D01*
G01X250400Y283100D02*
X249800Y282500D01*
X247160D01*
G01X242040Y275100D02*
Y276160D01*
X239600Y278600D01*
G01X246560Y682500D02*
X249700D01*
G01X241400Y693550D02*
X241440Y693510D01*
Y689900D01*
G01X246560D02*
X249800D01*
G01X233500Y1066100D02*
X234600Y1067200D01*
Y1069000D01*
G01X242000D02*
Y1066000D01*
G01X269500Y1135500D02*
Y1132332D01*
X264300Y1127132D01*
Y1107481D01*
X246319Y1089500D01*
X239786D01*
X237950Y1087664D01*
Y1081050D01*
X242000Y1077000D01*
Y1074120D01*
G01X241000Y1469600D02*
Y1473240D01*
G01X251000Y1504400D02*
Y1495100D01*
X241000Y1485100D01*
Y1478360D01*
G01X233600D02*
Y1481500D01*
X233700Y1481600D01*
G01X277799Y338599D02*
X278939Y337459D01*
Y333800D01*
G01X280689Y1942710D02*
X280699Y1942700D01*
X283589D01*
G01X308999Y87050D02*
X314289Y92340D01*
X317400D01*
G01X315800Y100500D02*
X317400Y98900D01*
Y97460D01*
G01X315939Y352350D02*
X313039D01*
G01X314499Y754550D02*
X316939Y756990D01*
Y759350D01*
G01X312999Y1566050D02*
X315939Y1568990D01*
Y1569850D01*
G01X324800Y92340D02*
Y89400D01*
G01Y97460D02*
X341360D01*
X344450Y100550D01*
G01X329999Y1952273D02*
Y1951550D01*
X327918Y1949469D01*
X326971D01*
G01X324200Y1966472D02*
X327100D01*
G01X315999Y1958550D02*
X316521Y1959072D01*
X319080D01*
G01X343499Y60150D02*
X345339Y61990D01*
X347749D01*
G01X344450Y100550D02*
X345999D01*
G01X386799Y41610D02*
X382339D01*
G01X381999Y50150D02*
X382839Y50990D01*
X387749D01*
G01X398799Y36152D02*
X398461Y36490D01*
X394199D01*
G01X759114Y1954773D02*
Y1957673D01*
G01X767083Y1131452D02*
Y1134550D01*
G01X768199Y1141490D02*
Y1138590D01*
G01X790559Y316110D02*
Y321300D01*
G01X784499Y334050D02*
X785439Y333110D01*
Y327800D01*
G01X784939Y728800D02*
Y733550D01*
G01X789559Y1119110D02*
Y1125300D01*
G01X822100Y264940D02*
Y261700D01*
G01Y270060D02*
Y279500D01*
G01X814700Y264940D02*
X809940D01*
G01X814700Y270060D02*
Y272300D01*
X816700Y274300D01*
G01X820600Y667540D02*
Y664300D01*
G01Y682050D02*
Y672660D01*
G01X813200Y667540D02*
X808660D01*
G01X813200Y672660D02*
Y675900D01*
G01X816000Y1083400D02*
X820300Y1079100D01*
Y1075460D01*
G01X807000Y1072900D02*
X809560Y1070340D01*
X812900D01*
G01X825800Y1072300D02*
X823840Y1070340D01*
X820300D01*
G01X822100Y1470700D02*
Y1466800D01*
G01Y1490900D02*
Y1483160D01*
G01X814700Y1478040D02*
X809960D01*
G01X822100D02*
Y1470700D01*
G01X814700Y1483160D02*
Y1486300D01*
G01X822700Y1871100D02*
Y1875100D01*
G01X817386Y1895000D02*
Y1894114D01*
X822700Y1888800D01*
Y1887560D01*
G01X815300Y1882440D02*
X810900D01*
G01X822700Y1875100D02*
Y1882440D01*
G01X815300Y1887560D02*
X809600D01*
G01D02*
X805900D01*
G54D102*
G01X12379Y309549D02*
X29531D01*
G01X12379Y1029510D02*
X29531D01*
G01X17720Y1885980D02*
Y1903132D01*
G01D02*
X34872D01*
G01X29531Y292397D02*
Y309549D01*
G01D02*
Y326701D01*
G01Y309549D02*
X46683D01*
G01X29531Y1012358D02*
Y1029510D01*
G01D02*
Y1046662D01*
G01Y1029510D02*
X46683D01*
G01X68898Y12645D02*
Y17047D01*
G01D02*
Y21449D01*
G01X62346Y17047D02*
X68898D01*
G01D02*
X75450D01*
G01X68898Y185873D02*
Y190275D01*
G01D02*
Y194677D01*
G01X62346Y190275D02*
X68898D01*
G01D02*
X75450D01*
G01X68898Y418157D02*
Y422559D01*
G01D02*
Y426961D01*
G01X62346Y422559D02*
X68898D01*
G01D02*
X75450D01*
G01X68898Y591385D02*
Y595787D01*
G01D02*
Y600189D01*
G01X62346Y595787D02*
X68898D01*
G01D02*
X75450D01*
G01X68898Y996897D02*
Y1001299D01*
G01D02*
Y1005701D01*
G01X62346Y1001299D02*
X68898D01*
G01D02*
X75450D01*
G01X68898Y1634693D02*
Y1639095D01*
G01D02*
Y1643497D01*
G01X62346Y1639095D02*
X68898D01*
G01X96100Y1384650D02*
X94114Y1382664D01*
X85617D01*
X85630Y1382677D01*
G01X112769Y17716D02*
X129921D01*
G01D02*
X147073D01*
G01X167323Y175401D02*
Y179803D01*
G01D02*
Y184205D01*
G01X160771Y179803D02*
X167323D01*
G01D02*
X173875D01*
G01X167323Y348629D02*
Y353031D01*
G01D02*
Y357433D01*
G01X160771Y353031D02*
X167323D01*
G01D02*
X173875D01*
G01X167323Y580913D02*
Y585315D01*
G01D02*
Y589717D01*
G01X160771Y585315D02*
X167323D01*
G01D02*
X173875D01*
G01X167323Y754141D02*
Y758543D01*
G01D02*
Y762945D01*
G01X160771Y758543D02*
X167323D01*
G01D02*
X173875D01*
G01X167323Y1159653D02*
Y1164055D01*
G01D02*
Y1168457D01*
G01X160771Y1164055D02*
X167323D01*
G01D02*
X173875D01*
G01X167323Y1391937D02*
Y1396339D01*
G01D02*
Y1400741D01*
G01X160771Y1396339D02*
X167323D01*
G01D02*
X173875D01*
G01X167323Y1565165D02*
Y1569567D01*
G01D02*
Y1573969D01*
G01X160771Y1569567D02*
X167323D01*
G01D02*
X173875D01*
G01X167323Y1797449D02*
Y1801851D01*
G01X160771D02*
X167323D01*
G01D02*
X173875D01*
G01X167323Y1970677D02*
Y1975079D01*
G01D02*
Y1979481D01*
G01X160771Y1975079D02*
X167323D01*
G01D02*
X173875D01*
G01X271657Y250547D02*
Y267699D01*
G01X254505D02*
X271657D01*
G01D02*
X288809D01*
G01X271657Y656058D02*
Y673210D01*
G01X254505D02*
X271657D01*
G01D02*
X288809D01*
G01X271657Y1061570D02*
Y1078722D01*
G01D02*
Y1095874D01*
G01Y1078722D02*
X288809D01*
G01X254505Y1484234D02*
X271657D01*
G01D02*
X288809D01*
G01X271657Y1872594D02*
Y1889746D01*
G01D02*
Y1906898D01*
G01X254505Y1889746D02*
X271657D01*
G01D02*
X288809D01*
G01X895669Y175401D02*
Y179803D01*
G01D02*
Y184205D01*
G01X889117Y179803D02*
X895669D01*
G01D02*
X902221D01*
G01X895669Y348629D02*
Y353031D01*
G01D02*
Y357433D01*
G01X889117Y353031D02*
X895669D01*
G01D02*
X902221D01*
G01X895669Y580913D02*
Y585315D01*
G01D02*
Y589717D01*
G01X889117Y585315D02*
X895669D01*
G01D02*
X902221D01*
G01X895669Y754141D02*
Y758543D01*
G01D02*
Y762945D01*
G01X889117Y758543D02*
X895669D01*
G01D02*
X902221D01*
G01X895669Y986425D02*
Y990827D01*
G01D02*
Y995229D01*
G01X889117Y990827D02*
X895669D01*
G01D02*
X902221D01*
G01X895669Y1159653D02*
Y1164055D01*
G01D02*
Y1168457D01*
G01X889117Y1164055D02*
X895669D01*
G01D02*
X902221D01*
G01X895669Y1391937D02*
Y1396339D01*
G01D02*
Y1400741D01*
G01X889117Y1396339D02*
X895669D01*
G01D02*
X902221D01*
G01X895669Y1565165D02*
Y1569567D01*
G01D02*
Y1573969D01*
G01X889117Y1569567D02*
X895669D01*
G01D02*
X902221D01*
G01X895669Y1797449D02*
Y1801851D01*
G01D02*
Y1806253D01*
G01X889117Y1801851D02*
X895669D01*
G01D02*
X902221D01*
G01X895669Y1970677D02*
Y1975079D01*
G01D02*
Y1979481D01*
G01X889117Y1975079D02*
X895669D01*
G01D02*
X902221D01*
G01X976946Y149588D02*
X994098D01*
G01X976946Y673210D02*
X994098D01*
G01X976946Y1068880D02*
X994098D01*
G01X976941Y1889751D02*
X994093D01*
G01X994098Y132436D02*
Y149588D01*
G01D02*
Y166740D01*
G01Y149588D02*
X1011250D01*
G01X994098Y656058D02*
Y673210D01*
G01D02*
Y690362D01*
G01Y673210D02*
X1011250D01*
G01X994098Y1051728D02*
Y1068880D01*
G01D02*
Y1086032D01*
G01Y1068880D02*
X1011250D01*
G01X994093Y1872599D02*
Y1889751D01*
G01D02*
Y1906903D01*
G01Y1889751D02*
X1011245D01*
G54D103*
G01X26299Y383854D02*
X26540Y384094D01*
G03X26099Y385158I-441J441D01*
G01X22182D01*
G03X21068Y384696I0J-1574D01*
G01X21067D01*
G02X19044Y383858I-2023J2023D01*
G01X12575D01*
X12569Y383852D01*
G01Y387789D02*
X12575Y387795D01*
X18881D01*
G02X20849Y386980I0J-2783D01*
G03X22109Y386458I1260J1260D01*
G01X24199D01*
G03X25785Y387115I0J2243D01*
G01X26299Y387629D01*
G01X38999Y372160D02*
X38886Y372047D01*
X12575D01*
X12569Y372041D01*
G01X28100Y374000D02*
X26116Y375984D01*
X12575D01*
X12569Y375978D01*
G01X26299Y399601D02*
Y400009D01*
G03X25402Y400906I-897J0D01*
G01X22096D01*
G03X20842Y400386I1J-1774D01*
G01X20841D01*
G02X18958Y399606I-1883J1883D01*
G01X12575D01*
X12569Y399600D01*
G01Y403537D02*
X18605D01*
X18611Y403543D01*
G02X20451Y402781I0J-2602D01*
G03X21839Y402206I1388J1388D01*
G01X25402D01*
G03X25709Y402333I0J434D01*
G03X26299Y403376I-627J1043D01*
G01X35900Y412600D02*
X34717Y411417D01*
X12575D01*
X12569Y411411D01*
G01Y427161D02*
X17730D01*
X17736Y427167D01*
G02X21398Y425650I0J-5179D01*
G03X21608Y425466I1453J1447D01*
G03X22612Y425050I1004J1004D01*
G01X24854D01*
G03X26524Y426720I0J1670D01*
G01X26399Y423322D02*
G03X25366Y423750I-1033J-1033D01*
G01X22294D01*
G03X21642Y423480I0J-922D01*
G02X21036Y423229I-606J606D01*
G01X12575D01*
X12569Y423223D01*
G01Y438972D02*
X19018D01*
X19024Y438978D01*
G03X20999Y439796I0J2793D01*
G02X22163Y440278I1164J-1164D01*
G01X24999D01*
G02X26492Y439350I0J-1665D01*
G01X12569Y442909D02*
X19037D01*
X19043Y442915D01*
G02X20868Y442159I0J-2581D01*
G03X22271Y441578I1403J1403D01*
G01X24999D01*
G03X26599Y442749I0J1679D01*
G01X12569Y454720D02*
X18476D01*
X18482Y454726D01*
G03X20493Y455559I0J2844D01*
G02X21620Y456026I1127J-1127D01*
G01X25723D01*
G02X26899Y454850I0J-1176D01*
G01X12569Y458657D02*
X18430D01*
X18436Y458663D01*
G02X20476Y457818I0J-2885D01*
G03X21664Y457326I1188J1188D01*
G01X24999D01*
G03X26073Y457771I0J1519D01*
G01X26799Y458497D01*
G01X12569Y470468D02*
X19413D01*
X19419Y470474D01*
G03X20872Y471076I0J2055D01*
G01X21172Y471376D01*
G02X22133Y471774I961J-961D01*
G01X61675D01*
G02X62503Y470946I0J-828D01*
G01X12569Y474405D02*
X19482D01*
X19488Y474411D01*
G02X20965Y473799I0J-2089D01*
G03X22715Y473074I1750J1750D01*
G01X59426D01*
G03X59712Y473083I6J4343D01*
G03X62497Y474346I-286J4334D01*
G01X12569Y486216D02*
X18747D01*
X18753Y486222D01*
G03X20711Y487033I0J2769D01*
G02X21940Y487542I1229J-1229D01*
G01X61653D01*
G02X62978Y486217I0J-1325D01*
G01X12569Y490153D02*
X18956D01*
X18962Y490159D01*
G02X20980Y489323I0J-2854D01*
G03X22141Y488842I1161J1161D01*
G01X62293D01*
G03X63067Y489616I0J774D01*
G01X12569Y501964D02*
X18409D01*
X18415Y501970D01*
G03X20585Y502869I0J3069D01*
G02X21553Y503270I968J-968D01*
G01X25095D01*
G02X26399Y501966I0J-1304D01*
G01X12569Y505901D02*
X18472D01*
X18478Y505907D01*
G02X20455Y505088I0J-2796D01*
G03X21706Y504570I1251J1251D01*
G01X25228D01*
G03X26399Y505741I0J1171D01*
G01X12569Y517712D02*
X19254D01*
X19260Y517718D01*
G03X20931Y518410I0J2363D01*
G03X21199Y518650I-2029J2535D01*
G02X21913Y519005I887J-889D01*
G02X22087Y519018I180J-1243D01*
G01X34499D01*
G02X36499Y517775I0J-2231D01*
G01X12569Y521649D02*
X18908D01*
X18914Y521655D01*
G02X21099Y520750I0J-3090D01*
G03X22142Y520318I1043J1043D01*
G01X28029D01*
G03X28270Y520559I0J241D01*
G02X28511Y520800I241J0D01*
G01X30429D01*
G02X30670Y520559I0J-241D01*
G03X30911Y520318I241J0D01*
G01X34499D01*
G03X36499Y521550I0J2239D01*
G01X60003Y534150D02*
G03X58516Y534766I-1487J-1487D01*
G01X23469D01*
G03X21499Y533950I0J-2786D01*
G02X20331Y533466I-1168J1168D01*
G01X12575D01*
X12569Y533460D01*
G01Y537397D02*
X19135D01*
X19141Y537403D01*
G02X21485Y536432I0J-3315D01*
G03X22369Y536066I884J884D01*
G01X35796D01*
G03X36188Y536458I0J392D01*
G02X36580Y536850I392J0D01*
G01X38196D01*
G02X38588Y536458I0J-392D01*
G03X38980Y536066I392J0D01*
G01X40596D01*
G03X40988Y536458I0J392D01*
G02X41380Y536850I392J0D01*
G01X42996D01*
G02X43388Y536458I0J-392D01*
G03X43780Y536066I392J0D01*
G01X58517D01*
G02X59102Y536015I-2J-3403D01*
G01Y536016D01*
G03X59999Y536771I131J755D01*
G01Y537550D01*
G01X43099Y555850D02*
Y555550D01*
X40449Y552900D01*
X28749D01*
X28498Y553151D01*
X12575D01*
X12569Y553145D01*
G01X46299Y552950D02*
X43699D01*
X39963Y549214D01*
X12575D01*
X12569Y549208D01*
G01X29999Y557150D02*
X29937Y557088D01*
X12575D01*
X12569Y557082D01*
G01X65599Y514250D02*
Y538996D01*
X60845Y543750D01*
X23399D01*
X21872Y545277D01*
X12575D01*
X12569Y545271D01*
G01X33699Y561850D02*
X32874Y561025D01*
X12575D01*
X12569Y561019D01*
G01Y568893D02*
X18476D01*
X18482Y568899D01*
G03X20877Y569891I0J3387D01*
G02X21621Y570199I744J-744D01*
G01X72819D01*
G03X77648Y572199I-1J6831D01*
G01X85149Y579700D01*
G03X86599Y583201I-3503J3502D01*
G01Y651337D01*
G03X85219Y654669I-4714J-1D01*
G01X80619Y659269D01*
Y659270D01*
G02X79977Y660267I1977J1978D01*
G01Y660268D01*
G02X79932Y660393I2608J1009D01*
G02X79816Y660947I2666J847D01*
G01X79680Y662237D01*
G02X79752Y663237I2833J299D01*
G02X80499Y664550I2761J-702D01*
G01X28000Y578500D02*
X25790Y580710D01*
X12575D01*
X12569Y580704D01*
G01Y572830D02*
X18469D01*
X18475Y572836D01*
G02X20527Y571986I0J-2902D01*
G03X21703Y571499I1176J1176D01*
G01X72818D01*
G03X76729Y573119I0J5531D01*
G01X84229Y580619D01*
G03X85299Y583202I-2583J2583D01*
G01Y651336D01*
G03X84299Y653750I-3414J0D01*
G01X79699Y658350D01*
G02X78694Y659996I2896J2898D01*
G01X78687Y660019D01*
G02X78469Y661402I4286J1384D01*
G03X78188Y662674I-5068J-453D01*
G03X76999Y664550I-4789J-1720D01*
G01X53400Y630500D02*
Y598479D01*
X46171Y591250D01*
X27550D01*
X26279Y592521D01*
X12575D01*
X12569Y592515D01*
G01X57400Y610900D02*
Y592000D01*
X50047Y584647D01*
X12575D01*
X12569Y584641D01*
G01X55500Y618500D02*
X55000Y618000D01*
Y597815D01*
X45885Y588700D01*
X27837D01*
X26166Y590371D01*
X22232D01*
X20445Y588584D01*
X12575D01*
X12569Y588578D01*
G01X28586Y600248D02*
X24796Y596458D01*
X12575D01*
X12569Y596452D01*
G01Y600389D02*
X12575Y600395D01*
X23192D01*
X27845Y605048D01*
X28519D01*
G01X34700Y623000D02*
X29499Y617799D01*
Y611653D01*
X25296Y607450D01*
X23253D01*
X22434Y608269D01*
X12575D01*
X12569Y608263D01*
G01Y620074D02*
X18336D01*
X18342Y620080D01*
G03X20486Y620968I0J3032D01*
G02X21481Y621380I995J-995D01*
G01X24657D01*
G02X27499Y620203I0J-4019D01*
G01X26800Y611500D02*
X26094Y612206D01*
X12575D01*
X12569Y612200D01*
G01X31249Y611550D02*
Y611140D01*
X24441Y604332D01*
X12575D01*
X12569Y604326D01*
G01Y624011D02*
X18285D01*
X18291Y624017D01*
G02X20471Y623114I0J-3083D01*
G03X21519Y622680I1048J1048D01*
G01X25161D01*
G03X27143Y623501I-1J2804D01*
G01X27499Y623857D01*
G01X12569Y635822D02*
X18370D01*
X18376Y635828D01*
G03X20445Y636685I0J2926D01*
G02X21512Y637127I1067J-1067D01*
G01X24100D01*
G02X26304Y636214I0J-3117D01*
G01X26568Y635950D01*
G01X12569Y639759D02*
X18303D01*
X18309Y639765D01*
G02X20446Y638880I0J-3022D01*
G03X21540Y638427I1094J1094D01*
G01X24100D01*
G03X26304Y639340I0J3117D01*
G01X26568Y639604D01*
G01X12569Y651570D02*
X18371D01*
X18377Y651576D01*
G03X20441Y652431I0J2919D01*
G02X21515Y652876I1074J-1074D01*
G01X24518D01*
G02X26737Y651957I0J-3138D01*
G01X12569Y655507D02*
X18286D01*
X18292Y655513D01*
G02X20470Y654611I0J-3080D01*
G03X21520Y654176I1050J1050D01*
G01X25596D01*
G03X26499Y654550I0J1277D01*
G03X26999Y655757I-1207J1207D01*
G01Y656550D01*
G01X12569Y667318D02*
X18669D01*
X18675Y667324D01*
G03X20196Y667954I0J2151D01*
G02X21024Y668483I1617J-1619D01*
G01X21028Y668484D01*
G02X21813Y668624I786J-2138D01*
G01X24999D01*
G02X27579Y667556I1J-3648D01*
G01X27687Y667447D01*
G01X12569Y671255D02*
X19494D01*
X19500Y671261D01*
G02X20271Y670941I-1J-1091D01*
G01X20725Y670488D01*
G03X22087Y669924I1362J1362D01*
G01X24999D01*
G03X27579Y670992I1J3648D01*
G01X27687Y671101D01*
G01X12569Y683066D02*
X18894D01*
X18900Y683072D01*
G03X20073Y683558I0J1659D01*
G01X20640Y684125D01*
G02X21134Y684427I877J-880D01*
G02X21519Y684489I388J-1181D01*
G01X23642D01*
G03X28569Y686530I0J6968D01*
G01X37319Y695280D01*
G02X40989Y696800I3670J-3670D01*
G01X47998D01*
G02X50410Y695801I0J-3411D01*
G01X12569Y687003D02*
X19594D01*
X19600Y687009D01*
G02X20268Y686733I1J-944D01*
G01X20600Y686400D01*
X20943Y686058D01*
G03X21591Y685789I649J648D01*
G01X23641D01*
G03X27650Y687449I1J5668D01*
G01X27649D01*
X36399Y696199D01*
X36400D01*
G02X40990Y698100I4589J-4589D01*
G01X47700D01*
G03X50260Y699161I-1J3621D01*
G01X50300Y699200D01*
G01X110500Y790200D02*
X88200D01*
X74250Y804150D01*
X62959D01*
X44247Y785438D01*
X12573D01*
X12560Y785451D01*
G01Y789388D02*
X30913D01*
X32700Y791175D01*
X45721D01*
X51399Y796853D01*
Y799014D01*
X58135Y805750D01*
X75950D01*
X86400Y795300D01*
X110300D01*
X110700Y795700D01*
G01X27299Y783550D02*
X25250Y781501D01*
X12573D01*
X12560Y781514D01*
G01Y813010D02*
X28240D01*
X28700Y812550D01*
X35753D01*
X36353Y813150D01*
X39635D01*
X41785Y811000D01*
X51510D01*
X54260Y813750D01*
X80903D01*
X83953Y810700D01*
X108300D01*
X111000Y813400D01*
X111100D01*
G01X111200Y799450D02*
X111150Y799500D01*
X108800D01*
X107218Y801082D01*
X82882D01*
X76614Y807350D01*
X57350D01*
X45550Y795550D01*
X42750D01*
X40512Y793312D01*
X12573D01*
X12560Y793325D01*
G01Y809073D02*
X12573Y809060D01*
X33561D01*
X36470Y806151D01*
X45751D01*
X48600Y809000D01*
X51773D01*
X54923Y812150D01*
X79903D01*
X83928Y808125D01*
X109125D01*
X111001Y810001D01*
X111207D01*
G01X32800Y803050D02*
X30949Y801199D01*
X12560D01*
G01X40734Y802473D02*
X35923D01*
X33260Y805136D01*
X12560D01*
G01X110800Y803100D02*
X109700Y804200D01*
X82200D01*
X77450Y808950D01*
X56687D01*
X44970Y797233D01*
X12589D01*
X12560Y797262D01*
G01X29299Y836901D02*
X25081Y832683D01*
X12573D01*
X12560Y832696D01*
G01X49900Y813200D02*
X49000Y814100D01*
X40949D01*
X38115Y816934D01*
X12573D01*
X12560Y816947D01*
G01X54074Y815750D02*
X41563D01*
X36429Y820884D01*
X12560D01*
G01X40400Y840792D02*
X29641D01*
X25469Y836620D01*
X12573D01*
X12560Y836633D01*
G01X48346Y844529D02*
X28178D01*
X24206Y840557D01*
X12573D01*
X12560Y840570D01*
G01Y844507D02*
X25478D01*
X27300Y846329D01*
X53821D01*
X66779Y833371D01*
X73244D01*
X77615Y829000D01*
X100949D01*
X106499Y834550D01*
G01X12560Y848444D02*
X12573Y848431D01*
X28770D01*
X29999Y849660D01*
G01X26662Y861550D02*
X25650D01*
X20405Y856305D01*
X12573D01*
X12560Y856318D01*
G01X20999Y1352050D02*
Y1355501D01*
X20201Y1356299D01*
X12575D01*
X12569Y1356293D01*
G01X25000Y1357742D02*
X22506Y1360236D01*
X12575D01*
X12569Y1360230D01*
G01Y1372041D02*
X18441D01*
X18447Y1372047D01*
G02X20262Y1371295I0J-2567D01*
G03X21674Y1370710I1412J1412D01*
G01X23322D01*
G03X24773Y1371311I0J2052D01*
G01X25507Y1372045D01*
G01X12569Y1368104D02*
X19025D01*
X19031Y1368110D01*
G03X20719Y1368809I0J2387D01*
G01X20910Y1369001D01*
G02X21899Y1369410I988J-989D01*
G01X23233D01*
G02X25558Y1368447I0J-3288D01*
G01X12569Y1383852D02*
X19028D01*
X19034Y1383858D01*
G03X20719Y1384556I0J2383D01*
G01X21052Y1384889D01*
G02X21699Y1385157I647J-647D01*
G01X22872D01*
G02X25510Y1384065I1J-3730D01*
G01X25512Y1384062D01*
X27389Y1382185D01*
G02X28273Y1380050I-2136J-2135D01*
G01X28274Y1380051D01*
Y1336625D01*
G02X27937Y1336288I-337J0D01*
G03X27600Y1335951I0J-337D01*
G01Y1334225D01*
G03X27937Y1333888I337J0D01*
G02X28274Y1333551I0J-337D01*
G01Y1331825D01*
G02X27937Y1331488I-337J0D01*
G03X27600Y1331151I0J-337D01*
G01Y1329425D01*
G03X27937Y1329088I337J0D01*
G02X28274Y1328751I0J-337D01*
G01Y1191496D01*
G02X27937Y1191159I-337J0D01*
G01X27936D01*
G03X27599Y1190822I0J-337D01*
G01Y1189096D01*
G03X27936Y1188759I337J0D01*
G01X27937D01*
G02X28274Y1188422I0J-337D01*
G01Y1186696D01*
G02X27937Y1186359I-337J0D01*
G01X27936D01*
G03X27599Y1186022I0J-337D01*
G01Y1184296D01*
G03X27936Y1183959I337J0D01*
G01X27937D01*
G02X28274Y1183622I0J-337D01*
G01Y1097253D01*
G02X27937Y1096916I-337J0D01*
G03X27600Y1096579I0J-337D01*
G01Y1094853D01*
G03X27937Y1094516I337J0D01*
G02X28274Y1094179I0J-337D01*
G01Y1076989D01*
G03X30900Y1070649I8966J0D01*
G01X94731Y1006818D01*
G02X96499Y1002550I-4268J-4268D01*
G01Y973029D01*
G02X95479Y970570I-3479J2D01*
G02X94834Y970302I-646J643D01*
G01X91629D01*
G02X91229Y970702I0J400D01*
G01Y971752D01*
G03X90829Y972152I-400J0D01*
G01X90816Y972165D01*
X85630D01*
G01X12569Y1387789D02*
X18239D01*
X18245Y1387795D01*
G02X20522Y1386852I0J-3220D01*
G03X21476Y1386457I954J954D01*
G01X22872D01*
G02X26489Y1384924I1J-5030D01*
G01X26681Y1384733D01*
X28309Y1383105D01*
G02X29574Y1380050I-3056J-3055D01*
G01Y1076989D01*
G03X31820Y1071569I7666J1D01*
G01X95651Y1007738D01*
G02X97799Y1002550I-5188J-5187D01*
G01Y973030D01*
G02X96399Y969650I-4780J0D01*
G02X94835Y969002I-1564J1564D01*
G01X91629D01*
G03X91229Y968602I0J-400D01*
G01Y967552D01*
G02X90829Y967152I-400J0D01*
G01X90816Y967165D01*
X85630D01*
G01X30500Y1395500D02*
X30331Y1395669D01*
X12575D01*
X12569Y1395663D01*
G01Y1407475D02*
X12575Y1407481D01*
X19730D01*
G03X20329Y1407729I0J847D01*
G01X20500Y1407900D01*
X21149Y1408548D01*
G02X21635Y1408750I487J-486D01*
G02X22257Y1408492I-1J-880D01*
G03X22841Y1408250I584J584D01*
G01X24211D01*
G02X25792Y1407595I0J-2237D01*
G02X26499Y1405888I-1707J-1707D01*
G01Y1405050D01*
G03X27066Y1403683I1934J1D01*
G01X27555Y1403193D01*
X34804Y1395945D01*
Y1395944D01*
X35180Y1395568D01*
G02X35699Y1394317I-1250J-1252D01*
G01Y1081050D01*
G03X38554Y1074155I9750J-1D01*
G01X45579Y1067130D01*
X115957Y996751D01*
G02X117699Y992549I-4200J-4203D01*
G01Y925061D01*
G02X117349Y924711I-350J0D01*
G03X116999Y924361I0J-350D01*
G01Y922661D01*
G03X117349Y922311I350J0D01*
G02X117699Y921961I0J-350D01*
G01Y920261D01*
G02X117349Y919911I-350J0D01*
G03X116999Y919561I0J-350D01*
G01Y917861D01*
G03X117349Y917511I350J0D01*
G02X117699Y917161I0J-350D01*
G01Y915461D01*
G02X117349Y915111I-350J0D01*
G03X116999Y914761I0J-350D01*
G01Y913061D01*
G03X117349Y912711I350J0D01*
G02X117699Y912361I0J-350D01*
G01Y889084D01*
G02X117400Y888785I-299J0D01*
G01X117399D01*
G03X117100Y888486I0J-299D01*
G01Y886684D01*
G03X117399Y886385I299J0D01*
G01X117400D01*
G02X117699Y886086I0J-299D01*
G01Y884284D01*
G02X117400Y883985I-299J0D01*
G01X117399D01*
G03X117100Y883686I0J-299D01*
G01Y881884D01*
G03X117399Y881585I299J0D01*
G01X117400D01*
G02X117699Y881286I0J-299D01*
G01Y761048D01*
X117698Y761049D01*
G02X116426Y757977I-4346J0D01*
G01X93972Y735523D01*
G03X91499Y729549I5974J-5972D01*
G01Y624051D01*
G03X93619Y618929I7242J-2D01*
G01X98122Y614427D01*
X98121Y614426D01*
X98438Y614109D01*
G02X99499Y611551I-2558J-2560D01*
G01Y569662D01*
G02X97679Y565270I-6210J0D01*
G02X96522Y564790I-1157J1155D01*
G01X91629D01*
G02X91229Y565190I0J400D01*
G01Y566240D01*
G03X90829Y566640I-400J0D01*
G01X90816Y566653D01*
X85630D01*
G01X12569Y1411413D02*
X18457D01*
X18463Y1411419D01*
G02X20455Y1410594I0J-2817D01*
G01X20470Y1410578D01*
G03X21205Y1410131I1282J1280D01*
G03X21426Y1410077I540J1730D01*
G03X21751Y1410048I323J1782D01*
G01X22108D01*
G02X22683Y1409810I0J-813D01*
G03X23311Y1409550I628J628D01*
G01X24216D01*
G02X25428Y1409335I0J-3521D01*
G02X26712Y1408515I-1217J-3321D01*
G02X27799Y1405887I-2628J-2626D01*
G01Y1405051D01*
G03X27985Y1404603I634J0D01*
G01X36100Y1396488D01*
G02X36999Y1394318I-2170J-2170D01*
G01Y1081050D01*
G03X39474Y1075075I8450J0D01*
G01X46499Y1068050D01*
X116877Y997671D01*
G02X118999Y992550I-5121J-5122D01*
G01Y761049D01*
G02X117346Y757057I-5647J0D01*
G01X94892Y734603D01*
G03X92800Y729549I5054J-5052D01*
G01X92799Y729550D01*
Y624050D01*
G03X94539Y619849I5941J0D01*
G01X99358Y615029D01*
G02X100799Y611550I-3479J-3479D01*
G01Y569661D01*
G02X98599Y564350I-7511J0D01*
G02X96523Y563490I-2076J2076D01*
G01X91629D01*
G03X91229Y563090I0J-400D01*
G01Y562040D01*
G02X90829Y561640I-400J0D01*
G01X90816Y561653D01*
X85630D01*
G01X12569Y1423224D02*
X18211D01*
X18217Y1423230D01*
G03X20634Y1424231I0J3418D01*
G02X21356Y1424530I722J-722D01*
G01X24499D01*
G02X27913Y1423116I0J-4828D01*
G01X34819Y1416210D01*
G02X35616Y1414286I-1924J-1924D01*
G01Y1408750D01*
G03X37255Y1404795I5595J1D01*
G01X37254Y1404794D01*
X42008Y1400041D01*
G02X43247Y1397050I-2991J-2991D01*
G01Y1084801D01*
G03X46313Y1077395I10473J-2D01*
G01X52079Y1071631D01*
X123641Y1000068D01*
G02X125099Y996550I-3518J-3519D01*
G01Y757050D01*
G02X123994Y754385I-3769J1D01*
G01X101541Y731932D01*
G03X98899Y725549I6384J-6380D01*
G01Y628558D01*
G03X100249Y625301I4608J2D01*
G01X100248Y625300D01*
X100498Y625049D01*
X118916Y606633D01*
X118915Y606632D01*
X118938Y606609D01*
G02X119999Y604051I-2558J-2560D01*
G01Y504048D01*
X119998Y504049D01*
G02X117877Y498928I-7243J0D01*
G01X105814Y486865D01*
G03X104099Y482721I4144J-4142D01*
G01Y433550D01*
G02X102790Y430389I-4471J0D01*
G01X101974Y429573D01*
X101975D01*
G03X100599Y426253I3321J-3322D01*
G01Y424794D01*
G02X100299Y424494I-300J0D01*
G03X99999Y424194I0J-300D01*
G01Y422394D01*
G03X100299Y422094I300J0D01*
G02X100599Y421794I0J-300D01*
G01Y419994D01*
G02X100299Y419694I-300J0D01*
G03X99999Y419394I0J-300D01*
G01Y417594D01*
G03X100299Y417294I300J0D01*
G02X100599Y416994I0J-300D01*
G01Y403449D01*
G02X100350Y403200I-249J0D01*
G01X100349D01*
G03X100100Y402951I0J-249D01*
G01Y401049D01*
G03X100349Y400800I249J0D01*
G01X100350D01*
G02X100599Y400551I0J-249D01*
G01Y398649D01*
G02X100350Y398400I-249J0D01*
G01X100349D01*
G03X100100Y398151I0J-249D01*
G01Y396249D01*
G03X100349Y396000I249J0D01*
G01X100350D01*
G02X100599Y395751I0J-249D01*
G01Y225399D01*
G03X101697Y222748I3748J-1D01*
G01X101696Y222747D01*
X102612Y221832D01*
X102830Y221615D01*
G02X104099Y218550I-3065J-3064D01*
G01Y216511D01*
G02X103800Y216212I-299J0D01*
G01X103799D01*
G03X103500Y215913I0J-299D01*
G01Y214111D01*
G03X103799Y213812I299J0D01*
G01X103800D01*
G02X104099Y213513I0J-299D01*
G01Y211711D01*
G02X103800Y211412I-299J0D01*
G01X103799D01*
G03X103500Y211113I0J-299D01*
G01Y209311D01*
G03X103799Y209012I299J0D01*
G01X103800D01*
G02X104099Y208713I0J-299D01*
G01Y163150D01*
G02X102755Y159907I-4587J1D01*
G01X102499Y159650D01*
G02X101601Y159278I-898J898D01*
G01X91629D01*
G02X91229Y159678I0J400D01*
G01Y160728D01*
G03X90829Y161128I-400J0D01*
G01X90816Y161141D01*
X85630D01*
G01X12569Y1427161D02*
X18209D01*
X18215Y1427167D01*
G02X20557Y1426197I0J-3312D01*
G03X21443Y1425830I886J886D01*
G01X24498D01*
G02X28833Y1424036I2J-6129D01*
G01X28909Y1423960D01*
X28908Y1423959D01*
X34908Y1417959D01*
X35203Y1417663D01*
X35737Y1417129D01*
X35738D01*
G02X36916Y1414287I-2843J-2844D01*
G01Y1408751D01*
G03X38174Y1405714I4295J0D01*
G01X42678Y1401210D01*
X42679D01*
X42928Y1400961D01*
G02X44547Y1397051I-3912J-3910D01*
G01Y1084801D01*
G03X47233Y1078315I9172J-1D01*
G01X52999Y1072551D01*
X124561Y1000988D01*
G02X126399Y996551I-4438J-4438D01*
G01Y757050D01*
G02X124914Y753465I-5070J0D01*
G01X102461Y731012D01*
G03X100200Y725549I5464J-5461D01*
G01X100199Y725550D01*
Y628559D01*
G03X101168Y626220I3308J0D01*
G01X119858Y607529D01*
G02X121299Y604050I-3479J-3479D01*
G01Y504049D01*
G02X118797Y498008I-8544J0D01*
G01X106734Y485945D01*
G03X105399Y482722I3223J-3223D01*
G01Y433551D01*
G02X103710Y429469I-5772J-2D01*
G01X103645Y429404D01*
X103644D01*
X102894Y428654D01*
G03X101899Y426252I2402J-2402D01*
G01Y225298D01*
G03X102544Y223741I2202J0D01*
G01X103749Y222536D01*
G02X105399Y218550I-3985J-3984D01*
G01Y163150D01*
X105398D01*
G02X103676Y158988I-5887J-2D01*
G01X103420Y158731D01*
G02X101602Y157978I-1818J1818D01*
G01X91629D01*
G03X91229Y157578I0J-400D01*
G01Y156528D01*
G02X90829Y156128I-400J0D01*
G01X90816Y156141D01*
X85630D01*
G01X12569Y1442909D02*
X18287D01*
X18293Y1442915D01*
G02X20471Y1442013I0J-3080D01*
G03X21521Y1441578I1050J1050D01*
G01X31256D01*
G02X33909Y1440480I0J-3754D01*
G01X42181Y1432207D01*
G02X44316Y1427049I-5157J-5156D01*
G01Y1412875D01*
G03X45635Y1409691I4503J0D01*
G01X46046Y1409280D01*
X46045Y1409279D01*
X46885Y1408437D01*
X50126Y1405197D01*
Y1405196D01*
X50522Y1404800D01*
G02X51944Y1401367I-3433J-3433D01*
G01X51947Y1401364D01*
Y1088050D01*
G03X54385Y1082164I8324J0D01*
G01X59499Y1077050D01*
X131184Y1005364D01*
G02X133799Y999051I-6314J-6314D01*
G01Y752550D01*
G02X132712Y749923I-3715J-1D01*
G01X109904Y727115D01*
G03X107600Y721549I5566J-5564D01*
G01X107599Y721550D01*
Y632301D01*
G03X108669Y629718I3653J0D01*
G01X126918Y611469D01*
G02X128700Y607167I-4302J-4302D01*
G01Y497982D01*
G02X127590Y495302I-3791J0D01*
G01X116870Y484582D01*
G03X115200Y480550I4032J-4032D01*
G01Y229050D01*
G03X117499Y225050I4629J0D01*
G01X117520Y225029D01*
G02X117538Y225012I-265J-299D01*
G01X127983Y214567D01*
G03X134000Y212074I6017J6015D01*
G01X144590D01*
G03X144990Y212474I0J400D01*
G01Y213524D01*
G02X145390Y213924I400J0D01*
G01X145403Y213937D01*
X150591D01*
G01X12569Y1438972D02*
X18298D01*
X18304Y1438978D01*
G03X20535Y1439902I0J3155D01*
G02X21443Y1440278I908J-908D01*
G01X31256D01*
G02X32987Y1439561I0J-2448D01*
G01X41261Y1431287D01*
G02X43016Y1427050I-4237J-4237D01*
G01Y1412872D01*
G03X44716Y1408768I5804J0D01*
G01X49207Y1404277D01*
X49604Y1403881D01*
G02X50647Y1401363I-2518J-2518D01*
G01Y1088050D01*
G03X53465Y1081244I9625J-1D01*
G01X58579Y1076130D01*
X130264Y1004444D01*
G02X132499Y999050I-5394J-5395D01*
G01Y752550D01*
G02X131792Y750843I-2414J0D01*
G01X108984Y728035D01*
G03X106299Y721549I6486J-6484D01*
G01Y632300D01*
G03X107749Y628798I4954J0D01*
G01X108279Y628268D01*
Y628269D01*
X125998Y610549D01*
X125999Y610550D01*
G02X127400Y607166I-3383J-3383D01*
G01Y497983D01*
G02X126670Y496222I-2491J1D01*
G01X115950Y485502D01*
G03X113900Y480549I4953J-4951D01*
G01Y229050D01*
G03X116691Y224019I5930J0D01*
G01X127063Y213647D01*
G03X133999Y210774I6936J6936D01*
G01X144590D01*
G02X144990Y210374I0J-400D01*
G01Y209324D01*
G03X145390Y208924I400J0D01*
G01X145403Y208937D01*
X150591D01*
G01X12569Y1458657D02*
X19265D01*
X19271Y1458663D01*
G02X21217Y1457857I0J-2752D01*
G03X22504Y1457356I1475J1885D01*
G03X22691Y1457349I183J2386D01*
G01X29500D01*
G02X33835Y1455554I0J-6132D01*
G01X33919Y1455470D01*
X33918Y1455469D01*
X49668Y1439719D01*
X50003Y1439385D01*
G02X51716Y1435249I-4136J-4136D01*
G01Y1416415D01*
G03X53370Y1412422I5647J0D01*
G01X53371Y1412423D01*
X54290Y1411503D01*
X54289Y1411502D01*
X57221Y1408571D01*
X57220Y1408570D01*
G02X59347Y1403437I-5134J-5135D01*
G01Y1091050D01*
G03X61122Y1086768I6055J1D01*
G01X66918Y1080970D01*
X138274Y1009614D01*
G02X141199Y1002551I-7065J-7063D01*
G01Y749507D01*
G02X139603Y745654I-5449J0D01*
G01X116767Y722818D01*
G03X114999Y718552I4268J-4268D01*
G01Y636042D01*
G03X116168Y633220I3991J0D01*
G01X122544Y626844D01*
Y626843D01*
X126143Y623244D01*
X126144D01*
X130168Y619220D01*
G03X134113Y617586I3945J3945D01*
G01X144590D01*
G03X144990Y617986I0J400D01*
G01Y619036D01*
G02X145390Y619436I400J0D01*
G01X145403Y619449D01*
X150591D01*
G01X12569Y1454720D02*
X19202D01*
X19208Y1454726D01*
G03X20782Y1455378I0J2226D01*
G02X21597Y1455902I1614J-1615D01*
G01X21602Y1455904D01*
G02X22402Y1456049I802J-2146D01*
G01X29499D01*
G02X32915Y1454634I0J-4831D01*
G01X49083Y1438465D01*
X49084Y1438466D01*
G02X50415Y1435249I-3218J-3215D01*
G01X50416Y1435250D01*
Y1416414D01*
G03X52451Y1411503I6947J1D01*
G01X52450Y1411502D01*
X56301Y1407651D01*
Y1407650D01*
G02X58047Y1403436I-4215J-4215D01*
G01Y1091049D01*
G03X60202Y1085848I7356J1D01*
G01X65998Y1080050D01*
X137354Y1008694D01*
G02X139899Y1002550I-6144J-6144D01*
G01Y749507D01*
G02X138683Y746574I-4148J1D01*
G01X115847Y723738D01*
G03X113699Y718551I5189J-5187D01*
G01Y636041D01*
G03X115249Y632301I5291J2D01*
G01X115248Y632300D01*
X129248Y618300D01*
X129249Y618301D01*
G03X134114Y616286I4864J4864D01*
G01X144590D01*
G02X144990Y615886I0J-400D01*
G01Y614836D01*
G03X145390Y614436I400J0D01*
G01X145403Y614449D01*
X150591D01*
G01X12569Y1490153D02*
X18712D01*
X18718Y1490159D01*
G02X20978Y1489223I0J-3196D01*
G03X21881Y1488849I903J903D01*
G01X27316D01*
G03X27541Y1489074I0J225D01*
G01Y1489075D01*
G02X27766Y1489300I225J0D01*
G01X29716D01*
G02X29941Y1489075I0J-225D01*
G01Y1489074D01*
G03X30166Y1488849I225J0D01*
G01X31656D01*
G02X35999Y1487050I0J-6142D01*
G01X80453Y1442595D01*
G02X82749Y1437051I-5545J-5544D01*
G01Y1426259D01*
G03X84494Y1422046I5958J0D01*
G01X95826Y1410714D01*
Y1410713D01*
X211991Y1294542D01*
G02X212018Y1294517I-311J-364D01*
G02X214131Y1291714I-7964J-8201D01*
G01X214132D01*
X214287Y1291427D01*
X214286D01*
X767356Y262675D01*
Y262674D01*
G03X770002Y260069I5539J2980D01*
G01X791356Y249452D01*
X836007Y227247D01*
X869979Y212832D01*
Y212831D01*
X870585Y212573D01*
X871191Y212317D01*
X871195Y212315D01*
X871336Y212255D01*
X871392Y212231D01*
G03X872371Y212421I349J820D01*
G01X872499Y212550D01*
X873494Y213545D01*
G02X874409Y213924I915J-915D01*
G01X874422Y213937D01*
X878937D01*
G01X12569Y1486216D02*
X18744D01*
X18750Y1486222D01*
G03X20865Y1487098I0J2991D01*
G02X21954Y1487549I1089J-1089D01*
G01X31655D01*
G02X35080Y1486130I0J-4842D01*
G01X79532Y1441678D01*
G02X81449Y1437050I-4628J-4628D01*
G01Y1426259D01*
G03X83575Y1421126I7259J0D01*
G01X94526Y1410175D01*
X94525Y1410174D01*
X94906Y1409794D01*
Y1409793D01*
X206324Y1298375D01*
X207324Y1297376D01*
X207323D01*
X207704Y1296995D01*
Y1296987D01*
X207986Y1296705D01*
X207988D01*
X211071Y1293622D01*
G02X212985Y1291100I-7014J-7310D01*
G01X213140Y1290811D01*
X766211Y262059D01*
Y262058D01*
X766212Y262059D01*
G03X769405Y258914I6685J3593D01*
G03X769746Y258744I5594J10794D01*
G01X835499Y226050D01*
X869147Y211770D01*
X869470Y211634D01*
X869472Y211632D01*
X870684Y211121D01*
Y211120D01*
X870685Y211119D01*
X870828Y211057D01*
X870875Y211038D01*
X870878Y211037D01*
X870881Y211035D01*
X871140Y210925D01*
X871141D01*
X871143Y210924D01*
X871380Y210824D01*
X871527Y210761D01*
X871719Y210681D01*
X871998Y210565D01*
G02X872003Y210562I-882J-1476D01*
G02X872022Y210554I-662J-1599D01*
G02X872040Y210546I-694J-1587D01*
G02X872076Y210529I-722J-1575D01*
G02X872137Y210499I-734J-1569D01*
G01X872436Y210343D01*
G02X872899Y209577I-401J-765D01*
G03X873060Y209188I550J0D01*
G03X873699Y208924I638J639D01*
G01X873712Y208937D01*
X878937D01*
G01X12569Y1470468D02*
X19241D01*
X19247Y1470474D01*
G03X21000Y1471200I0J2479D01*
G02X21381Y1471477I1073J-1075D01*
G01X21602Y1471591D01*
G02X22380Y1471779I778J-1516D01*
G01X31599D01*
G02X35579Y1470130I0J-5627D01*
G01X56417Y1449292D01*
G02X58381Y1444550I-4742J-4742D01*
G01Y1419310D01*
G03X60249Y1414800I6377J-1D01*
G01X61925Y1413123D01*
X62924Y1412124D01*
X62925Y1412125D01*
G03X65774Y1410944I2851J2850D01*
G01X71478D01*
G02X73399Y1410148I0J-2715D01*
G01X74604Y1408943D01*
G02X75243Y1407400I-1543J-1543D01*
G01Y1405000D01*
G02X74664Y1403603I-1975J0D01*
G01X68630Y1397569D01*
G03X65999Y1391217I6354J-6353D01*
G01Y1250153D01*
G03X68079Y1245131I7102J0D01*
G01X75264Y1237946D01*
G02X76134Y1235848I-2098J-2099D01*
G01Y1235802D01*
X76155Y1235502D01*
X76193Y1234968D01*
X76184Y1234959D01*
G02X76199Y1234550I-5926J-422D01*
G01Y1230550D01*
G02X74573Y1226624I-5553J0D01*
G01X67748Y1219799D01*
G03X65899Y1215335I4466J-4465D01*
G01Y1093765D01*
G03X67748Y1089300I6316J0D01*
G01X132601Y1024447D01*
G03X139000Y1021798I6397J6399D01*
G01X144590D01*
G02X144990Y1021398I0J-400D01*
G01Y1020348D01*
G03X145390Y1019948I400J0D01*
G01X145403Y1019961D01*
X150591D01*
G01X12569Y1474405D02*
X19377D01*
X19383Y1474411D01*
G02X21273Y1473628I0J-2673D01*
G03X22597Y1473079I1324J1322D01*
G03X22599I1J1736D01*
G01X31600D01*
G02X36498Y1471050I0J-6927D01*
G01X57337Y1450210D01*
G02X59681Y1444551I-5659J-5659D01*
G01Y1419310D01*
G03X61168Y1415720I5077J0D01*
G01X63844Y1413044D01*
G03X65775Y1412244I1931J1931D01*
G01X71479D01*
G02X74318Y1411068I0J-4015D01*
G01X75492Y1409893D01*
X75493Y1409894D01*
X75524Y1409863D01*
G02X76543Y1407399I-2464J-2462D01*
G01Y1404999D01*
G02X75584Y1402683I-3276J0D01*
G01X75200Y1402299D01*
X75199D01*
X69550Y1396650D01*
G03X67299Y1391216I5434J-5434D01*
G01Y1250152D01*
X67300Y1250153D01*
G03X68998Y1246051I5802J-1D01*
G01X68999D01*
X76184Y1238866D01*
G02X77434Y1235848I-3018J-3018D01*
G01X77490Y1235057D01*
X77499Y1235050D01*
Y1230549D01*
G02X75493Y1225704I-6854J0D01*
G01X75419Y1225630D01*
X75418D01*
X68668Y1218880D01*
G03X67199Y1215334I3546J-3546D01*
G01Y1093766D01*
G03X68668Y1090220I5015J0D01*
G01X133521Y1025367D01*
G03X138999Y1023098I5478J5478D01*
G01X144590D01*
G03X144990Y1023498I0J400D01*
G01Y1024548D01*
G02X145390Y1024948I400J0D01*
G01X145403Y1024961D01*
X150591D01*
G01X12569Y1501964D02*
X18468D01*
X18474Y1501970D01*
G03X20751Y1502913I0J3220D01*
G02X21613Y1503270I862J-862D01*
G01X36768D01*
G02X40200Y1501849I1J-4853D01*
G01Y1501847D01*
X40648Y1501399D01*
X40649D01*
X87474Y1454574D01*
G02X89349Y1450049I-4523J-4525D01*
G01Y1429948D01*
G03Y1429946I9048J-1D01*
G03X91998Y1423549I9046J-1D01*
G01X92303Y1423246D01*
X239352Y1276197D01*
X770761Y617961D01*
G03X774992Y616294I5621J8064D01*
G01X774999Y616293D01*
Y616286D01*
X872574D01*
G02X873499Y615361I0J-925D01*
G03X874424Y614436I925J0D01*
G01X874437Y614449D01*
X878937D01*
G01X12569Y1505901D02*
X18420D01*
X18426Y1505907D01*
G02X20724Y1504955I0J-3250D01*
G03X21653Y1504570I929J929D01*
G01X36768D01*
G02X41120Y1502768I1J-6153D01*
G01X88394Y1455494D01*
G02X90649Y1450050I-5444J-5444D01*
G01Y1429947D01*
X90650Y1429948D01*
G03X92918Y1424470I7748J-1D01*
G01X240321Y1277068D01*
X771775Y618779D01*
G03X774302Y617753I4930J8519D01*
G03X775141Y617586I2083J8272D01*
G01X872074D01*
G03X872999Y618511I0J925D01*
G02X873924Y619436I925J0D01*
G01X873937Y619449D01*
X878937D01*
G01X29631Y1533063D02*
X26097Y1529529D01*
X12575D01*
X12569Y1529523D01*
G01Y1517712D02*
X19231D01*
X19237Y1517718D01*
G03X20826Y1518376I0J2247D01*
G02X21947Y1518975I1549J-1551D01*
G02X22376Y1519018I432J-2149D01*
G01X29999D01*
G02X30298Y1518995I-3J-1999D01*
G02X31416Y1518429I-304J-1987D01*
G01X31999Y1517846D01*
G01X12569Y1521649D02*
X19210D01*
X19216Y1521655D01*
G02X20930Y1520945I0J-2424D01*
G03X22444Y1520318I1514J1514D01*
G01X29999D01*
G03X31396Y1520896I1J1975D01*
G01X31999Y1521500D01*
G01X12569Y1553145D02*
X18461D01*
X18467Y1553151D01*
G03X20628Y1554046I0J3056D01*
G02X21606Y1554451I978J-978D01*
G01X24104D01*
G02X25801Y1553748I0J-2400D01*
G01X39878Y1539671D01*
G02X40581Y1537974I-1697J-1697D01*
G01Y1517888D01*
G03X42999Y1512050I8255J-1D01*
G01X94999Y1460050D01*
G02X96749Y1455825I-4225J-4225D01*
G01Y1432436D01*
G03X98984Y1427035I7643J0D01*
G01X100054Y1425965D01*
X100055Y1425963D01*
X101934Y1424084D01*
X104984Y1421035D01*
X252743Y1273275D01*
X255889Y1270127D01*
X255891Y1270129D01*
G03X259729Y1267363I10435J10433D01*
G03X259947Y1267269I942J1884D01*
G01X857646Y1022247D01*
G03X860442Y1021798I2358J5754D01*
G01X872074D01*
G02X872999Y1020873I0J-925D01*
G03X873924Y1019948I925J0D01*
G01X873937Y1019961D01*
X878937D01*
G01X37999Y1530900D02*
X35900Y1532999D01*
Y1535200D01*
X29760Y1541340D01*
X12575D01*
X12569Y1541334D01*
G01X32099Y1535550D02*
X30246Y1537403D01*
X12575D01*
X12569Y1537397D01*
G01X26705Y1534795D02*
X25376Y1533466D01*
X12575D01*
X12569Y1533460D01*
G01X30199Y1545450D02*
X29260Y1544511D01*
X24253D01*
X23487Y1545277D01*
X12575D01*
X12569Y1545271D01*
G01X25521Y1563350D02*
X23909Y1564962D01*
X12575D01*
X12569Y1564956D01*
G01Y1557082D02*
X18892D01*
X18898Y1557088D01*
G02X21131Y1556163I0J-3158D01*
G03X22126Y1555751I995J995D01*
G01X24104D01*
G02X26721Y1554668I1J-3700D01*
G01X40798Y1540591D01*
G02X41881Y1537974I-2617J-2616D01*
G01Y1517888D01*
G03X43918Y1512970I6955J0D01*
G01X95918Y1460970D01*
G02X98049Y1455825I-5144J-5144D01*
G01Y1432435D01*
G03X99904Y1427955I6337J0D01*
G01X100976Y1426883D01*
X100977Y1426881D01*
X102854Y1425004D01*
X105904Y1421955D01*
X253663Y1274195D01*
X256810Y1271048D01*
G03X260310Y1268526I9515J9515D01*
G01X858139Y1023450D01*
X858138Y1023449D01*
G03X860351Y1023095I1863J4553D01*
G01X860396Y1023098D01*
X872074D01*
G03X872999Y1024023I0J925D01*
G02X873924Y1024948I925J0D01*
G01X873937Y1024961D01*
X878937D01*
G01X12569Y1568893D02*
X12575Y1568899D01*
X20099D01*
X21047Y1569847D01*
Y1572638D01*
X24019Y1575610D01*
X31939D01*
X34999Y1572550D01*
G01X12569Y1572830D02*
X18975D01*
X23355Y1577210D01*
X35285D01*
X38995Y1573500D01*
X39000D01*
G01X38499Y1601050D02*
X37050D01*
X33751Y1597751D01*
X30105D01*
X24104Y1591750D01*
X21900D01*
X21129Y1592521D01*
X12575D01*
X12569Y1592515D01*
G01Y1576767D02*
X12575Y1576773D01*
X20655D01*
X22692Y1578810D01*
X36271D01*
X40881Y1574200D01*
Y1572432D01*
X38290Y1569841D01*
X38208D01*
G01X30499Y1588610D02*
X30473Y1588584D01*
X12575D01*
X12569Y1588578D01*
G01X63014Y1560986D02*
X43290Y1580710D01*
X12575D01*
X12569Y1580704D01*
G01X60172Y1566828D02*
X42370Y1584630D01*
X26822D01*
X26805Y1584647D01*
X12575D01*
X12569Y1584641D01*
G01Y1604326D02*
X18642D01*
X18648Y1604332D01*
G03X20681Y1605174I0J2875D01*
G02X21586Y1605549I905J-905D01*
G01X322999D01*
G02X326771Y1604947I0J-12118D01*
G01X734308Y1466189D01*
X847257Y1427733D01*
G03X849999Y1427310I2742J8676D01*
G01X872399D01*
G02X872999Y1426710I0J-600D01*
G01Y1426060D01*
G03X873599Y1425460I600J0D01*
G01X873612Y1425473D01*
X878937D01*
G01X12569Y1608263D02*
X18299D01*
X18305Y1608269D01*
G02X20731Y1607264I0J-3431D01*
G01X20732Y1607263D01*
G03X21656Y1606851I999J998D01*
G03X21733Y1606849I75J1415D01*
G01X322999D01*
G02X327175Y1606183I1J-13418D01*
G02X327305Y1606139I-2144J-6549D01*
G01X734728Y1467421D01*
X847583Y1428996D01*
G03X849999Y1428610I2416J7368D01*
G01X872399D01*
G03X872999Y1429210I0J600D01*
G01Y1429860D01*
G02X873599Y1430460I600J0D01*
G01X873612Y1430473D01*
X878937D01*
G01X33599Y1600200D02*
X27386D01*
X23644Y1596458D01*
X12575D01*
X12569Y1596452D01*
G01Y1635822D02*
X18355D01*
X18361Y1635828D01*
G03X20464Y1636699I0J2974D01*
G02X21500Y1637128I1036J-1036D01*
G01X38937D01*
G03X43169Y1638881I0J5985D01*
G01X59418Y1655130D01*
X60398Y1656108D01*
G03X62249Y1660581I-4474J4471D01*
G01Y1811237D01*
G02X63414Y1814576I5370J-1D01*
G01X66750Y1817913D01*
G02X69774Y1819166I3025J-3024D01*
G01X124599D01*
G02X128498Y1817550I-1J-5514D01*
G01X135876Y1810172D01*
G03X142930Y1807250I7054J7054D01*
G01X258262D01*
G03X265840Y1810389I0J10717D01*
G03X265842Y1810391I-7582J7584D01*
G01X285317Y1829866D01*
G02X292480Y1832833I7163J-7163D01*
G01X871216D01*
G02X871321Y1832825I-7J-782D01*
G02X871999Y1832050I-104J-775D01*
G01Y1831472D01*
G03X872499Y1830972I500J0D01*
G01X878924D01*
X878937Y1830985D01*
G01X12569Y1620074D02*
X18524D01*
X18530Y1620080D01*
G03X20683Y1620972I0J3045D01*
G02X21668Y1621380I985J-985D01*
G01X72719D01*
G03X78199Y1623650I0J7750D01*
G03X79578Y1626979I-3329J3329D01*
G01Y1638551D01*
G03X77725Y1643023I-6325J-1D01*
G01X73820Y1646928D01*
G02X73262Y1647519I10069J10066D01*
G01X73259Y1647522D01*
G02X69649Y1656996I10626J9474D01*
G01Y1684667D01*
G02X70024Y1685042I375J0D01*
G01X70025D01*
G03X70400Y1685417I0J375D01*
G01Y1687067D01*
G03X70025Y1687442I-375J0D01*
G01X70024D01*
G02X69649Y1687817I0J375D01*
G01Y1689467D01*
G02X70024Y1689842I375J0D01*
G01X70025D01*
G03X70400Y1690217I0J375D01*
G01Y1691867D01*
G03X70025Y1692242I-375J0D01*
G01X70024D01*
G02X69649Y1692617I0J375D01*
G01Y1705431D01*
G02X70074Y1705856I425J0D01*
G03X70499Y1706281I0J425D01*
G01Y1707831D01*
G03X70074Y1708256I-425J0D01*
G02X69649Y1708681I0J425D01*
G01Y1710231D01*
G02X70074Y1710656I425J0D01*
G03X70499Y1711081I0J425D01*
G01Y1712631D01*
G03X70074Y1713056I-425J0D01*
G02X69649Y1713481I0J425D01*
G01Y1714094D01*
G02X70049Y1714494I400J0D01*
G03X70449Y1714894I0J400D01*
G01Y1716494D01*
G03X70049Y1716894I-400J0D01*
G02X69649Y1717294I0J400D01*
G01Y1780791D01*
G02X72413Y1787464I9437J0D01*
G01X75999Y1791050D01*
X76377Y1791429D01*
G02X81499Y1793550I5121J-5122D01*
G01X87106D01*
G02X90507Y1792442I-1J-5778D01*
G02X91191Y1791857I-3403J-4671D01*
G01X95498Y1787550D01*
X96001Y1787046D01*
Y1787045D01*
G02X96498Y1785845I-1200J-1200D01*
G01X96499Y1785846D01*
Y1782799D01*
X96498Y1782800D01*
G02X95909Y1781738I-1250J-1D01*
G01X95869Y1781715D01*
G02X95240Y1781550I-621J1085D01*
G01X93248D01*
G02X92823Y1781726I0J601D01*
G01X91799Y1782750D01*
G03X90771Y1783176I-1028J-1028D01*
G01X90758Y1783189D01*
X85630D01*
G01X12569Y1624011D02*
X18371D01*
X18377Y1624017D01*
G02X20777Y1623023I0J-3394D01*
G03X21605Y1622680I828J828D01*
G01X72718D01*
G03X77279Y1624570I0J6449D01*
G03X78278Y1626980I-2408J2410D01*
G01Y1638551D01*
G03X76805Y1642103I-5024J-2D01*
G01X72900Y1646008D01*
G02X68349Y1656995I10987J10987D01*
G01Y1780791D01*
G02X71493Y1788384I10738J1D01*
G01X75457Y1792348D01*
G02X81499Y1794849I6040J-6042D01*
G01Y1794850D01*
X87106D01*
G02X92111Y1792777I1J-7076D01*
G01X96418Y1788469D01*
X96921Y1787965D01*
G02X97799Y1785845I-2120J-2120D01*
G01Y1782800D01*
G02X96514Y1780585I-2550J-1D01*
G01Y1780586D01*
G02X95231Y1780250I-1265J2214D01*
G01X92536D01*
G03X91499Y1779213I0J-1037D01*
G02X90462Y1778176I-1037J0D01*
G01X90449Y1778189D01*
X85630D01*
G01X12569Y1651570D02*
X18558D01*
X18564Y1651576D01*
G03X20638Y1652435I0J2933D01*
G02X21703Y1652876I1065J-1065D01*
G01X35575D01*
G03X38472Y1654076I0J4097D01*
G01X51972Y1667576D01*
G03X54849Y1674522I-6946J6946D01*
G01Y1846236D01*
G02X57035Y1851513I7463J0D01*
G01X59535Y1854013D01*
G02X62842Y1855383I3307J-3307D01*
G01X88040D01*
G02X94628Y1852654I0J-9317D01*
G01X111615Y1835666D01*
X111616Y1835667D01*
G03X118485Y1832822I6868J6868D01*
G01X143899D01*
G02X143927Y1832821I-7J-600D01*
G02X143929I1J-600D01*
G02X144090Y1832790I-32J-599D01*
G01X144091D01*
Y1832789D01*
G02X144499Y1832222I-190J-567D01*
G01Y1831572D01*
G03X145099Y1830972I600J0D01*
G01X145112Y1830985D01*
X150591D01*
G01X12569Y1655507D02*
X18560D01*
X18566Y1655513D01*
G02X20555Y1654689I0J-2813D01*
G01X20556D01*
G03X21793Y1654176I1238J1237D01*
G01X35697D01*
G03X37465Y1654908I0J2501D01*
G01X51053Y1668496D01*
G03X53549Y1674522I-6026J6026D01*
G01Y1846237D01*
G02X56115Y1852432I8763J-1D01*
G01X58615Y1854932D01*
X58616D01*
G02X62841Y1856683I4227J-4226D01*
G01X88041D01*
G02X95547Y1853574I-1J-10617D01*
G01X112535Y1836586D01*
G03X118484Y1834122I5949J5949D01*
G01X144457D01*
G03X144999Y1834664I0J542D01*
G01Y1835372D01*
G02X145599Y1835972I600J0D01*
G01X145612Y1835985D01*
X150591D01*
G01X12569Y1639759D02*
X18211D01*
X18217Y1639765D01*
G02X20556Y1638796I0J-3308D01*
G03X21444Y1638428I888J888D01*
G01X38936D01*
G03X42249Y1639801I0J4684D01*
G01X58499Y1656050D01*
X59479Y1657028D01*
G03X60949Y1660577I-3549J3549D01*
G01Y1811238D01*
G02X62444Y1815446I6671J0D01*
G01X65830Y1818833D01*
G02X69774Y1820466I3943J-3944D01*
G01X124599D01*
G02X129418Y1818470I0J-6815D01*
G01X136796Y1811092D01*
G03X142931Y1808550I6135J6133D01*
G01X258261D01*
G03X264920Y1811309I0J9416D01*
G03X264922Y1811311I-6662J6664D01*
G01X284397Y1830786D01*
G02X292463Y1834127I8066J-8066D01*
G01X292961D01*
G02X293356Y1834133I403J-13543D01*
G01X871582D01*
G03X871999Y1834550I0J417D01*
G01Y1835550D01*
G02X872421Y1835972I422J0D01*
G01X872434Y1835985D01*
X878937D01*
G01X47000Y1737100D02*
X46195Y1736295D01*
G03X45700Y1735100I1195J-1195D01*
G01Y1734600D01*
G02X43900Y1732800I-1800J0D01*
G01X42507D01*
G03X41300Y1732300I0J-1707D01*
G01X39861Y1730860D01*
G03X38800Y1728300I2560J-2561D01*
G01Y1685156D01*
G02X37319Y1681580I-5056J-1D01*
G01X25697Y1669958D01*
G02X23500Y1669050I-2195J2200D01*
G01Y1669049D01*
X22589D01*
G03X22235Y1669006I1J-1489D01*
G03X21536Y1668613I353J-1446D01*
G01X20733Y1667810D01*
G02X19560Y1667324I-1173J1173D01*
G01X12575D01*
X12569Y1667318D01*
G01Y1671255D02*
X12575Y1671261D01*
X20338D01*
G02X20763Y1671085I0J-601D01*
G01X21198Y1670650D01*
X21199D01*
G03X21926Y1670349I727J727D01*
G01X23500D01*
G03X24778Y1670879I-1J1808D01*
G01X25050Y1671150D01*
X36400Y1682500D01*
G03X37500Y1685156I-2656J2656D01*
G01Y1716131D01*
G03X37250Y1716381I-250J0D01*
G02X37000Y1716631I0J250D01*
G01Y1718531D01*
G02X37250Y1718781I250J0D01*
G03X37500Y1719031I0J250D01*
G01Y1728300D01*
X37501D01*
G02X38941Y1731780I4921J2D01*
G01X40380Y1733220D01*
G02X42506Y1734100I2126J-2128D01*
G01X43900D01*
G03X44400Y1734600I0J500D01*
G01Y1735700D01*
G03X43976Y1736724I-1449J0D01*
G01X43600Y1737100D01*
G01X46999Y1779550D02*
X45013Y1777564D01*
X12573D01*
X12560Y1777577D01*
G01X46199Y1783050D02*
X39205D01*
X37656Y1781501D01*
X12573D01*
X12560Y1781514D01*
G01X38094Y1785840D02*
X38089D01*
X37699Y1785450D01*
X33599D01*
X33587Y1785438D01*
X12573D01*
X12560Y1785451D01*
G01X45799Y1757650D02*
X37696Y1765753D01*
X12573D01*
X12560Y1765766D01*
G01X47400Y1765250D02*
X40999D01*
X36559Y1769690D01*
X12573D01*
X12560Y1769703D01*
G01X43925Y1767890D02*
X38188Y1773627D01*
X12573D01*
X12560Y1773640D01*
G01X37699Y1789850D02*
X35699D01*
X32699Y1792850D01*
X29135D01*
X28673Y1793312D01*
X12573D01*
X12560Y1793325D01*
G01X42199Y1792250D02*
X35863D01*
X33662Y1794450D01*
X29799D01*
X27000Y1797249D01*
X12573D01*
X12560Y1797262D01*
G01X37574Y1794050D02*
Y1794475D01*
X30863Y1801186D01*
X12573D01*
X12560Y1801199D01*
G01Y1805136D02*
X23787D01*
X25600Y1803323D01*
X38376D01*
X46799Y1794900D01*
G01X31811Y1790271D02*
X30915Y1789375D01*
X12573D01*
X12560Y1789388D01*
G01X28123Y1831527D02*
X25342Y1828746D01*
X12573D01*
X12560Y1828759D01*
G01X35876Y1812350D02*
X36399Y1812873D01*
Y1816050D01*
X33626Y1818823D01*
X28999D01*
X26950Y1820872D01*
X12573D01*
X12560Y1820885D01*
G01X34129Y1815267D02*
X32461Y1816935D01*
X12573D01*
X12560Y1816948D01*
G01X36532Y1825352D02*
X33701D01*
X31499Y1823150D01*
X24499D01*
X22840Y1824809D01*
X12573D01*
X12560Y1824822D01*
G01X35900Y1832700D02*
X35273Y1833327D01*
X26744D01*
X26100Y1832683D01*
X12573D01*
X12560Y1832696D01*
G01X38249Y1838050D02*
X35742Y1840557D01*
X12573D01*
X12560Y1840570D01*
G01X42700Y412350D02*
X36150D01*
X35900Y412600D01*
G01X39600Y626984D02*
Y625900D01*
X49526Y615974D01*
Y600870D01*
X43856Y595200D01*
X37750D01*
X35550Y597400D01*
G01X42709Y625607D02*
X51426Y616890D01*
Y599193D01*
X45533Y593300D01*
X35550D01*
G01X28586Y600248D02*
X30286D01*
X31134Y599400D01*
X37650D01*
X39650Y597400D01*
G01X42900Y601350D02*
X42850Y601300D01*
X31922D01*
X30300Y602922D01*
Y603267D01*
X28519Y605048D01*
G01X32050Y593300D02*
X28958D01*
X28808Y593150D01*
G01X32050Y597400D02*
X29551D01*
X28700Y596549D01*
G01X38850Y603200D02*
Y603940D01*
X42202Y607292D01*
Y608195D01*
G01X41400Y611500D02*
Y611100D01*
X38850Y608550D01*
Y607326D01*
G01X38300Y633800D02*
X34700Y630200D01*
Y623000D01*
G01X31249Y616050D02*
Y611550D01*
G01X39499Y615550D02*
X37899Y613950D01*
X33349D01*
X31249Y616050D01*
G01X32200Y603710D02*
X34840D01*
X35350Y603200D01*
G01X31598Y607102D02*
X35126D01*
X35350Y607326D01*
G01X39649Y822000D02*
X61151D01*
X61701Y822550D01*
X77269D01*
X79450Y820369D01*
Y818050D01*
X80500Y817000D01*
G01X98700Y842600D02*
X93100D01*
X89800Y845900D01*
X58800D01*
X48600Y856100D01*
X27000D01*
X25000Y858100D01*
G01X98000Y833500D02*
X77000D01*
X75529Y834971D01*
X67442D01*
X48961Y853452D01*
X30148D01*
X29600Y854000D01*
G01X56186Y1021050D02*
Y1021910D01*
X54436Y1023660D01*
Y1031350D01*
X45600Y1040186D01*
Y1046800D01*
X36350Y1056050D01*
X28349D01*
G01X108295Y956489D02*
G03X110951Y955389I2656J2656D01*
G01X113099D01*
G03X113999Y956289I0J900D01*
G01Y975102D01*
G03X113749Y975352I-250J0D01*
G02X113499Y975602I0J250D01*
G01Y977502D01*
G02X113749Y977752I250J0D01*
G03X113999Y978002I0J250D01*
G01Y979421D01*
G03X113599Y979821I-400J0D01*
G02X113199Y980221I0J400D01*
G01Y981821D01*
G02X113599Y982221I400J0D01*
G03X113999Y982621I0J400D01*
G01Y990049D01*
G03X111762Y995446I-7632J-1D01*
G01X97079Y1010130D01*
X34670Y1072539D01*
G02X31974Y1079050I6511J6510D01*
G01Y1382367D01*
G03X31195Y1384246I-2656J0D01*
G01X31044Y1384397D01*
X31042Y1384402D01*
X30384Y1385061D01*
G02X29628Y1386937I1951J1877D01*
G01Y1389054D01*
G03X29445Y1389972I-2400J-1D01*
G01X29103Y1390799D01*
G03X28727Y1391050I-376J-156D01*
G01X28499D01*
G01X56186Y1025050D02*
Y1031863D01*
X47300Y1040749D01*
Y1048450D01*
X31650Y1064100D01*
X23799D01*
X22849Y1065050D01*
G01X20849Y1059925D02*
Y1063550D01*
X19349Y1065050D01*
G01D02*
Y1066149D01*
X22300Y1069100D01*
G01X108295Y952989D02*
G02X110951Y954089I2656J-2656D01*
G01X113099D01*
G03X115299Y956289I0J2200D01*
G01Y990050D01*
G03X112682Y996366I-8933J-1D01*
G01X97999Y1011050D01*
X35590Y1073459D01*
G02X33274Y1079050I5591J5591D01*
G01Y1382368D01*
G03X32115Y1385166I-3957J0D01*
G01X32113Y1385168D01*
X32111Y1385172D01*
X31314Y1385970D01*
G02X30928Y1386938I1021J968D01*
G01Y1387550D01*
G02X31231Y1388280I1033J-1D01*
G01X32333Y1389383D01*
G01X108695Y550988D02*
G03X111290Y549913I2595J2595D01*
G01X112499D01*
G03X114839Y550882I0J3310D01*
G01X115003Y551046D01*
G03X116199Y553933I-2887J2887D01*
G01Y574677D01*
G03X115949Y574927I-250J0D01*
G02X115699Y575177I0J250D01*
G01Y577077D01*
G02X115949Y577327I250J0D01*
G03X116199Y577577I0J250D01*
G01Y581573D01*
G03X115849Y581923I-350J0D01*
G02X115499Y582273I0J350D01*
G01Y583973D01*
G02X115849Y584323I350J0D01*
G03X116199Y584673I0J350D01*
G01Y586373D01*
G03X115849Y586723I-350J0D01*
G02X115499Y587073I0J350D01*
G01Y588773D01*
G02X115849Y589123I350J0D01*
G03X116199Y589473I0J350D01*
G01Y591173D01*
G03X115849Y591523I-350J0D01*
G02X115499Y591873I0J350D01*
G01Y593573D01*
G02X115849Y593923I350J0D01*
G03X116199Y594273I0J350D01*
G01Y595973D01*
G03X115849Y596323I-350J0D01*
G02X115499Y596673I0J350D01*
G01Y598373D01*
G02X115849Y598723I350J0D01*
G03X116199Y599073I0J350D01*
G01Y601283D01*
G03X114738Y604811I-4990J0D01*
G01X96498Y623050D01*
X96499Y623051D01*
G02X95199Y626190I3138J3138D01*
G01Y728051D01*
G02X97347Y733238I7337J0D01*
G01X99079Y734970D01*
X119093Y754983D01*
G03X121398Y760549I-5567J5566D01*
G01X121399Y760548D01*
Y994946D01*
G03X120079Y998131I-4504J0D01*
G01X43709Y1074501D01*
G02X39547Y1084549I10049J10048D01*
G01Y1394698D01*
G03X37965Y1398517I-5401J0D01*
G01X31198Y1405284D01*
G02X30199Y1407697I2415J2413D01*
G01Y1409050D01*
G03X29280Y1411269I-3138J0D01*
G01X28999Y1411550D01*
G01X20999Y1320550D02*
Y1315550D01*
X20499Y1315050D01*
G01X108695Y547488D02*
G02X111411Y548613I2716J-2716D01*
G01X112499D01*
G03X115741Y549956I0J4585D01*
G01X116111Y550326D01*
G03X117499Y553932I-3995J3608D01*
G01Y601282D01*
G03X115658Y605731I-6291J2D01*
G01X115239Y606150D01*
X115238Y606149D01*
X97418Y623970D01*
G02X96499Y626189I2219J2219D01*
G01Y728052D01*
G02X98267Y732318I6036J-2D01*
G01X99999Y734050D01*
X120013Y754063D01*
G03X122699Y760549I-6486J6485D01*
G01Y994947D01*
G03X120999Y999051I-5804J0D01*
G01X44629Y1075421D01*
G02X40847Y1084550I9129J9130D01*
G01Y1394699D01*
G03X38884Y1399436I-6701J-2D01*
G01X38885Y1399437D01*
X32118Y1406204D01*
G02X31499Y1407698I1494J1494D01*
G01Y1409170D01*
G02X32451Y1411468I3250J0D01*
G01X108749Y141550D02*
G02X109855Y142008I1106J-1106D01*
G01X112499D01*
Y142009D01*
G03X114271Y142741I2J2507D01*
G01X114539Y143009D01*
Y143010D01*
G03X115299Y144845I-1834J1834D01*
G01Y148376D01*
G03X114089Y151297I-4131J0D01*
G01X110315Y155073D01*
G02X109099Y158009I2936J2936D01*
G01Y220382D01*
G03X107659Y223860I-4918J1D01*
G01X107339Y224179D01*
X106482Y225036D01*
G02X105599Y227168I2132J2132D01*
G01Y424835D01*
G02X106511Y427037I3114J0D01*
G01X107011Y427537D01*
X107012D01*
X107386Y427911D01*
G03X109099Y432051I-4141J4138D01*
G01Y480771D01*
G02X110074Y483125I3329J0D01*
G01X121499Y494550D01*
X121997Y495049D01*
G03X124999Y502295I-7246J7247D01*
G01Y606007D01*
G03X123668Y609220I-4544J0D01*
G01X104918Y627970D01*
G02X103899Y630430I2460J2460D01*
G01Y723050D01*
G02X106305Y728855I8210J-2D01*
G01X107224Y729774D01*
Y729776D01*
X108499Y731050D01*
X128048Y750600D01*
G03X130099Y755550I-4950J4951D01*
G01Y997051D01*
G03X127456Y1003432I-9025J0D01*
G01X55919Y1074970D01*
X50877Y1080012D01*
G02X48247Y1086359I6347J6348D01*
G01Y1398587D01*
G03X46628Y1402497I-5531J0D01*
G01X46287Y1402838D01*
X46286Y1402837D01*
X41687Y1407436D01*
G02X40616Y1410022I2586J2586D01*
G01Y1415833D01*
G03X39449Y1418651I-3984J1D01*
G01X39450Y1418652D01*
X33525Y1424577D01*
G02X32499Y1427054I2477J2477D01*
G01Y1430645D01*
G02X33206Y1432352I2414J0D01*
G01X108749Y145050D02*
X109778Y144021D01*
G03X111499Y143308I1721J1721D01*
G01X112499D01*
G03X113352Y143662I-1J1207D01*
G01X113620Y143929D01*
G03X113999Y144844I-915J915D01*
G01Y148375D01*
G03X113170Y150378I-2831J1D01*
G01X109395Y154153D01*
X109396Y154154D01*
G02X107799Y158010I3855J3855D01*
G01Y220383D01*
X107798Y220382D01*
G03X107298Y222219I-3618J2D01*
G01X107297D01*
G03X106740Y222940I-3118J-1833D01*
G01X106420Y223259D01*
X105564Y224115D01*
G02X104299Y227167I3053J3054D01*
G01Y424834D01*
G02X105592Y427956I4414J1D01*
G01X105591D01*
X106466Y428831D01*
G03X107799Y432050I-3220J3219D01*
G01Y480770D01*
G02X109154Y484045I4630J2D01*
G01X115998Y490888D01*
X120579Y495469D01*
X121077Y495968D01*
Y495969D01*
G03X123699Y502296I-6325J6328D01*
G01Y606006D01*
G03X122749Y608301I-3244J1D01*
G01X122748Y608300D01*
X103998Y627050D01*
X103999Y627051D01*
G02X102599Y630429I3379J3379D01*
G01Y723051D01*
G02X105385Y729775I9511J-2D01*
G01X105384Y729776D01*
X106443Y730834D01*
G02X106444Y730835I9285J-9284D01*
G01X107579Y731970D01*
X127128Y751520D01*
G03X128799Y755551I-4029J4032D01*
G01Y997050D01*
G03X126536Y1002512I-7725J-1D01*
G01X54999Y1074050D01*
X49957Y1079092D01*
G02X46947Y1086359I7267J7267D01*
G01Y1398586D01*
G03X45708Y1401577I-4230J0D01*
G01X40767Y1406516D01*
X40768Y1406517D01*
G02X39316Y1410023I3505J3505D01*
G01Y1415834D01*
G03X38530Y1417732I-2684J0D01*
G01X32605Y1423657D01*
X32606Y1423658D01*
G02X31199Y1427055I3396J3396D01*
G01Y1431504D01*
G03X31017Y1432422I-2400J1D01*
G01X30661Y1433281D01*
G02X30499Y1434093I1960J813D01*
G01Y1434550D01*
G01X128249Y228050D02*
G02X124939Y226680I-3548J3890D01*
G02X124701Y226675I-230J5260D01*
G01X122418D01*
X122387Y226674D01*
G02X120739Y227308I-110J2174D01*
G01X120740Y227309D01*
X119555Y228494D01*
X119554Y228493D01*
G02X118997Y229969I1356J1355D01*
G03X118999Y230050I-1051J66D01*
G01Y479050D01*
G02X120173Y481884I4008J0D01*
G01X130919Y492630D01*
G03X132400Y496207I-3579J3577D01*
G01Y609385D01*
G03X131101Y612519I-4434J-2D01*
G01X131102Y612520D01*
X113283Y630339D01*
G02X111299Y635129I4790J4790D01*
G01Y720052D01*
X111300Y720051D01*
G02X113279Y724830I6760J0D01*
G01X136792Y748343D01*
G03X137499Y750050I-1707J1707D01*
G01Y1001049D01*
G03X134787Y1007601I-9265J3D01*
G01X63418Y1078970D01*
X57632Y1084758D01*
G02X55647Y1089547I4787J4790D01*
G01Y1401351D01*
G03X53131Y1407425I-8590J0D01*
G01X49003Y1411555D01*
G02X48016Y1413938I2383J2383D01*
G01Y1429939D01*
G03X46834Y1432794I-4039J0D01*
G01X34553Y1445074D01*
G03X31472Y1446350I-3082J-3083D01*
G02X31040Y1447393I-1J611D01*
G01X32094Y1448448D01*
G01X128249Y224550D02*
G03X125401Y225397I-2640J-3664D01*
G01X125002Y225379D01*
X124999Y225378D01*
Y225375D01*
X122451D01*
G02X119820Y226389I-173J3472D01*
G01X118635Y227574D01*
G02X117699Y230050I2275J2275D01*
G01Y479051D01*
G02X119253Y482804I5309J0D01*
G01X129999Y493550D01*
G03X131100Y496208I-2658J2658D01*
G01Y609384D01*
G03X130182Y611600I-3134J0D01*
G01X112363Y629419D01*
X112364Y629420D01*
G02X109999Y635130I5709J5709D01*
G01Y720051D01*
G02X112359Y725750I8060J0D01*
G01X135872Y749263D01*
G03X136199Y750050I-787J788D01*
G01Y1001050D01*
G03X133867Y1006681I-7964J0D01*
G01X62498Y1078050D01*
X56712Y1083838D01*
G02X54347Y1089546I5708J5709D01*
G01Y1401550D01*
G03X52353Y1406365I-6810J0D01*
G01X48083Y1410635D01*
X48084Y1410636D01*
G02X46716Y1413939I3302J3302D01*
G01Y1429938D01*
G03X45914Y1431874I-2738J0D01*
G01X45350Y1432438D01*
X45346D01*
X34616Y1443168D01*
Y1443175D01*
X34615Y1443174D01*
X34048Y1443741D01*
X33634Y1444154D01*
G03X31471Y1445050I-2163J-2163D01*
G01Y1445049D01*
G02X29627Y1447462I1J1912D01*
G03X28989Y1448296I-638J173D01*
G01X28697D01*
G01X131688Y630065D02*
G03X129093Y631140I-2595J-2595D01*
G01X123785D01*
G02X120465Y632516I2J4697D01*
G01Y632515D01*
X120464Y632514D01*
X118714Y634264D01*
X118715Y634265D01*
Y634266D01*
G02X117399Y637441I3176J3177D01*
G01Y717049D01*
G02X119334Y721726I6612J3D01*
G01X125579Y727970D01*
X142196Y744587D01*
G03X143600Y747974I-3387J3388D01*
G01Y750501D01*
X143599Y750502D01*
Y1004627D01*
G03X141249Y1010300I-8023J0D01*
G01X66999Y1084550D01*
X63689Y1087859D01*
G02X61747Y1092549I4690J4689D01*
G01Y1406310D01*
G03X60579Y1409130I-3988J0D01*
G01X55712Y1413997D01*
G02X55383Y1414356I3947J3947D01*
G02X54116Y1417839I4148J3481D01*
G01Y1437789D01*
G03X53382Y1439561I-2506J0D01*
G01X42946Y1449998D01*
X30425Y1462518D01*
X30378D01*
G01X131688Y633565D02*
X131669Y633546D01*
G02X128999Y632440I-2670J2670D01*
G01X123786D01*
G02X121384Y633435I0J3397D01*
G01X119634Y635185D01*
G02X118699Y637442I2257J2257D01*
G01Y717050D01*
G02X120254Y720806I5311J1D01*
G01X126499Y727050D01*
X143116Y743667D01*
G03X144900Y747974I-4307J4307D01*
G01Y751040D01*
X144899Y751041D01*
Y1004628D01*
G03X142168Y1011219I-9323J-2D01*
G01X142169Y1011220D01*
X67919Y1085470D01*
X64609Y1088779D01*
G02X63048Y1092549I3771J3769D01*
G01X63047Y1092548D01*
Y1406309D01*
G03X61498Y1410049I-5288J1D01*
G01X61499Y1410050D01*
X61498Y1410051D01*
X56621Y1414930D01*
G02X55416Y1417839I2909J2909D01*
G01Y1433589D01*
X55421Y1433594D01*
Y1434670D01*
X55416Y1434675D01*
Y1437790D01*
G03X54301Y1440480I-3806J-1D01*
G01X54302Y1440481D01*
X39438Y1455345D01*
X38789Y1455993D01*
X38722Y1456060D01*
Y1456061D01*
X34366Y1460417D01*
G02X33915Y1461506I1089J1089D01*
G01Y1462681D01*
G01X855728Y228424D02*
G03X853305Y227834I0J-5270D01*
G02X851999Y227324I-1306J1417D01*
G01X851120D01*
X845787Y228318D01*
G02X842685Y229176I14131J57124D01*
G01X841970Y229523D01*
X841950Y229532D01*
X773693Y262725D01*
G02X770623Y266107I5292J7888D01*
G01X770526Y266287D01*
X770525Y266290D01*
X217719Y1293622D01*
X217717Y1293624D01*
X217601Y1293839D01*
G03X216638Y1295136I-4885J-2621D01*
G01X216111Y1295663D01*
X215668Y1296105D01*
X215490Y1296284D01*
X88111Y1423663D01*
G02X86449Y1427675I4012J4012D01*
G01Y1438549D01*
G03X84128Y1444156I-7928J2D01*
G01X83866Y1444418D01*
X83865Y1444417D01*
X36616Y1491667D01*
X36253Y1492029D01*
G03X34423Y1492941I-3160J-4049D01*
G02X33777Y1493315I377J1396D01*
G01X33770Y1493321D01*
X33520Y1493571D01*
G02X32949Y1494950I1379J1379D01*
G01Y1495550D01*
G02X33550Y1497001I2052J0D01*
G01X34099Y1497550D01*
G01X855728Y224924D02*
G02X853384Y225435I0J5632D01*
G03X852311Y225998I-1390J-1345D01*
G03X851999Y226024I-315J-1897D01*
G01X850999D01*
X845724Y227007D01*
G02X845474Y227056I373J2568D01*
G02X842305Y227933I14452J58384D01*
G01X842304Y227932D01*
X842208Y227962D01*
X841419Y228345D01*
X841399Y228354D01*
X773381Y261431D01*
G02X769378Y265673I5884J9562D01*
G01X216456Y1293223D01*
G03X215718Y1294216I-3738J-2007D01*
G01X214747Y1295187D01*
X214569Y1295366D01*
X87191Y1422744D01*
G02X85149Y1427674I4932J4931D01*
G01Y1438550D01*
G03X83208Y1443236I-6627J0D01*
G01X35946Y1490498D01*
X35697Y1490748D01*
X35453Y1491004D01*
G03X34087Y1491686I-2362J-3022D01*
G01X34086Y1491684D01*
G02X34084Y1491685I1227J2457D01*
G02X32899Y1492355I717J2651D01*
G01X32886Y1492366D01*
X32850Y1492401D01*
X32600Y1492651D01*
G02X31649Y1494950I2300J2297D01*
G01Y1495550D01*
G03X31048Y1497001I-2052J0D01*
G01X30499Y1497550D01*
G01X129249Y1039050D02*
X128967Y1038768D01*
G02X125853I-1557J1557D01*
G01X125723Y1038899D01*
X72535Y1092087D01*
G02X70899Y1096037I3950J3950D01*
G01Y1209858D01*
G02X72449Y1213600I5292J0D01*
G01X81424Y1222575D01*
G03X87200Y1236519I-13944J13944D01*
G01Y1243290D01*
G03X86284Y1247202I-8811J0D01*
G03X84620Y1249520I-7895J-3911D01*
G01X82647Y1251494D01*
G03X77799Y1253500I-4845J-4848D01*
G01X72448D01*
G02X71920Y1253720I2J748D01*
G02X71300Y1255217I1497J1497D01*
G01X71299Y1255216D01*
Y1380359D01*
G02X72600Y1383500I4442J0D01*
G01X74100Y1385000D01*
G02X76756Y1386100I2656J-2656D01*
G01X83326D01*
G03X86419Y1387381I1J4373D01*
G01Y1387380D01*
X87519Y1388480D01*
Y1388481D01*
G03X88791Y1391550I-3070J3070D01*
G01Y1398100D01*
G03X86153Y1404467I-9005J-1D01*
G01X85719Y1404902D01*
X82659Y1407964D01*
X81711Y1408912D01*
Y1408911D01*
X81710Y1408910D01*
X76392Y1414231D01*
G03X71999Y1416050I-4392J-4393D01*
G01X67196D01*
G02X65277Y1416845I0J2714D01*
G01X64286Y1417837D01*
G02X63381Y1420019I2181J2183D01*
G01Y1446334D01*
G03X61214Y1451570I-7404J2D01*
G01X61108Y1451676D01*
X61107Y1451675D01*
X34282Y1478500D01*
X34076Y1478707D01*
X33409Y1479374D01*
G02X32999Y1480364I990J990D01*
G02X34318Y1481683I1319J0D01*
G01X34465D01*
G01X129249Y1035550D02*
G02X125802Y1036978I0J4874D01*
G01X125541Y1037239D01*
X124931Y1037850D01*
X124803Y1037979D01*
X124615Y1038168D01*
Y1038167D01*
X71615Y1091167D01*
X71616Y1091168D01*
G02X69599Y1096038I4869J4869D01*
G01Y1209859D01*
G02X71530Y1214519I6592J-1D01*
G01X71528D01*
G02X71529Y1214520I4662J-4661D01*
G01X80504Y1223495D01*
G03X85900Y1236522I-13027J13027D01*
G01Y1243289D01*
G03X83700Y1248600I-7511J0D01*
G01X81727Y1250574D01*
G03X77800Y1252200I-3926J-3927D01*
G01X72449D01*
G02X71000Y1252800I0J2049D01*
G02X69999Y1255217I2417J2417D01*
G01Y1380358D01*
G02X71681Y1384419I5742J1D01*
G01X71680D01*
X73180Y1385919D01*
X73181D01*
G02X76757Y1387400I3575J-3575D01*
G01X83327D01*
G03X85500Y1388300I0J3073D01*
G01X86600Y1389400D01*
G03X87491Y1391551I-2151J2151D01*
G01Y1398100D01*
G03X85234Y1403549I-7706J0D01*
G01X75616Y1413167D01*
X75472Y1413312D01*
G03X71999Y1414750I-3472J-3473D01*
G01X67193D01*
G02X64359Y1415924I0J4008D01*
G01X63366Y1416917D01*
G02X62081Y1420019I3102J3102D01*
G01Y1446335D01*
G03X60294Y1450650I-6103J0D01*
G01X60188Y1450756D01*
X59887Y1451056D01*
X34445Y1476497D01*
X33497Y1477445D01*
X33362Y1477581D01*
X32488Y1478455D01*
G02X30999Y1482050I3595J3595D01*
G01X855946Y630382D02*
G03X852999Y631482I-2947J-3398D01*
G01X774499D01*
G02X771374Y631719I-407J15349D01*
G01X767212Y632470D01*
G02X766919Y632527I302J2332D01*
G02X761701Y635903I2509J9599D01*
G01X761700Y635902D01*
X250866Y1269918D01*
X95616Y1425168D01*
X95040Y1425745D01*
G02X93049Y1430550I4805J4806D01*
G01Y1452050D01*
G03X91505Y1455778I-5273J0D01*
G01X41866Y1505417D01*
X41586Y1505698D01*
G03X38499Y1506976I-3086J-3087D01*
G01X36127D01*
G02X32724Y1508385I0J4813D01*
G01X32149Y1508961D01*
G02X31386Y1510802I1840J1841D01*
G03X30288Y1511900I-1098J0D01*
G01X30115D01*
G01X855946Y633882D02*
G02X852999Y632782I-2947J3398D01*
G01X774465D01*
G02X771604Y632998I-378J14050D01*
G01X767247Y633785D01*
G02X762713Y636718I2181J8342D01*
G01X251835Y1270788D01*
X96536Y1426087D01*
X95960Y1426664D01*
Y1426665D01*
G02X95173Y1427658I3884J3887D01*
G02X94349Y1430550I4672J2894D01*
G01Y1452051D01*
G03X92425Y1456698I-6574J0D01*
G01X92286Y1456837D01*
X92285Y1456836D01*
X42787Y1506335D01*
X42507Y1506617D01*
G03X38499Y1508275I-4005J-4007D01*
G01Y1508276D01*
X36128D01*
G02X33644Y1509305I0J3513D01*
G01X33068Y1509881D01*
G02X32686Y1510802I919J921D01*
G01Y1511225D01*
G02X33512Y1512051I826J0D01*
G01X855583Y1039392D02*
G02X851999Y1038292I-3584J5289D01*
G01X842303D01*
G02X838335Y1038967I-453J9336D01*
G01X260918Y1273207D01*
G02X258032Y1275063I2829J7571D01*
G01X108522Y1424573D01*
X103932Y1429160D01*
G02X101749Y1434430I5270J5270D01*
G01Y1458971D01*
G03X99749Y1463800I-6831J-1D01*
G01X49335Y1514214D01*
G02X47617Y1518362I4148J4148D01*
G01Y1520931D01*
X47618Y1520932D01*
Y1535050D01*
G03X43424Y1544476I-12689J0D01*
G01X32174Y1555726D01*
G03X31174Y1556725I-999000J-999000D01*
G02X29349Y1561050I4212J4325D01*
G01Y1569550D01*
G02X30520Y1572049I3252J0D01*
G01X855583Y1035892D02*
G03X851881Y1036953I-4583J-9002D01*
G03X850999Y1036992I-887J-10062D01*
G01X842366D01*
Y1036993D01*
G02X837847Y1037763I-513J10635D01*
G01X837846Y1037762D01*
X260462Y1271989D01*
G02X257111Y1274142I4055J9995D01*
G01X107602Y1423653D01*
X103012Y1428241D01*
G02X100449Y1434429I6190J6189D01*
G01Y1458970D01*
G03X98829Y1462881I-5531J0D01*
G01X48416Y1513294D01*
G02X46317Y1518362I5067J5067D01*
G01Y1521470D01*
X46318Y1521471D01*
Y1535050D01*
G03X42554Y1543510I-11389J0D01*
G01X42528Y1543532D01*
X30266Y1555794D01*
G02X28049Y1561050I5121J5255D01*
G01Y1569550D01*
G03X27123Y1572205I-4269J0D01*
G01X42449Y1588600D02*
X34599D01*
G01D02*
X30509D01*
X30499Y1588610D01*
G01X857077Y1440796D02*
G03X854144Y1441896I-2933J-3360D01*
G01X830499D01*
G02X826783Y1442443I0J12896D01*
G01X327885Y1608910D01*
G03X324948Y1609408I-3385J-11053D01*
G03X324499Y1609417I-456J-11551D01*
G01X32734D01*
G02X29999Y1610550I0J3868D01*
G02X28899Y1613206I2656J2656D01*
G01Y1613524D01*
G01X42199Y1601050D02*
X38499D01*
G01X857077Y1444296D02*
G02X854144Y1443196I-2933J3360D01*
G01X830499D01*
G02X827206Y1443674I0J11582D01*
G01X328287Y1610148D01*
G03X324999Y1610707I-3799J-12397D01*
G03X324500Y1610717I-507J-12850D01*
G01X32735D01*
G02X30919Y1611470I0J2567D01*
G02X30878Y1611513I1756J1715D01*
G02X30895Y1612446I492J458D01*
G01X31743Y1613293D01*
G02X32299Y1613524I557J-556D01*
G01X107249Y1767550D02*
X107279Y1767521D01*
G03X109863Y1766450I2585J2584D01*
G03X111631Y1767182I0J2501D01*
G01X111867Y1767418D01*
G03X112599Y1769186I-1769J1768D01*
G01Y1775826D01*
G03X111867Y1777594I-2501J0D01*
G01X85127Y1804334D01*
G03X80499Y1806251I-4628J-4628D01*
G01Y1806250D01*
X75999D01*
G03X71219Y1804270I0J-6760D01*
G01X68825Y1801876D01*
G03X65949Y1794933I6943J-6943D01*
G01Y1660004D01*
G02X62834Y1652484I-10635J0D01*
G01X36643Y1626293D01*
G02X34149Y1625260I-2494J2494D01*
G01X32896D01*
G02X31985Y1625638I1J1289D01*
G01X31776Y1625846D01*
G02X30906Y1627534I2204J2204D01*
G03X30122Y1629427I-2677J0D01*
G01X29499Y1630050D01*
G01X107249Y1764050D02*
X107617Y1764417D01*
G02X109127Y1765136I1768J-1768D01*
G02X109385Y1765150I264J-2486D01*
G01X109863D01*
G03X112551Y1766262I1J3802D01*
G01X112787Y1766498D01*
G03X113899Y1769186I-2690J2687D01*
G01Y1775826D01*
G03X112787Y1778514I-3802J1D01*
G01X86047Y1805254D01*
G03X80342Y1807550I-5547J-5548D01*
G01X75999D01*
G03X70299Y1805189I0J-8061D01*
G01X67905Y1802795D01*
G03X64649Y1794934I7863J-7862D01*
G01Y1659842D01*
G02X62030Y1653519I-8942J0D01*
G01X35532Y1627021D01*
G02X34419Y1626560I-1113J1113D01*
G01X33246D01*
G02X32663Y1627143I0J583D01*
G01Y1628181D01*
G01X128342Y1849754D02*
X128263Y1849675D01*
G02X125499Y1848530I-2764J2764D01*
G01X113842D01*
G02X108989Y1850540I0J6863D01*
G01X100238Y1859291D01*
G03X94784Y1861550I-5455J-5456D01*
G01X62474D01*
G03X58249Y1859799I2J-5977D01*
G01X58248D01*
X52499Y1854050D01*
G03X49849Y1847652I6397J-6397D01*
G01Y1675786D01*
G02X47897Y1671075I-6663J1D01*
G01X47686Y1670863D01*
X35129Y1658306D01*
G02X34743Y1658028I-1037J1033D01*
G02X34700Y1658008I-639J1317D01*
G02X34304Y1657892I-605J1332D01*
G02X34091Y1657876I-216J1448D01*
G01X33209D01*
G02X31499Y1658552I0J2501D01*
G01X31353Y1658698D01*
G02X31124Y1659017I853J854D01*
G01X31123D01*
G02X30999Y1659551I1083J533D01*
G02Y1659568I1393J9D01*
G02X31000Y1659593I1392J-43D01*
G03X30995Y1659809I-1997J62D01*
G02X31179Y1660307I633J49D01*
G01X31999Y1661127D01*
G01X128342Y1846254D02*
G03X125986Y1847230I-2356J-2356D01*
G01X113843D01*
G02X108070Y1849621I-1J8163D01*
G01X108069Y1849620D01*
X99319Y1858371D01*
G03X94783Y1860250I-4536J-4536D01*
G01X62475D01*
G03X59168Y1858880I0J-4677D01*
G01X53418Y1853130D01*
G03X51149Y1847652I5478J-5478D01*
G01Y1675786D01*
G02X48816Y1670155I-7962J0D01*
G01X48605Y1669943D01*
X38605Y1659943D01*
X36049Y1657386D01*
G02X35319Y1656862I-1955J1954D01*
G02X34095Y1656576I-1224J2476D01*
G01X33209D01*
G02X30521Y1657688I-1J3802D01*
G01X30433Y1657776D01*
Y1657778D01*
G02X29699Y1659546I1773J1772D01*
G02Y1659579I2693J17D01*
G02X29700Y1659630I2693J-27D01*
G03X29496Y1660143I-697J20D01*
G01X28600Y1661039D01*
G01X859064Y1846613D02*
X858537Y1847141D01*
G03X854499Y1848813I-4037J-4038D01*
G01X849501D01*
G03X842248Y1845808I0J-10256D01*
G01X840520Y1844080D01*
X840519D01*
X835569Y1839128D01*
G02X829300Y1836534I-6266J6270D01*
G01Y1836533D01*
X289000D01*
G03X283574Y1834284I1J-7673D01*
G01X271919Y1822630D01*
G02X269157Y1820646I-7437J7438D01*
G02X264482Y1819550I-4675J9422D01*
G01X134898D01*
G02X134897Y1819549I-4093J4092D01*
G01X134896Y1819550D01*
G02X130804Y1821245I0J5787D01*
G01X130498Y1821551D01*
X130021Y1822029D01*
G03X127999Y1822867I-2023J-2023D01*
G01Y1822866D01*
X67459D01*
G03X64832Y1821778I0J-3715D01*
G01X60051Y1816997D01*
G03X58549Y1813371I3626J-3626D01*
G01Y1666550D01*
G02X56143Y1660743I-8213J1D01*
G01X55832Y1660431D01*
X37098Y1641697D01*
G02X35000Y1640828I-2098J2099D01*
G01X33224D01*
G02X30933Y1641776I-1J3239D01*
G02X30218Y1643226I1772J1775D01*
G01X30116Y1644007D01*
G03X29626Y1645002I-1708J-223D01*
G01X859064Y1850113D02*
X849500D01*
G03X841328Y1846728I0J-11557D01*
G01X839600Y1845000D01*
X834649Y1840048D01*
G02X829300Y1837833I-5348J5349D01*
G01X288999D01*
G03X282654Y1835204I1J-8974D01*
G01X270999Y1823550D01*
G02X264481Y1820850I-6518J6518D01*
G01X134897D01*
G02X131723Y1822165I0J4487D01*
G01X131418Y1822470D01*
X130941Y1822948D01*
G03X127999Y1824166I-2941J-2942D01*
G01X67460D01*
G03X63913Y1822697I-1J-5015D01*
G01X63912D01*
X59131Y1817916D01*
G03X57249Y1813372I4546J-4545D01*
G01Y1666550D01*
G02X55225Y1661662I-6912J-1D01*
G01X53055Y1659493D01*
X37055Y1643493D01*
X36178Y1642617D01*
G02X34999Y1642128I-1180J1179D01*
G01X33224D01*
G02X31853Y1642696I0J1939D01*
G02Y1644404I853J854D01*
G01X32128Y1644679D01*
G02X33026Y1645051I898J-898D01*
G01X45877Y1728477D02*
X45195Y1727795D01*
G02X44000Y1727300I-1195J1195D01*
G01X43966D01*
G03X42080Y1726519I0J-2667D01*
G03X41200Y1724394I2125J-2125D01*
G01Y1674751D01*
G02X39750Y1671250I-4951J0D01*
G01X35848Y1667348D01*
G02X33800Y1666500I-2048J2049D01*
G01X32733D01*
G02X31719Y1666920I0J1434D01*
G01X31655Y1666984D01*
G02X31400Y1667600I617J616D01*
G01Y1668100D01*
G02X31762Y1668974I1236J0D01*
G01X32494Y1669706D01*
G01X45877Y1724823D02*
X45195Y1725505D01*
G03X44000Y1726000I-1195J-1195D01*
G01X43966D01*
G03X43000Y1725600I0J-1366D01*
G03X42500Y1724393I1207J-1207D01*
G01Y1674752D01*
G02X40669Y1670331I-6251J-1D01*
G01Y1670329D01*
X36768Y1666428D01*
G02X33799Y1665200I-2967J2970D01*
G01X32734D01*
G02X30800Y1666001I-1J2734D01*
G01X30799Y1666000D01*
X30735Y1666064D01*
G02X30100Y1667599I1538J1535D01*
G01Y1668100D01*
G03X29817Y1668783I-966J0D01*
G01X29100Y1669500D01*
G01X46499Y1850050D02*
X46249D01*
X38249Y1842050D01*
G01D02*
X37749Y1842550D01*
X25999D01*
G01X46999Y1832550D02*
X43299Y1836250D01*
X40049D01*
X38249Y1838050D01*
G01X55749Y203550D02*
Y201800D01*
X52499Y198550D01*
G01X66023Y206431D02*
X66011Y206419D01*
X61380D01*
X60374Y207425D01*
X59374D01*
X59249Y207550D01*
G01D02*
Y208300D01*
X61499Y210550D01*
Y216157D01*
X61757Y216415D01*
G01X49949Y207900D02*
X50299Y207550D01*
X55749D01*
G01D02*
Y203550D01*
G01X59249Y211550D02*
Y213300D01*
X56999Y215550D01*
Y217050D01*
G01X66023Y209631D02*
X66022Y209632D01*
Y213027D01*
X63857Y215191D01*
Y217285D01*
X62627Y218515D01*
X57964D01*
X56999Y217550D01*
Y217050D01*
G01X51849Y217100D02*
Y219000D01*
X52964Y220115D01*
X63290D01*
X65999Y217406D01*
Y216050D01*
G01X55749Y211550D02*
Y213200D01*
X51849Y217100D01*
G01X42449Y211775D02*
X41499Y212725D01*
Y219050D01*
G01X48349Y217100D02*
X46399Y219050D01*
X41499D01*
G01X52730Y406470D02*
X52400Y406800D01*
Y409900D01*
X49950Y412350D01*
X46800D01*
G01X42700D02*
X46800D01*
G01X47626Y611300D02*
Y601876D01*
X43150Y597400D01*
G01X60400Y616000D02*
Y613576D01*
X64103Y609873D01*
X69373D01*
X71443Y611943D01*
X71773D01*
G01X42900Y604850D02*
Y604899D01*
X45701Y607700D01*
G01X55500Y618500D02*
Y632000D01*
X52500Y635000D01*
G01X56999Y652487D02*
X55487D01*
X53500Y650500D01*
Y646500D01*
X62500Y637500D01*
Y633300D01*
G01X44950Y639600D02*
X44452Y639102D01*
X41367D01*
G01D02*
Y642667D01*
X41500Y642800D01*
G01X48450Y635500D02*
X53400Y630550D01*
Y630500D01*
G01X66023Y638100D02*
Y639463D01*
X56999Y648487D01*
G01X44950Y635500D02*
X42000D01*
X41500Y635000D01*
G01X44950Y635500D02*
Y632950D01*
X43500Y631500D01*
G01X48999Y642900D02*
Y640149D01*
X48450Y639600D01*
G01X66549Y651900D02*
X61086D01*
X60499Y652487D01*
G01D02*
Y656487D01*
G01D02*
Y660050D01*
X61999Y661550D01*
G01X60499Y648487D02*
X69771D01*
X71509Y650225D01*
X76824D01*
X79249Y647800D01*
Y642550D01*
G01X40734Y802473D02*
X45947D01*
X46887Y803413D01*
G01X111089Y806603D02*
X109866D01*
X109788Y806525D01*
X83264D01*
X79239Y810550D01*
X55587D01*
X51337Y806300D01*
X51100D01*
G01X98700Y822550D02*
X81802D01*
X72581Y831771D01*
X47756D01*
X46576Y832951D01*
G01X59686Y1021050D02*
Y1021737D01*
X61999Y1024050D01*
X63197D01*
X63273Y1023974D01*
G01X56186Y1021050D02*
Y1017113D01*
X56249Y1017050D01*
G01D02*
X52749Y1013550D01*
X52499D01*
G01X59686Y1025050D02*
X61186Y1026550D01*
X65499D01*
X66499Y1025550D01*
Y1025050D01*
G01X65486Y1031515D02*
Y1031486D01*
X63550Y1029550D01*
X60686D01*
X56186Y1025050D01*
G01X89250Y1557500D02*
X87250Y1559500D01*
X67500D01*
X60172Y1566828D01*
G01X66023Y1831679D02*
X67370D01*
X68600Y1830449D01*
Y1827054D01*
X68112Y1826566D01*
X63220D01*
X60999Y1828787D01*
Y1834535D01*
X63399Y1836935D01*
Y1845053D01*
X64996Y1846650D01*
X75536D01*
X77249Y1848363D01*
Y1849050D01*
G01X41749Y1838050D02*
X44999D01*
X46499Y1836550D01*
G01X41749Y1842050D02*
X45000D01*
X47166Y1839884D01*
G01X63849Y1851900D02*
Y1849875D01*
X60449Y1846475D01*
G01D02*
X60424D01*
X57499Y1843550D01*
Y1830550D01*
X57999Y1830050D01*
G01X105249Y129550D02*
X104780Y129080D01*
G02X103499Y128550I-1280J1281D01*
G01X101299D01*
G03X99099Y126350I0J-2200D01*
G01Y122894D01*
G02X95899Y119694I-3200J0D01*
G01X81615D01*
G02X81221Y119857I0J557D01*
G03X79458Y120498I-1763J-2104D01*
G01X79445Y120511D01*
X77166D01*
G01X105249Y126050D02*
X104243Y127056D01*
G03X103774Y127250I-469J-470D01*
G01X101299D01*
G03X100399Y126350I0J-900D01*
G01Y122894D01*
G02X95899Y118394I-4500J0D01*
G01X81629D01*
G03X80799Y118050I0J-1174D01*
G02X79107Y117349I-1692J1692D01*
G01X79094Y117362D01*
X77166D01*
G01X86899Y130567D02*
Y130543D01*
G02X85499Y129143I-1400J0D01*
G01X81615D01*
G02X81221Y129306I0J557D01*
G03X79458Y129947I-1763J-2104D01*
G01X79445Y129960D01*
X77166D01*
G01X86599Y126750D02*
X86218Y127131D01*
G03X84499Y127843I-1719J-1719D01*
G01X81629D01*
G03X80799Y127499I0J-1174D01*
G02X79107Y126798I-1692J1692D01*
G01X79094Y126811D01*
X77166D01*
G01X77749Y204550D02*
X75880Y206419D01*
X71785D01*
X71773Y206431D01*
G01D02*
X70118D01*
X68900Y207649D01*
Y216611D01*
X69510Y217221D01*
G01X77749Y213500D02*
Y208550D01*
G01X71773Y209631D02*
X75642Y213500D01*
X77749D01*
G01X101195Y525988D02*
G02X99655Y525350I-1540J1540D01*
G01X82194D01*
G02X81702Y525554I0J696D01*
G03X80179Y526010I-1522J-2313D01*
G01X80166Y526023D01*
X77166D01*
G01X101195Y522488D02*
G03X97424Y524050I-3771J-3771D01*
G01X83789D01*
G03X83475Y524029I2J-2390D01*
G03X82099Y523350I314J-2369D01*
G02X80918Y522861I-1181J1181D01*
G01X80905Y522874D01*
X77166D01*
G01X86199Y536025D02*
X84986Y534812D01*
G02X84111Y534450I-874J875D01*
G01X82809D01*
G02X81677Y534919I0J1601D01*
G03X80373Y535459I-1304J-1304D01*
G01X80360Y535472D01*
X77166D01*
G01X86199Y532250D02*
G03X84026Y533150I-2173J-2173D01*
G01X82703D01*
G03X81708Y532738I0J-1407D01*
G02X80675Y532310I-1033J1033D01*
G01X80662Y532323D01*
X77166D01*
G01X71773Y611943D02*
X77258D01*
X77751Y611450D01*
G01X66023Y611943D02*
X65233D01*
X62500Y614676D01*
Y633300D01*
G01X66023Y615143D02*
Y638100D01*
G01X71800Y622700D02*
X71773Y622673D01*
Y615143D01*
G01D02*
X77444D01*
X77751Y615450D01*
G01X82499Y627050D02*
X82249D01*
X81499Y627800D01*
Y640300D01*
X79249Y642550D01*
G01X74049Y648025D02*
Y644250D01*
X75749Y642550D01*
G01D02*
Y638300D01*
X76499Y637550D01*
G01X99795Y931489D02*
X98278D01*
G03X96950Y930939I0J-1878D01*
G02X95622Y930389I-1328J1328D01*
G01X83421D01*
G02X82038Y930962I0J1956D01*
G03X80655Y931535I-1383J-1383D01*
G01X77166D01*
G01X85999Y940429D02*
G02X85246Y940117I-753J753D01*
G01X82839D01*
G02X82146Y940404I0J980D01*
G01X82099Y940450D01*
G03X80841Y940971I-1258J-1258D01*
G01X80828Y940984D01*
X77166D01*
G01Y928386D02*
X81048D01*
G03X82328Y928765I0J2351D01*
G02X83422Y929089I1095J-1687D01*
G01X96133D01*
G02X97461Y928539I0J-1878D01*
G03X98789Y927989I1328J1328D01*
G01X99795D01*
G01X86399Y937050D02*
G03X85975Y938074I-1449J0D01*
G01X85799Y938250D01*
G03X84592Y938750I-1207J-1207D01*
G01X82994D01*
G03X82149Y938400I0J-1195D01*
G02X80754Y937822I-1395J1395D01*
G01X80741Y937835D01*
X77166D01*
G01X71773Y1017455D02*
Y1013627D01*
X72000Y1013400D01*
G01X81250Y1008500D02*
X75500D01*
X72000Y1012000D01*
Y1013400D01*
G01X63273Y1023974D02*
Y1023823D01*
X62999Y1023549D01*
Y1019050D01*
X64594Y1017455D01*
X66023D01*
G01Y1020655D02*
X66499Y1021131D01*
Y1025050D01*
G01X71773Y1020655D02*
Y1025027D01*
X68000Y1028800D01*
G01X71773Y1020655D02*
X71928Y1020500D01*
X76000D01*
X82750Y1013750D01*
Y1013000D01*
G01X76999Y1196550D02*
X81999Y1191550D01*
X114499D01*
X115499Y1192550D01*
Y1197550D01*
G01X100578Y1336952D02*
G02X98400Y1336050I-2178J2178D01*
G01X83179D01*
G02X81991Y1336542I0J1680D01*
G03X80803Y1337034I-1188J-1188D01*
G01X80790Y1337047D01*
X77166D01*
G01X100578Y1333452D02*
X100115Y1333915D01*
G03X98099Y1334750I-2016J-2016D01*
G01X82353D01*
G03X81749Y1334500I0J-854D01*
G02X80264Y1333885I-1485J1485D01*
G01X80251Y1333898D01*
X77166D01*
G01X86890Y1346635D02*
X86882Y1346627D01*
G02X83799Y1345350I-3083J3083D01*
G01X82882D01*
G02X82399Y1345550I0J683D01*
G03X80147Y1346483I-2252J-2252D01*
G01X80134Y1346496D01*
X77166D01*
G01X86890Y1342860D02*
G03X84017Y1344050I-2873J-2873D01*
G01X82582D01*
G03X82099Y1343850I0J-683D01*
G02X80853Y1343334I-1246J1246D01*
G01X80840Y1343347D01*
X77166D01*
G01X71773Y1422967D02*
X76076D01*
X90526Y1408517D01*
Y1408513D01*
X113999Y1385040D01*
Y1380550D01*
G01X66023Y1422967D02*
X66022Y1422966D01*
Y1422465D01*
X70036Y1418451D01*
X75567D01*
X108950Y1385068D01*
Y1373798D01*
X115499Y1367249D01*
Y1364550D01*
G01X121000Y1364000D02*
Y1365747D01*
X110550Y1376197D01*
Y1385731D01*
X76230Y1420051D01*
X70699D01*
X69272Y1421478D01*
Y1423708D01*
X66826Y1426154D01*
X66036D01*
X66023Y1426167D01*
G01X71773D02*
X75139D01*
X92126Y1409180D01*
Y1409176D01*
X122800Y1378502D01*
Y1372700D01*
X123500Y1372000D01*
G01X79000Y1548250D02*
Y1545700D01*
X80009Y1544691D01*
X80043D01*
G01X79000Y1551750D02*
Y1555500D01*
G01X78600Y1561900D02*
Y1562000D01*
X79000Y1562400D01*
Y1565150D01*
G01X75000D02*
Y1561800D01*
G01X80400Y1571766D02*
X77506D01*
X75000Y1569260D01*
Y1568650D01*
G01X79000D02*
X81796D01*
X82329Y1568117D01*
G01X63014Y1560986D02*
X66400Y1557600D01*
X85150D01*
X89250Y1553500D01*
G01X96999Y1632050D02*
Y1637400D01*
X87099Y1647300D01*
Y1651250D01*
X77900Y1660449D01*
Y1680500D01*
X80589Y1683189D01*
X85630D01*
G01X101749Y1743050D02*
X101503Y1742805D01*
G02X99199Y1741850I-2305J2304D01*
G01X83361D01*
G02X82190Y1742335I0J1656D01*
G03X81681Y1742546I-509J-509D01*
G01X81668Y1742559D01*
X77166D01*
G01X101749Y1739550D02*
G03X99335Y1740550I-2414J-2414D01*
G01X82853D01*
G03X82249Y1740300I0J-854D01*
G01X81799Y1739850D01*
G02X80705Y1739397I-1094J1094D01*
G01X80692Y1739410D01*
X77166D01*
G01X85341Y1752245D02*
G02X83744Y1751402I-2161J2161D01*
G02X83180Y1751350I-561J3004D01*
G01X82498D01*
G02X81972Y1751509I0J949D01*
G02X81829Y1751626I522J784D01*
G01X81701Y1751754D01*
G03X80737Y1751995I-963J-1804D01*
G01X80724Y1752008D01*
X77166D01*
G01X85194Y1748848D02*
G03X85199I3J102D01*
G01Y1748950D01*
G03X85084Y1749227I-391J0D01*
G01X84800Y1749511D01*
G03X83499Y1750050I-1301J-1301D01*
G01X82492D01*
G03X81558Y1749663I0J-1321D01*
G01X81293Y1749397D01*
G02X79963Y1748846I-1330J1330D01*
G01X79950Y1748859D01*
X77166D01*
G01X71773Y1828479D02*
X71786Y1828466D01*
X76883D01*
X78099Y1827250D01*
G01X82499Y1828613D02*
X81136Y1827250D01*
X78099D01*
G01X66023Y1828479D02*
X63570D01*
X62599Y1829450D01*
Y1832413D01*
X64999Y1834813D01*
Y1844390D01*
X65522Y1844913D01*
X76136D01*
X77499Y1843550D01*
Y1843113D01*
G01D02*
X82092D01*
X82629Y1843650D01*
X88962D01*
X89499Y1843113D01*
G01X83499Y1841550D02*
X81999Y1840050D01*
X76354D01*
X73854Y1837550D01*
X73749D01*
G01X73999Y1843113D02*
X68462D01*
X67949Y1842600D01*
G01X73749Y1837550D02*
X73499Y1837800D01*
Y1840050D01*
X73999Y1840550D01*
Y1843113D01*
G01X77249Y1849050D02*
X79999D01*
X81499Y1847550D01*
G01X82499Y1832613D02*
X81729Y1833383D01*
X79032D01*
X77999Y1832350D01*
G01X71773Y1831679D02*
X77328D01*
X77999Y1832350D01*
G01X67349Y1851900D02*
X70899D01*
X73749Y1849050D01*
G01D02*
Y1849300D01*
X75299Y1850850D01*
X88594D01*
X96394Y1843050D01*
X97999D01*
G01X85630Y61141D02*
X85643Y61128D01*
X97999D01*
X102999Y56128D01*
Y29050D01*
G01X97499Y90050D02*
X96421Y91128D01*
X85643D01*
X85630Y91141D01*
G01X105249Y145050D02*
G02X102199Y144278I-3050J5639D01*
G01X91629D01*
G02X91229Y144678I0J400D01*
G01Y145728D01*
G03X90829Y146128I-400J0D01*
G01X90816Y146141D01*
X85630D01*
G01X105249Y141550D02*
G03X102348Y142947I-3447J-3447D01*
G03X102114Y142967I-532J-4845D01*
G03X101802Y142978I-328J-4863D01*
G01X91629D01*
G03X91229Y142578I0J-400D01*
G01Y141528D01*
G02X90829Y141128I-400J0D01*
G01X90816Y141141D01*
X85630D01*
G01Y466653D02*
X85643Y466640D01*
X99089D01*
X100999Y468550D01*
G01X107499Y497050D02*
X107089Y496640D01*
X85643D01*
X85630Y496653D01*
G01X95500Y513400D02*
X96227Y514126D01*
G03X96600Y515028I-902J901D01*
G02X97500Y517200I3073J-1D01*
G01X97899Y517599D01*
G02X101161Y518950I3261J-3261D01*
G01X109017D01*
G03X109499Y519149I1J680D01*
G01X109498D01*
X109799Y519450D01*
G03X110199Y520416I-966J966D01*
G01Y521588D01*
G03X109731Y522718I-1598J0D01*
G01X109188Y523260D01*
X109189Y523261D01*
G03X108398Y523588I-790J-790D01*
G01X107351D01*
G03X104695Y522488I0J-3756D01*
G01Y525988D02*
G03X107351Y524888I2656J2656D01*
G01X108399D01*
G02X110108Y524180I0J-2417D01*
G01X110368Y523919D01*
X110649Y523637D01*
X110650D01*
G02X111499Y521587I-2049J-2049D01*
G01Y520417D01*
G02X110718Y518531I-2666J-1D01*
G01Y518530D01*
X110418Y518230D01*
G02X109018Y517650I-1400J1400D01*
G01X101161D01*
G03X98819Y516680I0J-3312D01*
G01X98418Y516279D01*
G03X97901Y515027I1255J-1251D01*
G01X97900Y515028D01*
G03X98344Y513956I1516J0D01*
G01X98900Y513400D01*
G01X85630Y551653D02*
X90816D01*
X90829Y551640D01*
G02X91229Y551240I0J-400D01*
G01Y550190D01*
G03X91629Y549790I400J0D01*
G01X102303D01*
G03X105195Y550988I0J4090D01*
G01X85630Y546653D02*
X90816D01*
X90829Y546640D01*
G03X91229Y547040I0J400D01*
G01Y548090D01*
G02X91629Y548490I400J0D01*
G01X102776D01*
G02X105195Y547488I0J-3421D01*
G01X85630Y872165D02*
X85643Y872152D01*
X109601D01*
X109999Y872550D01*
G01X94999Y901550D02*
X94397Y902152D01*
X85643D01*
X85630Y902165D01*
G01X103295Y931489D02*
X103685Y931099D01*
G03X105399Y930389I1714J1714D01*
G01X108110D01*
G03X108499Y930550I0J550D01*
G03X108845Y931385I-835J835D01*
G01Y931657D01*
G01X103295Y927989D02*
X103331Y928026D01*
G02X105532Y929070I2567J-2569D01*
G02X105899Y929089I371J-3612D01*
G01X107538D01*
G02X108770Y928578I-1J-1743D01*
G01X109099Y928250D01*
G01X104795Y956489D02*
G02X101929Y955302I-2866J2866D01*
G01X91629D01*
G02X91229Y955702I0J400D01*
G01Y956752D01*
G03X90829Y957152I-400J0D01*
G01X90816Y957165D01*
X85630D01*
G01X104795Y952989D02*
G03X102349Y954002I-2446J-2446D01*
G01X91629D01*
G03X91229Y953602I0J-400D01*
G01Y952552D01*
G02X90829Y952152I-400J0D01*
G01X90816Y952165D01*
X85630D01*
G01X105500Y972000D02*
X103100D01*
X102100Y971000D01*
Y968500D01*
G01X105449Y967850D02*
X102599Y965000D01*
X99000D01*
G01X87349Y1000450D02*
X90000Y997799D01*
Y993100D01*
G01X92600Y996100D02*
X92250D01*
X91900Y996450D01*
Y999899D01*
X87349Y1004450D01*
G01X101999Y1086800D02*
X103899Y1088700D01*
X108149D01*
X108349Y1088900D01*
X122999D01*
X124349Y1087550D01*
X125999D01*
G01X97499Y1086800D02*
X101999D01*
G01X101349Y1081700D02*
X104349D01*
X105499Y1080550D01*
G01X101349Y1077400D02*
X105149D01*
X106499Y1076050D01*
X106718D01*
G01X106099Y1106640D02*
X101910D01*
X100700Y1107850D01*
G01X97250Y1115400D02*
X96950Y1115100D01*
X93500D01*
X92200Y1113800D01*
Y1108500D01*
X92850Y1107850D01*
X100700D01*
G01X101999Y1090300D02*
X107485D01*
X107685Y1090500D01*
X111949D01*
X112999Y1091550D01*
Y1097550D01*
X111439Y1099110D01*
X109749D01*
G01X100700Y1111350D02*
X102850Y1109200D01*
X106099D01*
G01X97250Y1115400D02*
Y1118321D01*
X99399Y1120470D01*
Y1135450D01*
X99999Y1136050D01*
X104999D01*
G01X94735Y1110135D02*
X96000Y1111400D01*
X100400D01*
X100700Y1111350D01*
G01X105499Y1201863D02*
X100686D01*
X99999Y1202550D01*
G01D02*
Y1204550D01*
X100999Y1205550D01*
X106010D01*
X106162Y1205702D01*
G01X112059Y1216863D02*
Y1215110D01*
X110499Y1213550D01*
X100999D01*
G01X106999Y1227363D02*
X101812D01*
X100499Y1226050D01*
G01X85630Y1277677D02*
X91372D01*
X98449Y1270600D01*
X127398D01*
X128397Y1269601D01*
X128500D01*
X128501Y1269600D01*
X138949D01*
X141499Y1267050D01*
G01X103499Y1297863D02*
X101686D01*
X101099Y1298450D01*
Y1306150D01*
X105999Y1311050D01*
G01X85630Y1307677D02*
X85643Y1307664D01*
X95499D01*
X98885Y1311050D01*
X105999D01*
G01X112499Y1329050D02*
X109449Y1326000D01*
X103600D01*
X100500Y1322900D01*
Y1319800D01*
X109099Y1311201D01*
Y1309700D01*
X113499Y1305300D01*
X114939D01*
G01X116499Y1321363D02*
X102700D01*
G01X104078Y1361952D02*
X103509Y1361383D01*
G02X102135Y1360814I-1374J1374D01*
G01X92424D01*
G02X91499Y1361739I0J925D01*
G03X90574Y1362664I-925J0D01*
G01X90561Y1362677D01*
X85630D01*
G01X104078Y1358452D02*
X103547Y1358983D01*
G03X102265Y1359514I-1282J-1282D01*
G01X92424D01*
G03X91499Y1358589I0J-925D01*
G02X90574Y1357664I-925J0D01*
G01X90561Y1357677D01*
X85630D01*
G01X102350Y1344500D02*
X102891Y1345040D01*
G02X104000Y1345500I1110J-1109D01*
G02X105365Y1344934I-1J-1931D01*
G01X105700Y1344600D01*
G01X102350Y1348154D02*
Y1348150D01*
G03X103500Y1347000I1150J0D01*
G03X105378Y1347778I0J2656D01*
G01X105700Y1348100D01*
G01X97229Y1373337D02*
X96813Y1373753D01*
G03X94975Y1374514I-1838J-1839D01*
G01X91629D01*
G03X91229Y1374114I0J-400D01*
G01Y1373064D01*
G02X90829Y1372664I-400J0D01*
G01X90816Y1372677D01*
X85630D01*
G01X97000Y1377600D02*
X96496Y1377097D01*
G02X93400Y1375814I-3097J3096D01*
G01X91629D01*
G02X91229Y1376214I0J400D01*
G01Y1377264D01*
G03X90829Y1377664I-400J0D01*
G01X90816Y1377677D01*
X85630D01*
G01X110925Y1484981D02*
X110924Y1484982D01*
Y1489125D01*
X110499Y1489550D01*
X100999D01*
X97999Y1486550D01*
G01X103999Y1472050D02*
X103094D01*
X101693Y1473451D01*
X98097D01*
X96199Y1475350D01*
X95899D01*
G01X83000Y1548250D02*
Y1545637D01*
X83932Y1544705D01*
G01X97499Y1554550D02*
X96449Y1553500D01*
X92750D01*
G01X112599Y1513600D02*
Y1539811D01*
X97860Y1554550D01*
X97499D01*
G01X96999Y1558050D02*
X97048D01*
X116699Y1538399D01*
Y1513650D01*
X116749Y1513600D01*
G01X83000Y1551750D02*
Y1554929D01*
X82429Y1555500D01*
G01X96999Y1558050D02*
X96449Y1557500D01*
X92750D01*
G01X104999Y1702113D02*
X103562D01*
X92499Y1713176D01*
X85643D01*
X85630Y1713189D01*
G01X103749Y1764050D02*
G03X101393Y1765026I-2356J-2356D01*
G01X91629D01*
G03X91563Y1765020I3J-400D01*
G03X91229Y1764626I65J-394D01*
G01Y1763576D01*
G02X90829Y1763176I-400J0D01*
G01X90816Y1763189D01*
X85630D01*
G01X103749Y1767550D02*
G02X100794Y1766326I-2955J2955D01*
G01X91629D01*
G02X91229Y1766726I0J400D01*
G01Y1767050D01*
G03X90946Y1767733I-966J0D01*
G01X90814Y1767865D01*
G03X90063Y1768176I-751J-751D01*
G01X90050Y1768189D01*
X85630D01*
G01X108749Y126050D02*
X109999D01*
G03X110994Y126462I0J1407D01*
G01X111458Y126926D01*
G02X111999Y127150I541J-541D01*
G01X114499D01*
G02X115876Y125973I0J-1394D01*
G01X108749Y129550D02*
X109999D01*
G02X110994Y129138I0J-1407D01*
G01X111385Y128747D01*
G03X111544Y128618I715J719D01*
G03X111950Y128450I406J406D01*
G01X114999D01*
G03X115876Y129327I0J877D01*
G01Y130050D01*
G01X128249Y252550D02*
X126874Y251175D01*
G02X126089Y250850I-785J785D01*
G01X123823D01*
G02X123099Y251150I0J1024D01*
G01X122798Y251451D01*
G02X122397Y252419I968J968D01*
G01Y252688D01*
G01X128249Y249050D02*
G03X127042Y249550I-1207J-1207D01*
G01X123765D01*
G03X122799Y249150I0J-1366D01*
G01X159055Y1051142D02*
X162609D01*
X162622Y1051129D01*
G03X163469Y1051480I0J1198D01*
G01X163919Y1051930D01*
G02X164692Y1052250I773J-773D01*
G01X166799D01*
G02X167899Y1051150I0J-1100D01*
G01Y1007504D01*
G02X165979Y1002869I-6555J0D01*
G01X148730Y985620D01*
G03X147299Y982165I3454J-3454D01*
G01Y752036D01*
X147300Y752035D01*
Y745550D01*
G02X145349Y740839I-6663J0D01*
G01X145160Y740649D01*
X145159D01*
X123247Y718738D01*
G03X121191Y714710I5188J-5187D01*
G03X121099Y713551I7244J-1158D01*
G01Y638233D01*
G03X121679Y636830I1983J-1D01*
G01X121780Y636730D01*
G03X123865Y636178I1518J1521D01*
G01X124368D01*
G02X125227Y635822I0J-1214D01*
G01X125499Y635550D01*
G01Y638950D02*
X124615Y638066D01*
G02X123522Y637432I-1739J1740D01*
G02X122699Y637650I-223J819D01*
G01X122599Y637750D01*
G02X122399Y638233I483J483D01*
G01Y713550D01*
G02X122475Y714504I6036J-1D01*
G02X124167Y717818I5960J-954D01*
G01X145698Y739349D01*
X145699D01*
X146269Y739919D01*
G03X148600Y745551I-5633J5630D01*
G01Y752574D01*
X148599Y752575D01*
Y982165D01*
G02X149649Y984700I3585J0D01*
G01X166899Y1001950D01*
G03X169199Y1007503I-5555J5554D01*
G01Y1051150D01*
G03X166799Y1053550I-2400J0D01*
G01X164494D01*
G02X163649Y1053900I0J1195D01*
G03X163299Y1054149I-913J-913D01*
G03X162988Y1054278I-311J-311D01*
G01X162975Y1054291D01*
X159055D01*
G01X110499Y834550D02*
X106499D01*
G01X129249Y1063550D02*
X126073Y1060374D01*
G03X124699Y1057057I3317J-3317D01*
G01Y1055740D01*
G02X124583Y1055006I-2390J2D01*
G02X124116Y1054176I-2275J733D01*
G02X123999Y1054050I-1809J1562D01*
G01X129249Y1060050D02*
X128206D01*
G03X126999Y1059550I0J-1707D01*
G03X125999Y1057136I2414J-2414D01*
G01Y1052550D01*
G02X124099Y1050650I-1900J0D01*
G01X123999D01*
G01X116700Y1063500D02*
Y1075106D01*
X119899Y1078305D01*
Y1081201D01*
X115300Y1085800D01*
X114559D01*
G01X105499Y1080550D02*
X106749Y1079300D01*
X109439D01*
G01X106718Y1076050D02*
X107499D01*
X107999Y1075550D01*
X111499D01*
X111999Y1076050D01*
Y1079300D01*
G01X124423Y1077523D02*
X124752Y1077851D01*
G02X126800Y1078700I2049J-2048D01*
G02X129019Y1077781I0J-3138D01*
G01X129200Y1077600D01*
G01X124423Y1081177D02*
X124752Y1080849D01*
G03X126800Y1080000I2049J2048D01*
G03X129019Y1080919I0J3138D01*
G01X129200Y1081100D01*
G01X119499Y1106300D02*
X128499D01*
X134999Y1099800D01*
Y1093050D01*
X129499Y1087550D01*
X125999D01*
G01X120749Y1093990D02*
X116249D01*
G01X124730Y1094482D02*
X121241D01*
X120749Y1093990D01*
G01X123999Y1102550D02*
Y1102050D01*
G01X116249Y1096550D02*
X118499D01*
X123999Y1102050D01*
G01X124730Y1098482D02*
X123999Y1099213D01*
Y1102050D01*
G01X113499Y1109200D02*
X118899D01*
X119499Y1109800D01*
G01D02*
X124249D01*
X124999Y1110550D01*
G01X108999Y1102050D02*
X109749Y1101300D01*
Y1099110D01*
G01X113499Y1111760D02*
X118709D01*
X121999Y1115050D01*
Y1117050D01*
G01X122249Y1125050D02*
X121999Y1124800D01*
Y1117050D01*
G01X138600Y1124600D02*
X138150Y1125050D01*
X122249D01*
G01X114499Y1135050D02*
X113499Y1136050D01*
X104999D01*
G01X106162Y1205702D02*
X106939Y1206479D01*
Y1210363D01*
G01X115499Y1197550D02*
Y1199363D01*
X112999Y1201863D01*
X109499D01*
G01D02*
Y1210363D01*
G01X116499Y1223863D02*
Y1215050D01*
X117499Y1214050D01*
G01X123299Y1216113D02*
X119562D01*
X117499Y1214050D01*
G01X123299Y1213553D02*
X126253D01*
X127499Y1214799D01*
Y1224363D01*
G01X123299Y1213553D02*
Y1206900D01*
G01X111999Y1227363D02*
X106999D01*
G01X116499D02*
X111999D01*
G01X127499Y1224363D02*
X126760D01*
X123970Y1221573D01*
G01X111999Y1223863D02*
Y1216923D01*
X112059Y1216863D01*
G01X107999Y1298113D02*
X103749D01*
X103499Y1297863D01*
G01X124550Y1319900D02*
Y1317850D01*
X122200Y1315500D01*
Y1309751D01*
X121149Y1308700D01*
X117900D01*
X117400Y1308200D01*
Y1303431D01*
X112749Y1298780D01*
Y1298113D01*
G01D02*
X107999D01*
G01X120507Y1317050D02*
X120059Y1316602D01*
Y1311800D01*
G01X120507Y1321446D02*
Y1317050D01*
G01X107999Y1304113D02*
Y1307713D01*
G01X117499Y1311800D02*
Y1314888D01*
X117487Y1314900D01*
Y1320375D01*
X116499Y1321363D01*
G01X104078Y1336952D02*
X104598Y1336433D01*
G03X105999Y1335852I1402J1401D01*
G01X106999D01*
G03X108690Y1336553I-1J2392D01*
G01X109228Y1337090D01*
G01X104078Y1333452D02*
X104598Y1333971D01*
G02X105999Y1334552I1402J-1401D01*
G01X106999D01*
G02X108693Y1333851I1J-2395D01*
G01X109228Y1333315D01*
G01X119499Y1339050D02*
Y1338050D01*
X116499Y1335050D01*
G01X120249Y1343050D02*
X119499Y1342300D01*
Y1339050D01*
G01X123749Y1343050D02*
Y1338658D01*
X114141Y1329050D01*
X112499D01*
G01X113999Y1380550D02*
Y1375880D01*
X121500Y1368379D01*
Y1367510D01*
X122600Y1366410D01*
Y1364946D01*
X122800Y1364746D01*
Y1364700D01*
X126500Y1361000D01*
X128250D01*
G01X119749Y1352050D02*
X115499Y1356300D01*
Y1364550D01*
G01X107578Y1358452D02*
Y1358540D01*
G02X107641Y1358692I214J0D01*
G01X108039Y1359090D01*
G02X109154Y1359552I1115J-1114D01*
G01X110603D01*
G02X112300Y1358849I0J-2400D01*
G01X112440Y1358709D01*
Y1358196D01*
G01X107578Y1361952D02*
X107837D01*
G02X108280Y1361769I1J-626D01*
G01X108647Y1361402D01*
G03X109975Y1360852I1328J1328D01*
G01X111314D01*
G03X112999Y1361550I0J2383D01*
G01X129749Y1351550D02*
X123749D01*
X123249Y1352050D01*
G01D02*
Y1356050D01*
G01X127749Y1342050D02*
X126749Y1343050D01*
X123749D01*
G01X113500Y1344500D02*
X113207Y1344793D01*
G03X111500Y1345500I-1707J-1707D01*
G01X111373D01*
G03X109200Y1344600I0J-3073D01*
G01Y1348100D02*
X109452Y1347849D01*
G03X111500Y1347000I2049J2048D01*
G03X112944Y1347598I0J2042D01*
G01X113500Y1348154D01*
G01X123500Y1372000D02*
X124645D01*
X131645Y1365000D01*
X131750D01*
G01X117390Y1426201D02*
X117945Y1426756D01*
G02X119283Y1427310I1338J-1339D01*
G01X143574D01*
G02X144499Y1426385I0J-925D01*
G03X145424Y1425460I925J0D01*
G01X145437Y1425473D01*
X150591D01*
G01Y1430473D02*
X146745D01*
X146732Y1430460D01*
G03X144499Y1429535I0J-3158D01*
G01X143980Y1429017D01*
G02X142999Y1428610I-982J981D01*
G01X128243D01*
G02X127998Y1428855I0J245D01*
G03X127753Y1429100I-245J0D01*
G01X125843D01*
G03X125598Y1428855I0J-245D01*
G02X125353Y1428610I-245J0D01*
G01X119283D01*
G02X117945Y1429164I0J1893D01*
G01X117572Y1429538D01*
G02X117390Y1429976I438J439D01*
G01X127640Y1441241D02*
X127474D01*
G02X127191Y1441358I0J401D01*
G01X126140Y1442409D01*
G03X124799Y1443085I-1696J-1697D01*
G03X124443Y1443112I-359J-2373D01*
G01X106857D01*
G03X105498Y1442549I0J-1922D01*
G01X105413Y1442464D01*
G03X104935Y1441310I1154J-1154D01*
G01Y1440634D01*
G01X127640Y1444741D02*
X127475Y1444576D01*
G02X127078Y1444412I-397J399D01*
G01X105902D01*
G02X105264Y1444676I0J903D01*
G01X104999Y1444941D01*
G01X124290Y1469241D02*
X127640D01*
G01Y1465741D02*
X126907Y1466474D01*
G03X125999Y1466850I-908J-908D01*
G01X125794D01*
G03X124297Y1466230I0J-2117D01*
G03X123808Y1465050I1179J-1180D01*
G01X113485Y1484981D02*
X113484Y1484980D01*
Y1478065D01*
X115499Y1476050D01*
G01D02*
Y1472100D01*
X115599Y1472000D01*
G01D02*
X119049D01*
X120499Y1470550D01*
G01X111499Y1476050D02*
X110924Y1476625D01*
Y1484980D01*
X110925Y1484981D01*
G01X111499Y1472050D02*
Y1476050D01*
G01X108365Y1484981D02*
X108364Y1484980D01*
Y1480415D01*
X103999Y1476050D01*
G01D02*
Y1472050D01*
G01X110925Y1501161D02*
X110924Y1501162D01*
Y1507725D01*
X107699Y1510950D01*
G01X121499Y1511050D02*
X120549Y1510100D01*
X116749D01*
G01D02*
X116045Y1509396D01*
Y1501161D01*
G01X113485D02*
Y1509214D01*
X112599Y1510100D01*
G01X108000Y1517000D02*
Y1514804D01*
X112599Y1510205D01*
Y1510100D01*
G01X150591Y1525473D02*
X150578Y1525460D01*
X119089D01*
X118999Y1525550D01*
G01X109499Y1702613D02*
X105499D01*
X104999Y1702113D01*
G01X109499Y1708613D02*
Y1712213D01*
G01X112753Y1716613D02*
Y1716804D01*
X113499Y1717550D01*
X117249D01*
G01X109249Y1716613D02*
X112753D01*
G01X122642Y1704243D02*
Y1706907D01*
X121499Y1708050D01*
G01D02*
X121099Y1708450D01*
X115399D01*
X113999Y1707050D01*
Y1702613D01*
G01D02*
X109499D01*
G01X109249Y1720613D02*
Y1725800D01*
G01D02*
X111849D01*
X112562Y1725087D01*
Y1720613D01*
G01D02*
X113436D01*
X113939Y1720110D01*
X117249D01*
G01X123749Y1714990D02*
Y1711550D01*
G01X105249Y1743050D02*
X105395Y1742905D01*
G03X107699Y1741950I2305J2304D01*
G03X108041Y1742091I1J483D01*
G01X109499Y1743550D01*
G01X105249Y1739550D02*
X105395Y1739695D01*
G02X107699Y1740650I2305J-2304D01*
G02X109079Y1740079I1J-1951D01*
G01X109399Y1739758D01*
Y1739550D01*
G01X128342Y1870754D02*
X128299Y1870798D01*
G03X125999Y1871750I-2299J-2300D01*
G01X124999D01*
G03X123779Y1871244I1J-1726D01*
G01X123393Y1870859D01*
G01X128342Y1874254D02*
X128121Y1874033D01*
G02X125999Y1873154I-2122J2122D01*
G01X125299D01*
G02X124263Y1873583I0J1465D01*
G01X123592Y1874254D01*
G01X131749Y224550D02*
G02X134704Y225774I2955J-2955D01*
G01X144590D01*
G02X144990Y225374I0J-400D01*
G01Y224324D01*
G03X145390Y223924I400J0D01*
G01X145403Y223937D01*
X150591D01*
G01X131749Y228050D02*
G03X134105Y227074I2356J2356D01*
G01X144590D01*
G03X144990Y227474I0J400D01*
G01Y228524D01*
G02X145390Y228924I400J0D01*
G01X145403Y228937D01*
X150591D01*
G01X131749Y249050D02*
X131786Y249086D01*
G02X134031Y250150I2613J-2613D01*
G02X134251Y250166I378J-3676D01*
G02X134399Y250169I149J-3693D01*
G01X153000D01*
G02X153649Y249900I0J-918D01*
G03X154484Y249554I835J835D01*
G01X154497Y249567D01*
X159055D01*
G01X131749Y252550D02*
Y252066D01*
G03X131924Y251644I596J0D01*
G03X132346Y251469I422J421D01*
G01X152744D01*
G03X153557Y251702I0J1536D01*
G03X153830Y251919I-813J1303D01*
G01X154130Y252219D01*
X154201Y252289D01*
G02X155199Y252703I999J-998D01*
G01X155212Y252716D01*
X159055D01*
G01X141499Y427550D02*
X144752D01*
X145439Y426863D01*
G01X137749Y427113D02*
X141062D01*
X141499Y427550D01*
G01X147999Y426863D02*
Y421550D01*
X145999Y419550D01*
X144999D01*
G01X141499Y423050D02*
X144999Y419550D01*
G01X137749Y423113D02*
X141436D01*
X141499Y423050D01*
G01X146499Y443863D02*
X141499D01*
G01D02*
X138237D01*
X137500Y444600D01*
G01X135300Y524329D02*
X135499Y524130D01*
Y517550D01*
G01D02*
X135686Y517363D01*
X138999D01*
G01X143499Y517613D02*
X148249D01*
G01X138999Y517363D02*
X139249Y517613D01*
X143499D01*
G01X136000Y528750D02*
X135311Y528061D01*
Y524340D01*
X135300Y524329D01*
G01X137899Y545451D02*
X142800Y540550D01*
Y535299D01*
X143499Y534600D01*
Y523613D01*
G01X136000Y532250D02*
X136100Y532700D01*
Y534157D01*
X136099Y534158D01*
Y537000D01*
X134899Y538200D01*
G01X141125Y531550D02*
X136700D01*
X136000Y532250D01*
G01X145000Y539050D02*
Y543750D01*
X143750Y545000D01*
G01X143500Y557700D02*
Y550300D01*
G01X143750Y545000D02*
Y550050D01*
X143500Y550300D01*
G01X143750Y545000D02*
X142200D01*
X139100Y548100D01*
X139088D01*
X137688Y549500D01*
X135300D01*
G01X135188Y630065D02*
X135284Y630162D01*
G02X137999Y631286I2714J-2715D01*
G01X144590D01*
G02X144990Y630886I0J-400D01*
G01Y629836D01*
G03X145390Y629436I400J0D01*
G01X145403Y629449D01*
X150591D01*
G01X135188Y633565D02*
G03X137552Y632586I2364J2364D01*
G01X144590D01*
G03X144990Y632986I0J400D01*
G01Y634036D01*
G02X145390Y634436I400J0D01*
G01X145403Y634449D01*
X150591D01*
G01X131688Y658065D02*
X131161Y657539D01*
G02X129499Y656850I-1663J1662D01*
G01X128771D01*
G03X126598Y655950I-1J-3072D01*
G01X126597D01*
G03X125499Y653299I2653J-2652D01*
G01Y652050D01*
G03X126735Y649067I4218J0D01*
G01X126875Y648927D01*
X126874Y648925D01*
X128374Y647425D01*
G02X128591Y647108I-752J-747D01*
G02X128592Y647105I-1005J-337D01*
G02X128643Y646968I-965J-437D01*
G02X128657Y646433I-1019J-294D01*
G02X128374Y645925I-1033J242D01*
G01X127999Y645550D01*
G01X131400Y644600D02*
Y645102D01*
G03X130595Y647045I-2748J0D01*
G01X129931Y647708D01*
X127794Y649845D01*
Y649846D01*
X127795Y649847D01*
X127655Y649987D01*
G02X126799Y652051I2061J2064D01*
G01Y653298D01*
G02X127517Y655031I2451J0D01*
G02X128770Y655550I1253J-1253D01*
G01X129499D01*
G02X131555Y654699I1J-2907D01*
G01X131688Y654565D01*
G01X144238Y645356D02*
G02X145432Y646550I1194J0D01*
G01X153199D01*
G02X154564Y645984I-1J-1931D01*
G03X155450Y645617I886J886D01*
G01X155463Y645630D01*
X159055D01*
G01X144238Y649131D02*
G03X145519Y647850I1281J0D01*
G01X153633D01*
G03X154599Y648250I0J1366D01*
G02X155845Y648766I1246J-1246D01*
G01X155858Y648779D01*
X159055D01*
G01X135188Y654565D02*
G02X138773Y656050I3585J-3585D01*
G01X153999D01*
G02X154088Y656041I-6J-499D01*
G02X154499Y655550I-88J-491D01*
G03X154983Y655066I484J0D01*
G01X154996Y655079D01*
X159055D01*
G01X135188Y658065D02*
G03X136914Y657350I1726J1726D01*
G01X153999D01*
G03X154087Y657359I4J400D01*
G03X154399Y657750I-89J391D01*
G02X154864Y658215I465J0D01*
G01X154877Y658228D01*
X159055D01*
G01X132749Y1035550D02*
G02X134546Y1036621I3013J-3013D01*
G02X134835Y1036696I1214J-4084D01*
G02X135762Y1036798I927J-4159D01*
G01X144590D01*
G02X144990Y1036398I0J-400D01*
G01Y1035348D01*
G03X145390Y1034948I400J0D01*
G01X145403Y1034961D01*
X150591D01*
G01X132749Y1039050D02*
G03X134063Y1038248I2313J2313D01*
G01X134303Y1038171D01*
G03X134514Y1038138I211J657D01*
G03X135062Y1038092I547J3225D01*
G01X135497D01*
G02X135762Y1038098I258J-5555D01*
G01X144590D01*
G03X144990Y1038498I0J400D01*
G01Y1039548D01*
G02X145390Y1039948I400J0D01*
G01X145403Y1039961D01*
X150591D01*
G01X132749Y1060050D02*
X133247Y1060547D01*
G02X135399Y1061439I2153J-2152D01*
G01X153583D01*
G02X154293Y1061145I0J-1004D01*
G01X154543Y1060895D01*
G03X155308Y1060578I765J765D01*
G01X155321Y1060591D01*
X159055D01*
G01X132749Y1063550D02*
G03X134707Y1062739I1958J1958D01*
G01X153124D01*
G03X153892Y1063057I0J1086D01*
G01X154242Y1063407D01*
G02X155015Y1063727I773J-773D01*
G01X155028Y1063740D01*
X159055D01*
G01X137481Y1077557D02*
X136825Y1078214D01*
G03X135650Y1078700I-1174J-1175D01*
G01X135250D01*
G03X132774Y1077675I-1J-3501D01*
G01X132700Y1077600D01*
G01X137477Y1081177D02*
X136759Y1080460D01*
G02X135650Y1080000I-1110J1109D01*
G01X135250D01*
G02X132774Y1081025I-1J3501D01*
G01X132700Y1081100D01*
G01X150591Y1119961D02*
X150578Y1119948D01*
X127897D01*
X126999Y1119050D01*
G01X139650Y1210400D02*
Y1214962D01*
X138499Y1216113D01*
G01X139650Y1210400D02*
Y1203139D01*
X140911Y1201878D01*
G01X136150Y1210400D02*
Y1212050D01*
X132087Y1216113D01*
X130699D01*
G01X135400Y1205700D02*
Y1209650D01*
X136150Y1210400D01*
G01X130699Y1218673D02*
X134376D01*
X136936Y1216113D01*
X138499D01*
G01X130699Y1218673D02*
Y1223063D01*
X131999Y1224363D01*
G01X128050Y1319900D02*
X128100Y1319850D01*
Y1316844D01*
X129339Y1315605D01*
X129699D01*
G01X125725Y1326750D02*
Y1322225D01*
X128050Y1319900D01*
G01X131249Y1342050D02*
X131298Y1342001D01*
X135601D01*
X136200Y1342600D01*
G01X147400Y1327100D02*
X140000D01*
G01D02*
X137500D01*
X136800Y1327800D01*
Y1332600D01*
X138650Y1334450D01*
Y1335800D01*
G01X129600Y1334250D02*
X131150Y1335800D01*
X138650D01*
G01X148000Y1346500D02*
X147500D01*
X142450Y1351550D01*
X129749D01*
G01X137249Y1347675D02*
Y1343649D01*
X136200Y1342600D01*
G01X131140Y1441241D02*
X131674Y1441775D01*
G02X132965Y1442310I1291J-1290D01*
G01X144074D01*
G02X144999Y1441385I0J-925D01*
G03X145924Y1440460I925J0D01*
G01X145937Y1440473D01*
X150591D01*
G01X131140Y1444741D02*
Y1444605D01*
G03X131236Y1444373I328J0D01*
G01X131570Y1444040D01*
G03X132606Y1443610I1037J1036D01*
G01X144074D01*
G03X144999Y1444535I0J925D01*
G02X145924Y1445460I925J0D01*
G01X145937Y1445473D01*
X150591D01*
G01X142999Y1456373D02*
X143452Y1456827D01*
G02X145199Y1457550I1746J-1747D01*
G01X153019D01*
G02X153994Y1457146I0J-1379D01*
G03X154436Y1456826I1219J1219D01*
G03X154883Y1456641I447J447D01*
G01X154896Y1456654D01*
X159055D01*
G01X131140Y1465741D02*
G02X134216Y1467015I3076J-3076D01*
G01X152056D01*
G02X153550Y1466396I0J-2113D01*
G03X154289Y1466090I739J739D01*
G01X154302Y1466103D01*
X159055D01*
G01X131140Y1469241D02*
G03X133376Y1468315I2236J2236D01*
G01X152507D01*
G03X153799Y1468850I0J1827D01*
G02X154738Y1469239I939J-939D01*
G01X154751Y1469252D01*
X159055D01*
G01X142900Y1460000D02*
G03X145676Y1458850I2776J2776D01*
G01X153106D01*
G03X153710Y1459032I0J1093D01*
G03X153879Y1459170I-603J911D01*
G01X154129Y1459420D01*
G02X155022Y1459790I893J-893D01*
G01X155035Y1459803D01*
X159055D01*
G01X131999Y1710050D02*
X132939Y1710990D01*
Y1714800D01*
G01X131999Y1706800D02*
Y1710050D01*
G01X135999Y1706800D02*
Y1709650D01*
X135499Y1710150D01*
G01D02*
Y1714800D01*
G01X144999Y1711050D02*
X144249Y1711800D01*
Y1718550D01*
G01D02*
X141499Y1721300D01*
X138059D01*
G01X131842Y1846254D02*
G02X135627Y1847822I3785J-3785D01*
G01X144590D01*
G02X144990Y1847422I0J-400D01*
G01Y1846372D01*
G03X145390Y1845972I400J0D01*
G01X145403Y1845985D01*
X150591D01*
G01X131842Y1849754D02*
G03X133368Y1849122I1526J1526D01*
G01X144590D01*
G03X144990Y1849522I0J400D01*
G01Y1850572D01*
G02X145390Y1850972I400J0D01*
G01X145403Y1850985D01*
X150591D01*
G01X137999Y1861497D02*
X138363Y1861861D01*
G02X141222Y1863076I2936J-2937D01*
G02X141299Y1863077I92J-4151D01*
G01X153280D01*
G02X154161Y1862712I0J-1246D01*
G03X155511Y1862153I1350J1350D01*
G01X155524Y1862166D01*
X159055D01*
G01X137999Y1865151D02*
X138903Y1864247D01*
G03X139560Y1864093I453J454D01*
G02X141196Y1864376I1737J-5169D01*
G02X141296Y1864377I105J-5451D01*
G01X153247D01*
G03X154184Y1864765I0J1325D01*
G01X154384Y1864965D01*
G02X155198Y1865302I814J-814D01*
G01X155211Y1865315D01*
X159055D01*
G01X131842Y1870754D02*
X132211Y1871122D01*
G02X135129Y1872502I3388J-3388D01*
G02X135599Y1872526I479J-4767D01*
G01X153034D01*
G02X154335Y1871987I0J-1840D01*
G03X155264Y1871602I929J929D01*
G01X155277Y1871615D01*
X159055D01*
G01X131842Y1874254D02*
G03X132875Y1873826I1033J1033D01*
G01X153353D01*
G03X154109Y1874139I0J1069D01*
G01X154409Y1874439D01*
G02X155162Y1874751I753J-753D01*
G01X155175Y1874764D01*
X159055D01*
G01X164448Y160447D02*
X164447Y160446D01*
Y156498D01*
X162499Y154550D01*
X162177D01*
G01X158249Y161050D02*
X160999Y158300D01*
Y155728D01*
X162177Y154550D01*
G01X158249Y165050D02*
X159652Y163647D01*
X164448D01*
G01D02*
X166402D01*
X167499Y162550D01*
Y156050D01*
X166999Y155550D01*
G01X149999Y243504D02*
X150876Y242627D01*
G03X151536Y242331I718J717D01*
G03X151593Y242330I46J1013D01*
G01X153285D01*
G03X154157Y242691I0J1233D01*
G01X154457Y242991D01*
G02X155092Y243254I635J-635D01*
G01X155105Y243267D01*
X159055D01*
G01X149999Y239729D02*
X151067Y240796D01*
G02X151632Y241030I565J-565D01*
G01X153199D01*
G02X154218Y240608I0J-1441D01*
G01X154437Y240389D01*
G03X155123Y240105I686J686D01*
G01X155136Y240118D01*
X159055D01*
G01X212578Y287448D02*
X212494Y287364D01*
X203313D01*
X194873Y278924D01*
X150604D01*
X150591Y278937D01*
G01Y308937D02*
X150604Y308924D01*
X176359D01*
X189799Y322364D01*
X253080D01*
X256894Y318550D01*
X284999D01*
X287999Y315550D01*
G01X150999Y440363D02*
Y438126D01*
X152159Y436966D01*
Y435403D01*
X155999Y431563D01*
Y431550D01*
X160499Y427050D01*
X161399D01*
X161999Y426450D01*
G01X162999Y443863D02*
X161999Y442863D01*
Y434050D01*
X161002Y433053D01*
X158299D01*
G01X156959Y426292D02*
Y427389D01*
X150985Y433363D01*
X150559D01*
G01X150999Y443863D02*
X146499D01*
G01X158299Y435613D02*
X155749D01*
X150999Y440363D01*
G01X159600Y446399D02*
X160499Y445500D01*
X160549D01*
X162186Y443863D01*
X162999D01*
G01X166999D02*
X165699Y442563D01*
Y438173D01*
G01X173999Y430050D02*
X171150D01*
X170000Y431200D01*
X169999Y431301D01*
Y435801D01*
X167627Y438173D01*
X165699D01*
G01X146499Y440363D02*
X150559Y436303D01*
Y433363D01*
G01X165699Y435613D02*
X167087D01*
X168399Y434301D01*
Y424951D01*
X168950Y424400D01*
G01X166437Y533288D02*
X166436Y533289D01*
Y537487D01*
X168049Y539100D01*
X169786D01*
X169836Y539150D01*
X176099D01*
X179499Y542550D01*
G01X166949Y524850D02*
X166053Y525746D01*
Y528944D01*
X166436Y529327D01*
Y533287D01*
X166437Y533288D01*
G01X151699Y524650D02*
X151899D01*
X155949Y520600D01*
X159199D01*
G01X159449Y524850D02*
X163876Y529277D01*
Y533287D01*
X163877Y533288D01*
G01X159199Y520600D02*
Y524600D01*
X159449Y524850D01*
G01X149000Y537500D02*
X151499D01*
X154049Y540050D01*
G01X155999Y535775D02*
Y536550D01*
X157549Y538100D01*
Y540050D01*
G01X166437Y549468D02*
X166436Y549469D01*
Y553913D01*
X162849Y557500D01*
X162500D01*
G01X150750Y540416D02*
Y540951D01*
X154049Y544250D01*
G01X157549Y540050D02*
X158599Y541100D01*
X168288D01*
X171557Y544369D01*
Y549468D01*
G01X156499Y548550D02*
X157549Y547500D01*
Y544250D01*
G01D02*
X158799Y543000D01*
X167500D01*
X168997Y544497D01*
Y549468D01*
G01X157749Y570050D02*
X158999D01*
X159903Y569146D01*
X164435D01*
X164448Y569159D01*
G01D02*
X165338D01*
X167200Y567297D01*
Y561000D01*
G01X164448Y565959D02*
X164357Y566050D01*
X157749D01*
G01D02*
Y562000D01*
G01X213299Y693800D02*
X205749D01*
X196385Y684436D01*
X150604D01*
X150591Y684449D01*
G01Y714449D02*
X150604Y714436D01*
X182936D01*
X198550Y730050D01*
X222550D01*
X223050Y730550D01*
X229948D01*
X231398Y729100D01*
X231449D01*
X238999Y721550D01*
X251600D01*
X255550Y725500D01*
X287049D01*
X288999Y723550D01*
G01X166499Y812363D02*
Y814550D01*
X165499Y815550D01*
G01D02*
X167439Y817490D01*
Y820363D01*
G01X167499Y836863D02*
X167045Y837317D01*
Y841004D01*
X166499Y841550D01*
G01X203439Y885300D02*
Y883800D01*
X200189Y880550D01*
X155019D01*
X151699Y883870D01*
Y925250D01*
X160999Y934550D01*
Y942550D01*
G01X153499Y918550D02*
X155469D01*
X156969Y917050D01*
G01X166499Y916113D02*
X162249D01*
X161999Y915863D01*
G01X171249Y916113D02*
X166499D01*
G01X161999Y915863D02*
X158156D01*
X156969Y917050D01*
G01X171100Y935000D02*
X171000D01*
X166499Y930499D01*
Y922113D01*
G01X152500Y960000D02*
Y956549D01*
X160999Y948050D01*
Y947274D01*
X161286Y946987D01*
Y946684D01*
X161600Y946370D01*
Y944630D01*
X160999Y944029D01*
Y942550D01*
G01X164448Y971471D02*
X164435Y971458D01*
X158341D01*
X158249Y971550D01*
G01D02*
Y968051D01*
X158800Y967500D01*
G01X158249Y975550D02*
X159141Y974658D01*
X164435D01*
X164448Y974671D01*
G01D02*
X165238D01*
X166948Y972961D01*
Y972947D01*
X167400Y972495D01*
Y967451D01*
X164999Y965050D01*
G01X212600Y1089961D02*
X150591D01*
G01X147400Y1327100D02*
X153100D01*
X153500Y1326700D01*
G01X164448Y1376983D02*
X164447Y1376982D01*
Y1373102D01*
X169999Y1367550D01*
X176999D01*
G01X164448Y1380183D02*
X165317D01*
X167499Y1378001D01*
Y1373050D01*
X169999Y1370550D01*
X171499D01*
G01X211914Y1504015D02*
X210964D01*
X202409Y1495460D01*
X150604D01*
X150591Y1495473D01*
G01X152600Y1681150D02*
Y1678000D01*
X152633Y1677967D01*
G01X161700Y1689550D02*
X163350Y1691200D01*
X170750D01*
G01X152600Y1684650D02*
X149350D01*
X148100Y1683400D01*
G01X157825Y1682050D02*
X155225Y1684650D01*
X152600D01*
G01X147749Y1718550D02*
Y1717550D01*
X150999Y1714300D01*
Y1713550D01*
G01X147749Y1722550D02*
Y1718550D01*
G01X158027Y1778300D02*
Y1782715D01*
X158221Y1782909D01*
G01X164448Y1782494D02*
X164033Y1782909D01*
X158221D01*
G01Y1786909D02*
X163233D01*
X164448Y1785694D01*
G01D02*
X165855D01*
X166999Y1784550D01*
Y1774550D01*
G01X150591Y1900985D02*
X150604Y1900972D01*
X211577D01*
X215499Y1897050D01*
X218499D01*
G01X233100Y1929800D02*
Y1929631D01*
X227419Y1923950D01*
X221216D01*
X220779Y1923513D01*
X216824D01*
X216624Y1923713D01*
X212565D01*
X212328Y1923950D01*
X165099D01*
X158077Y1930972D01*
X150604D01*
X150591Y1930985D01*
G01X170198Y160447D02*
X170197Y160446D01*
Y154852D01*
X171499Y153550D01*
G01X176749Y156550D02*
X173249Y153050D01*
X171999D01*
X171499Y153550D01*
G01X183149Y152000D02*
Y150900D01*
X184649Y149400D01*
X211349D01*
X218499Y156550D01*
Y183050D01*
G01X180249Y156550D02*
X183149Y153650D01*
Y152000D01*
G01X186649D02*
X191449D01*
G01X170198Y163647D02*
X171902D01*
X173515Y162034D01*
X173528D01*
X174512Y161050D01*
X176749D01*
G01D02*
Y160300D01*
X178499Y158550D01*
X190034D01*
X191009Y159525D01*
X196089D01*
X197064Y158550D01*
X200499D01*
X200999Y159050D01*
G01X186049Y161200D02*
X198149D01*
X201490Y164541D01*
X201561D01*
G01X180249Y161050D02*
X185899D01*
X186049Y161200D01*
G01X180249Y165050D02*
Y161050D01*
G01X176900Y424600D02*
Y427149D01*
X173999Y430050D01*
G01X172450Y424400D02*
X176700D01*
X176900Y424600D01*
G01X168950Y424400D02*
X168900Y423800D01*
Y419100D01*
G01X172499Y491053D02*
X175199Y488353D01*
X176999D01*
G01X181899Y496400D02*
X176549D01*
X172499Y492350D01*
Y491053D01*
G01X176799Y493850D02*
X176999Y493650D01*
Y490913D01*
G01X185999Y496400D02*
X184949D01*
X182399Y493850D01*
X176799D01*
G01X183499Y485793D02*
X186707D01*
X188000Y484500D01*
G01X168997Y533288D02*
Y536297D01*
X170250Y537550D01*
X177999D01*
X179000Y536549D01*
Y535500D01*
G01X174449Y524850D02*
Y525400D01*
X168997Y530852D01*
Y533288D01*
G01X174199Y520600D02*
X174449Y520850D01*
Y524850D01*
G01X167199Y520600D02*
Y524600D01*
X166949Y524850D01*
G01X172199Y557108D02*
X172372Y557281D01*
Y557638D01*
X172542Y557808D01*
Y558083D01*
X174000Y559541D01*
Y561301D01*
X176749Y564050D01*
G01X180249D02*
X177999Y561800D01*
Y559300D01*
G01D02*
X183149D01*
G01D02*
Y556450D01*
X183499Y556100D01*
G01X186649Y559300D02*
X187899Y558050D01*
X193999D01*
G01X170198Y569159D02*
X170211Y569146D01*
X175653D01*
X176749Y568050D01*
G01D02*
Y567300D01*
X177999Y566050D01*
X189499D01*
X190499Y567050D01*
X198999D01*
X200999Y565050D01*
G01X186049Y568400D02*
X186699Y569050D01*
X199652D01*
X200417Y569815D01*
G01X180249Y568050D02*
X185699D01*
X186049Y568400D01*
G01X180249Y572050D02*
Y568050D01*
G01X170198Y565959D02*
X170211Y565946D01*
X174853D01*
X176749Y564050D01*
G01X170499Y812363D02*
Y814472D01*
X169106Y815865D01*
G01D02*
Y816657D01*
X169999Y817550D01*
Y820363D01*
G01X181799Y834113D02*
X179249D01*
X178499Y833363D01*
X176499D01*
G01D02*
Y829550D01*
X179999Y826050D01*
G01X185999Y842363D02*
X184502Y840866D01*
Y834256D01*
X184499Y834253D01*
Y833023D01*
X183029Y831553D01*
X181799D01*
G01X237499Y900050D02*
Y832799D01*
X219200Y814500D01*
X196400D01*
X186499Y824401D01*
Y841863D01*
X185999Y842363D01*
G01X179499Y820550D02*
X178499D01*
X172559Y826490D01*
Y826863D01*
G01X172499Y833363D02*
X172559Y833303D01*
Y826863D01*
G01X172499Y836863D02*
X167499D01*
G01X176499D02*
X172499D01*
G01X171250Y922700D02*
X169500Y920950D01*
Y917862D01*
X171249Y916113D01*
G01X180025Y918250D02*
X175575Y922700D01*
X174750D01*
G01X183900Y944500D02*
Y937100D01*
G01X183850Y931600D02*
X183900Y931550D01*
Y925750D01*
G01X183850Y931600D02*
Y937050D01*
X183900Y937100D01*
G01Y925750D02*
X184100Y925500D01*
X194800D01*
G01X171000Y927000D02*
X173100D01*
X174800Y925300D01*
Y922500D01*
X174750Y922700D01*
G01X183649Y963100D02*
X182099Y961550D01*
X178999D01*
G01X172000Y961000D02*
X172550Y961550D01*
X178999D01*
G01X170198Y974671D02*
X174378D01*
X176499Y972550D01*
G01D02*
Y971550D01*
X178499Y969550D01*
X182499D01*
X183499Y968550D01*
X188499D01*
X190999Y971050D01*
X199999D01*
G01X188499Y982050D02*
X187999Y981550D01*
Y974050D01*
X186049Y972100D01*
G01X179999Y972550D02*
X180449Y972100D01*
X186049D01*
G01X179999Y976550D02*
Y972550D01*
G01X170198Y971471D02*
X170197Y971470D01*
Y966352D01*
X171499Y965050D01*
G01X176749Y967550D02*
X174749Y965550D01*
X171999D01*
X171499Y965050D01*
G01X180249Y967550D02*
X183649Y964150D01*
Y963100D01*
G01X187149D02*
X187699Y962550D01*
X193549D01*
G01X179499Y1275550D02*
X177936Y1277113D01*
X171499D01*
G01X186000Y1382400D02*
X188302D01*
X188849Y1381853D01*
Y1379450D01*
X191249Y1377050D01*
G01X170198Y1380183D02*
X170211Y1380170D01*
X172948D01*
X175178Y1382400D01*
X186000D01*
G01X170198Y1376983D02*
X172024D01*
X175220Y1380179D01*
X186770D01*
X187249Y1379700D01*
Y1375800D01*
X189999Y1373050D01*
X191249D01*
G01X180500Y1376550D02*
X176999Y1373049D01*
Y1367550D01*
G01X184600Y1376550D02*
X182571Y1378579D01*
X179528D01*
X171499Y1370550D01*
G01X174499Y1653113D02*
Y1656050D01*
X171999Y1658550D01*
G01D02*
Y1662250D01*
G01X179999Y1650427D02*
X179185Y1649613D01*
X174499D01*
G01D02*
X170436D01*
X168999Y1651050D01*
G01X200900Y1657200D02*
X186613D01*
X183099Y1653686D01*
Y1648550D01*
X182416Y1647867D01*
X179999D01*
G01X192800Y1654550D02*
X191237Y1652987D01*
X187399D01*
G01X188499Y1640613D02*
X184699Y1644413D01*
Y1652000D01*
X185686Y1652987D01*
X187399D01*
G01X192800Y1651050D02*
X192177Y1650427D01*
X187399D01*
G01X174800Y1678400D02*
Y1685800D01*
G01Y1678400D02*
Y1670800D01*
G01X172499Y1700113D02*
X178900D01*
G01D02*
X205499Y1673514D01*
Y1632050D01*
X204062Y1630613D01*
X198799D01*
G01X174800Y1685800D02*
Y1687150D01*
X170750Y1691200D01*
G01X172999Y1775050D02*
X174999Y1777050D01*
Y1780050D01*
X177314Y1782365D01*
Y1782613D01*
G01X170198Y1785694D02*
X170211Y1785681D01*
X174246D01*
X177314Y1782613D01*
G01X186549Y1782500D02*
X198949D01*
X201199Y1784750D01*
X201499D01*
G01X180814Y1782613D02*
X180927Y1782500D01*
X186549D01*
G01X180814Y1786613D02*
Y1782613D01*
G01X170198Y1782494D02*
X170197Y1782493D01*
Y1773852D01*
X171999Y1772050D01*
X177314D01*
G01Y1778613D02*
Y1772050D01*
G01X182649Y1773200D02*
Y1770400D01*
X184999Y1768050D01*
X194999D01*
X200499Y1773550D01*
Y1780050D01*
X201499Y1781050D01*
G01X180814Y1778613D02*
Y1775035D01*
X182649Y1773200D01*
G01X186149D02*
X187799Y1771550D01*
X192999D01*
G01X193549Y157325D02*
Y154100D01*
X191449Y152000D01*
G01X215400Y516400D02*
X213900D01*
X211613Y514113D01*
X206499D01*
G01X193549Y564525D02*
X194499Y563575D01*
Y558550D01*
X193999Y558050D01*
G01X198499Y828613D02*
X195887D01*
X193816Y830684D01*
Y833316D01*
X192131Y835001D01*
Y836050D01*
X191508Y836673D01*
X189199D01*
G01X198850Y823000D02*
Y828262D01*
X198499Y828613D01*
G01X198850Y823000D02*
X204000D01*
G01X195350D02*
X192184Y826166D01*
Y832684D01*
X190756Y834113D01*
X189199D01*
G01X204000Y817500D02*
X200400Y821100D01*
X197510D01*
X195610Y823000D01*
X195350D01*
G01X190499Y842363D02*
X189199Y841063D01*
Y836673D01*
G01X208559Y891800D02*
X208950D01*
X211750Y894600D01*
G01X205999Y891800D02*
Y898263D01*
G01X200799Y896600D02*
X202637D01*
X204300Y898263D01*
X205999D01*
G01X193549Y962550D02*
Y968225D01*
G01X199149Y1362900D02*
Y1360200D01*
X197999Y1359050D01*
G01X199149Y1367400D02*
Y1362900D01*
G01X216499Y1377550D02*
X215749Y1376800D01*
X200549D01*
G01X194749Y1377050D02*
X200299D01*
X200549Y1376800D01*
G01X194749Y1381050D02*
Y1377050D01*
G01X191249Y1373050D02*
Y1368300D01*
X190499Y1367550D01*
G01X194749Y1373050D02*
Y1371800D01*
X199149Y1367400D01*
G01X202649D02*
X203499Y1366550D01*
X208999D01*
G01X208049Y1372925D02*
X208999Y1371975D01*
Y1366550D01*
G01X198799Y1630613D02*
X201499Y1633313D01*
Y1656601D01*
X200900Y1657200D01*
G01X198799Y1635113D02*
Y1638750D01*
X196936Y1640613D01*
X194999D01*
G01D02*
X188499D01*
G01X192800Y1651050D02*
X197050D01*
X198300Y1649800D01*
G01X194049Y1778625D02*
Y1772600D01*
X192999Y1771550D01*
G01X218499Y190550D02*
Y183050D01*
G01X225298Y281114D02*
Y277549D01*
X223899Y276150D01*
X221799D01*
G01X221498Y281114D02*
Y276451D01*
X221799Y276150D01*
G01X228650Y283000D02*
X226248Y285402D01*
Y287114D01*
G01X216998Y287364D02*
X212684D01*
X212600Y287448D01*
X212578D01*
G01X221498Y287114D02*
X221248Y287364D01*
X216998D01*
G01X226248Y287114D02*
X221498D01*
G01X220000Y516400D02*
X215400D01*
G01X350499Y715050D02*
X325999Y690550D01*
X263650D01*
X234600Y661500D01*
X227900D01*
X221499Y667901D01*
Y687550D01*
G01X216999Y693800D02*
X213299D01*
G01X221499Y693550D02*
X221249Y693800D01*
X216999D01*
G01X226250Y689500D02*
X226249Y689501D01*
Y693550D01*
G01D02*
X221499D01*
G01X234500Y690652D02*
X230902D01*
X229750Y689500D01*
G01X211750Y894600D02*
Y896512D01*
X209999Y898263D01*
G01X229999Y912613D02*
X237499Y905113D01*
Y900050D01*
G01X217500Y1084000D02*
Y1071181D01*
X219381Y1069300D01*
X221800D01*
G01X224500Y1082500D02*
Y1084105D01*
X225300Y1084905D01*
Y1085050D01*
X226800Y1086550D01*
G01D02*
X226400D01*
X222900Y1090050D01*
G01X234600Y1071560D02*
X227440D01*
X227028Y1071148D01*
G01X223700Y1078500D02*
X224600D01*
X227600Y1081500D01*
Y1082100D01*
X228000Y1082500D01*
G01X234000Y1089500D02*
Y1088500D01*
X228000Y1082500D01*
G01X217461Y1089961D02*
X217500Y1090000D01*
G01X217461Y1089961D02*
X212600D01*
G01X222900Y1090050D02*
X218699D01*
X218610Y1089961D01*
X217461D01*
G01X220999Y1497550D02*
Y1488769D01*
X220200Y1487970D01*
Y1486230D01*
X220700Y1485730D01*
Y1473799D01*
X229849Y1464650D01*
X282699D01*
X293999Y1475950D01*
X343699D01*
G01X233600Y1475800D02*
X231400D01*
X228250Y1478950D01*
Y1480100D01*
G01X223501Y1487433D02*
X224984Y1485950D01*
X232700D01*
G01D02*
X228250Y1481500D01*
Y1480100D01*
G01X220999Y1503550D02*
X220749Y1503800D01*
X216999D01*
G01X229650Y1499300D02*
X225499D01*
G01D02*
X221249Y1503550D01*
X220999D01*
G01X216999Y1503800D02*
X212129D01*
X211914Y1504015D01*
G01X227814Y1891113D02*
Y1887513D01*
G01X218100Y1880400D02*
X225500D01*
G01D02*
X230950D01*
X231000Y1880450D01*
G01X218499Y1897050D02*
X223371D01*
X223436Y1897115D01*
G01X227814Y1897113D02*
X232064D01*
X232314Y1897363D01*
G01X223436Y1897115D02*
X227812D01*
X227814Y1897113D01*
G01X231500Y269350D02*
X231400Y268300D01*
Y262800D01*
G01X244600Y275100D02*
Y282500D01*
G01X240550Y269700D02*
X240200Y269350D01*
X231500D01*
G01X240550Y269700D02*
X244600Y273750D01*
Y275100D01*
G01X232150Y283000D02*
X232650Y283500D01*
X236800D01*
G01X235375Y276850D02*
Y279775D01*
X232150Y283000D01*
G01X239300Y669600D02*
X240000Y670300D01*
Y676700D01*
X239950Y677100D01*
G01X244000Y682500D02*
Y689900D01*
G01X230900Y676250D02*
X239100D01*
X239950Y677100D01*
G01D02*
X244000Y681150D01*
Y682500D01*
G01X234775Y683750D02*
Y690377D01*
X234500Y690652D01*
G01X234600Y1071560D02*
X242000D01*
G01X247500Y1078500D02*
Y1075500D01*
X243560Y1071560D01*
X242000D01*
G01X241500Y1085625D02*
Y1081500D01*
X244300Y1078700D01*
X247300D01*
X247500Y1078500D01*
G01X247299Y1136650D02*
X251450D01*
X251500Y1136700D01*
G01X241000Y1475800D02*
X233600D01*
G01X242700Y1499400D02*
X233300D01*
X233150Y1499300D01*
G01X236575Y1493450D02*
Y1495875D01*
X233150Y1499300D01*
G01X231000Y1880450D02*
X240100D01*
G01D02*
Y1875000D01*
G01X245249Y1896283D02*
X243800Y1894834D01*
Y1888100D01*
X243975Y1887950D01*
G01D02*
X242000D01*
X236100Y1893850D01*
G01X232314Y1897363D02*
X232327Y1897350D01*
X236100D01*
G01X253998Y295114D02*
Y291537D01*
X253871Y291410D01*
G01X254499Y701550D02*
Y697700D01*
G01X261999Y1516050D02*
X258999Y1513050D01*
X252999D01*
G01X257499Y1911050D02*
Y1915469D01*
X255777Y1917191D01*
G01X292999Y86363D02*
X293249Y86613D01*
X297499D01*
G01X282800Y87500D02*
X283937Y86363D01*
X287100D01*
G01D02*
X292999D01*
G01X293999Y293550D02*
X292999Y294550D01*
Y317050D01*
X287899Y322150D01*
X280899D01*
X278939Y324110D01*
Y327300D01*
G01X284999Y338650D02*
Y338050D01*
X284059Y337110D01*
Y333800D01*
G01X284999Y341800D02*
Y338650D01*
G01X281499Y338550D02*
Y333800D01*
G01X280499Y341800D02*
X281499Y340800D01*
Y338550D01*
G01X279939Y733800D02*
Y728610D01*
G01X285499Y745050D02*
X285059Y744610D01*
Y740300D01*
G01X285499Y748300D02*
Y745050D01*
G01X282099D02*
X282499Y744650D01*
Y740300D01*
G01X281499Y748300D02*
Y745650D01*
X282099Y745050D01*
G01X295000Y1513000D02*
Y1521000D01*
X278999Y1537001D01*
Y1544740D01*
X278939Y1544800D01*
G01X283499Y1556050D02*
X284059Y1555490D01*
Y1551300D01*
G01X279999Y1556050D02*
X281499Y1554550D01*
Y1551300D01*
G01X282499Y1559300D02*
Y1557050D01*
X283499Y1556050D01*
G01X278499Y1559300D02*
Y1557550D01*
X279999Y1556050D01*
G01X285499Y1930050D02*
X283589Y1931960D01*
Y1936200D01*
G01X288709Y1948042D02*
Y1942700D01*
G01X288358Y1951578D02*
Y1948393D01*
X288709Y1948042D01*
G01X284358Y1951578D02*
X280027D01*
X278999Y1950550D01*
G01D02*
X281858Y1947691D01*
X284999D01*
G01D02*
X286149Y1946541D01*
Y1942700D01*
G01X297499Y86613D02*
X302249D01*
G01D02*
Y90699D01*
X302250Y90700D01*
G01X297499Y92613D02*
Y97550D01*
G01X303125Y97650D02*
Y93325D01*
X305750Y90700D01*
G01X317400Y94900D02*
X315200D01*
X313600Y96500D01*
Y102650D01*
X316150Y105200D01*
G01X307300Y113300D02*
Y105800D01*
X307000Y105150D01*
G01D02*
X307050Y105200D01*
X316150D01*
G01X295500Y101900D02*
X299600D01*
X302800Y98700D01*
X303125Y97650D01*
G01X305249Y339050D02*
Y343550D01*
G01Y334050D02*
Y339050D01*
G01Y343550D02*
X304845Y343954D01*
X302454D01*
X299000Y340500D01*
G01X308749Y343550D02*
X310526D01*
X312912Y345936D01*
G01X318499Y352350D02*
Y349650D01*
X314849Y346000D01*
X314064D01*
X314000Y345936D01*
X312912D01*
G01X301249Y346050D02*
X302913Y347714D01*
X305999D01*
X309398Y351113D01*
Y355199D01*
X310249Y356050D01*
G01X308749Y339050D02*
X308873Y339174D01*
X315248D01*
G01X310249Y356050D02*
X319999D01*
X321059Y354990D01*
Y352350D01*
G01X314950Y365200D02*
X315939Y364211D01*
Y359750D01*
G01X299999Y366050D02*
X306749D01*
X310249Y362550D01*
Y360050D01*
G01D02*
X315639D01*
X315939Y359750D01*
G01X314950Y365200D02*
X314400Y365700D01*
Y370100D01*
G01X306749Y746050D02*
Y750050D01*
G01Y742050D02*
Y746050D01*
G01Y750050D02*
X301799D01*
X301099Y750750D01*
G01X310249Y750050D02*
X316499D01*
X318499Y752050D01*
G01X310249Y746050D02*
X316689D01*
X316749Y746110D01*
G01X310999Y757050D02*
Y762300D01*
X311249Y762550D01*
G01D02*
X321499D01*
X322059Y761990D01*
Y759350D01*
G01X316939Y766750D02*
X311549D01*
X311249Y767050D01*
G01D02*
Y769300D01*
X311999Y770050D01*
Y773550D01*
G01X300999Y772550D02*
X308999D01*
X309999Y773550D01*
X311999D01*
G01X303249Y1554550D02*
Y1550800D01*
X304499Y1549550D01*
G01X303249Y1558550D02*
Y1554550D01*
G01Y1562550D02*
Y1558550D01*
G01X318499Y1567301D02*
Y1566599D01*
X315750Y1563850D01*
X308049D01*
X306749Y1562550D01*
G01X321059Y1569850D02*
Y1573090D01*
X320659Y1573490D01*
X310689D01*
X310249Y1573050D01*
G01D02*
Y1569800D01*
G01X306749Y1558550D02*
X309499D01*
X310559Y1559610D01*
X313249D01*
G01D02*
X313939D01*
X316499Y1557050D01*
Y1550050D01*
X317499Y1549050D01*
G01X299999Y1583550D02*
X307499D01*
X307749Y1583300D01*
G01X314950Y1582600D02*
X315939Y1581611D01*
Y1577250D01*
G01X307749Y1583300D02*
X310249Y1580800D01*
Y1577050D01*
G01D02*
X315739D01*
X315939Y1577250D01*
G01X310471Y1948909D02*
Y1944909D01*
G01X310108Y1953328D02*
Y1949272D01*
X310471Y1948909D01*
G01Y1944909D02*
Y1943522D01*
X307999Y1941050D01*
Y1940050D01*
X306199Y1938250D01*
Y1937010D01*
G01X313608Y1953328D02*
X327777D01*
X331999Y1957550D01*
G01X313971Y1948909D02*
X316999D01*
X317559Y1949469D01*
X320471D01*
G01X324200Y1959072D02*
Y1960990D01*
X322999Y1962191D01*
X313527D01*
G01D02*
Y1960078D01*
X310499Y1957050D01*
G01X309999Y1976191D02*
X299777D01*
G01X319080Y1966472D02*
X318799Y1966191D01*
X313527D01*
G01D02*
X312999Y1966719D01*
Y1975050D01*
X311858Y1976191D01*
X309999D01*
G01X324800Y94900D02*
X317400D01*
G01X326499Y334054D02*
X321748D01*
G01X329748Y333114D02*
X328808Y334054D01*
X326499D01*
G01Y337454D02*
X325659Y336614D01*
X321748D01*
G01X329748Y337114D02*
X329408Y337454D01*
X326499D01*
G01X315248Y339174D02*
Y342399D01*
X318652Y345803D01*
Y345850D01*
X319102Y346300D01*
G01X322200Y369300D02*
X318450Y365550D01*
Y365200D01*
G01D02*
X318499Y365151D01*
Y359750D01*
G01X327999Y740550D02*
X327559Y740990D01*
X323249D01*
G01X331249Y741050D02*
X328499D01*
X327999Y740550D01*
G01X331249Y745050D02*
Y749050D01*
X330249Y750050D01*
G01D02*
X328999D01*
X327749Y748800D01*
Y744050D01*
G01D02*
X327599D01*
X327099Y743550D01*
X323249D01*
G01X316749Y746110D02*
X317059D01*
X320849Y749900D01*
Y750005D01*
X323894Y753050D01*
X324499D01*
G01X319499Y759350D02*
Y753050D01*
X318499Y752050D01*
G01X315950Y772200D02*
X316939Y771211D01*
Y766750D01*
G01X319450Y772200D02*
X319499Y772151D01*
Y766750D01*
G01X319450Y772200D02*
X319550Y772300D01*
X327000D01*
G01X327749Y1553550D02*
X326809Y1554490D01*
X319749D01*
G01X326500Y1550200D02*
X327749Y1551449D01*
Y1553550D01*
G01Y1557550D02*
X327249Y1557050D01*
X319749D01*
G01X327749Y1557550D02*
Y1558649D01*
X330300Y1561200D01*
G01X318499Y1567301D02*
Y1569850D01*
G01X328600Y1566100D02*
X319700D01*
X318499Y1567301D01*
G01X318450Y1582600D02*
X318499Y1582551D01*
Y1577250D01*
G01X318450Y1582600D02*
X329100D01*
G01X331622Y1944767D02*
X331204Y1944349D01*
X326971D01*
G01X335971Y1943409D02*
X334499D01*
X333141Y1944767D01*
X331622D01*
G01X335971Y1947409D02*
X335520Y1947860D01*
Y1953650D01*
G01D02*
X332103Y1950233D01*
Y1948133D01*
G01D02*
X330879Y1946909D01*
X326971D01*
G01X323999Y1938550D02*
X323571Y1938978D01*
Y1947978D01*
X322080Y1949469D01*
X320471D01*
G01X321640Y1959072D02*
Y1956409D01*
X321999Y1956050D01*
X325999D01*
X327499Y1957550D01*
X331999D01*
G01X329999Y1962550D02*
Y1961550D01*
X328499Y1960050D01*
X325178D01*
X324200Y1959072D01*
G01X318150Y1971900D02*
X319080Y1970970D01*
Y1966472D01*
G01X330000Y1971600D02*
X329600Y1972000D01*
X321800D01*
X321650Y1971900D01*
G01D02*
X321640Y1971890D01*
Y1966472D01*
G01X341499Y63050D02*
X342499D01*
X343999Y64550D01*
X347749D01*
G01X337749Y63050D02*
X341499D01*
G01Y67110D02*
X347749D01*
G01X337749Y67050D02*
X341439D01*
X341499Y67110D01*
G01X354249Y61990D02*
Y59360D01*
X358059Y55550D01*
G01X402499Y1476850D02*
X401599Y1475950D01*
X343699D01*
G01X375350Y42300D02*
Y37699D01*
X376499Y36550D01*
G01D02*
X386739D01*
X386799Y36490D01*
G01X375350Y42300D02*
X375233Y42500D01*
X370900D01*
X370500Y42900D01*
G01X358999Y61550D02*
Y56490D01*
X358059Y55550D01*
G01X360999Y86550D02*
X365499D01*
G01X386749Y26050D02*
X390499Y29800D01*
Y41050D01*
X391059Y41610D01*
X394199D01*
G01X386749Y30550D02*
X386799Y30600D01*
Y36490D01*
G01X394199Y39050D02*
X399749D01*
X399999Y39300D01*
G01X394199Y45050D02*
Y41610D01*
G01X394249Y50990D02*
X400689D01*
X400749Y51050D01*
G01X378850Y42300D02*
Y41987D01*
X381787Y39050D01*
X386799D01*
G01X378850Y42300D02*
X378700Y42900D01*
Y47300D01*
G01X381999Y57050D02*
X382939Y56110D01*
X387749D01*
G01X378749Y57050D02*
X381999D01*
G01Y53550D02*
X387749D01*
G01X378749Y53050D02*
X379249Y53550D01*
X381999D01*
G01X404249Y51050D02*
X406999D01*
X409999Y54050D01*
G01X399999Y42800D02*
X405249D01*
X406499Y44050D01*
Y48050D01*
X404249Y50300D01*
Y51050D01*
G01X399999Y39300D02*
X404499D01*
G01X400749Y51050D02*
Y48800D01*
X402999Y46550D01*
G01X404249Y56050D02*
X407999D01*
X409999Y54050D01*
G01X651299Y1818634D02*
X651549Y1818884D01*
X655549D01*
G01X649049Y1810884D02*
X654799D01*
X655049Y1810634D01*
G01X682699Y1812604D02*
X674740D01*
X673249Y1814095D01*
Y1820673D01*
X677810Y1825234D01*
X681549D01*
G01X666399Y1814569D02*
Y1820784D01*
X664549Y1822634D01*
X661549D01*
G01X655549Y1818884D02*
X659299Y1822634D01*
X661549D01*
G01X666399Y1812604D02*
X666369Y1812634D01*
X657049D01*
X655049Y1810634D01*
G01X693799Y1825634D02*
X693399Y1825234D01*
X681549D01*
G01X693799Y1821634D02*
X693099Y1822334D01*
X687049D01*
G01D02*
X677598D01*
X675149Y1819885D01*
Y1815500D01*
X676080Y1814569D01*
X682699D01*
G01X697299Y1821634D02*
X698665Y1823000D01*
X710761D01*
X711652Y1822109D01*
G01X697299Y1825634D02*
X698032Y1824901D01*
X711245D01*
X711848Y1825504D01*
G01X739799Y1806634D02*
X736099Y1802934D01*
X732549D01*
G01X768228Y352424D02*
Y353872D01*
X767828Y354272D01*
X759221D01*
X741999Y337050D01*
Y324368D01*
X748099Y313032D01*
X749336Y310734D01*
Y310733D01*
X757946Y294732D01*
X767128Y285550D01*
X785999D01*
G01X751228Y323924D02*
X748625D01*
X746999Y325550D01*
G01X751228Y328924D02*
Y323924D01*
G01X754978Y335674D02*
X750922D01*
X750898Y335650D01*
X749229D01*
X747999Y334420D01*
Y332153D01*
X751228Y328924D01*
G01X760778Y339424D02*
X755228D01*
X754978Y339174D01*
G01D02*
X752999Y341153D01*
Y343550D01*
G01X750099Y333550D02*
X751599Y332050D01*
X752499D01*
X754728Y329821D01*
Y328924D01*
G01D02*
X761168D01*
X761228Y328984D01*
G01X776999Y690050D02*
X751999D01*
X742599Y699450D01*
Y741482D01*
X753999Y752882D01*
X766446D01*
G01X749946Y724882D02*
X745864D01*
X745696Y725050D01*
G01X749946Y729882D02*
X745696Y725632D01*
Y725050D01*
G01X753196Y735132D02*
X752466Y735862D01*
X746399D01*
X745399Y734862D01*
Y732264D01*
X747781Y729882D01*
X749946D01*
G01X758996Y739882D02*
X755474D01*
X752306Y743050D01*
X748499D01*
X746999Y741550D01*
Y741050D01*
G01X753196Y738632D02*
X749417D01*
X746999Y741050D01*
G01X766446Y752882D02*
X762999Y749435D01*
Y739050D01*
X761271Y737322D01*
X758996D01*
G01X747499Y733762D02*
X749484D01*
X753196Y730050D01*
X753446Y729882D01*
G01D02*
X753506Y729942D01*
X760446D01*
G01X781999Y1085050D02*
X761019D01*
X743499Y1102570D01*
Y1145050D01*
X755341Y1156892D01*
X766583D01*
G01X750583Y1126392D02*
X748257D01*
X745599Y1129050D01*
G01X750583Y1131392D02*
X747941D01*
X745599Y1129050D01*
G01X755499Y1140300D02*
X750583Y1135384D01*
Y1131392D01*
G01X755499Y1143800D02*
X754249Y1142550D01*
X749499D01*
G01X760799Y1144050D02*
X755749D01*
X755499Y1143800D01*
G01X754083Y1131392D02*
Y1135914D01*
X754151Y1135982D01*
G01X760583Y1131452D02*
Y1134466D01*
X759067Y1135982D01*
X754151D01*
G01X769077Y1559296D02*
X767823Y1560550D01*
X757499D01*
X740999Y1544050D01*
Y1509550D01*
X757999Y1492550D01*
X791499D01*
G01X753577Y1536296D02*
Y1531296D01*
G01D02*
X745600D01*
G01X756327Y1543046D02*
X751495D01*
X749999Y1541550D01*
Y1539050D01*
X752753Y1536296D01*
X753577D01*
G01X756327Y1546546D02*
X754999Y1547874D01*
Y1550788D01*
G01X761627Y1546296D02*
X756577D01*
X756327Y1546546D01*
G01X757077Y1536296D02*
Y1537472D01*
X756453Y1538096D01*
X754453D01*
X752099Y1540450D01*
Y1540568D01*
G01X763577Y1536356D02*
X757137D01*
X757077Y1536296D01*
G01X753949Y1806414D02*
X744079D01*
X744049Y1806384D01*
G01D02*
X740049D01*
X739799Y1806634D01*
G01Y1798634D02*
X738049Y1796884D01*
Y1793884D01*
G01D02*
X739049D01*
X744049Y1798884D01*
G01D02*
X746799D01*
X748049Y1800134D01*
Y1802634D01*
X749269Y1803854D01*
X753949D01*
G01X739799Y1814134D02*
Y1816634D01*
X741549Y1818384D01*
G01D02*
X742299D01*
X744049Y1816634D01*
Y1813884D01*
G01D02*
X745299Y1812634D01*
X748549D01*
X752209Y1808974D01*
X753949D01*
G01X790499Y1899550D02*
X765062D01*
X747999Y1916613D01*
X747936D01*
X739999Y1924550D01*
Y1953050D01*
X753999Y1967050D01*
X764727D01*
X766564Y1965213D01*
G01X749499Y1933050D02*
X750064Y1933615D01*
Y1937713D01*
G01Y1942213D02*
X749527Y1942750D01*
X747099D01*
X746199Y1943650D01*
Y1947950D01*
X746712Y1948463D01*
X753314D01*
G01X750064Y1937713D02*
Y1942213D01*
G01X751096Y1955250D02*
X751100Y1955246D01*
Y1954200D01*
X753000Y1952300D01*
X753314Y1951963D01*
G01X759114Y1952213D02*
X753564D01*
X753314Y1951963D01*
G01X748299Y1946363D02*
X749485D01*
X753564Y1942284D01*
Y1942213D01*
G01D02*
X760004D01*
X760064Y1942273D01*
G01X772499Y323050D02*
X771685Y323864D01*
X767728D01*
G01X776249Y322550D02*
X772999D01*
X772499Y323050D01*
G01X772873Y326924D02*
X772373Y326424D01*
X767728D01*
G01X776249Y326550D02*
X773247D01*
X772873Y326924D01*
G01X768228Y352424D02*
X766915Y351111D01*
X762389D01*
X761650Y350372D01*
Y348819D01*
X761600Y348770D01*
Y347623D01*
X764499Y344724D01*
Y339050D01*
X762313Y336864D01*
X760778D01*
G01X768228Y347924D02*
Y342034D01*
X768178Y341984D01*
G01X779150Y336200D02*
Y340752D01*
X777978Y341924D01*
G01D02*
X768238D01*
X768178Y341984D01*
G01X768228Y347924D02*
X767895Y348257D01*
X763937D01*
G01X768178Y339424D02*
X772426D01*
X775650Y336200D01*
G01D02*
Y331900D01*
G01X776999Y690050D02*
X807550D01*
X814599Y697099D01*
Y710150D01*
X816302Y711853D01*
X820831D01*
G01X771105Y722789D02*
X769072Y724822D01*
X766946D01*
G01X774249Y724050D02*
X772366D01*
X771105Y722789D01*
G01X769999Y733050D02*
X774249Y728800D01*
Y728550D01*
G01D02*
X773081Y727382D01*
X766946D01*
G01X779200Y732800D02*
Y732850D01*
X778100Y733950D01*
Y736400D01*
X777850Y736700D01*
G01X766446Y748382D02*
X766396Y748332D01*
Y742442D01*
G01X777850Y736700D02*
Y741228D01*
X776696Y742382D01*
G01D02*
X766456D01*
X766396Y742442D01*
G01Y739882D02*
X771168D01*
X774350Y736700D01*
G01D02*
Y732900D01*
G01X771999Y1124550D02*
X770217Y1126332D01*
X767083D01*
G01X775249Y1123550D02*
X772999D01*
X771999Y1124550D01*
G01X772499Y1130050D02*
X771341Y1128892D01*
X767083D01*
G01X775249Y1127550D02*
X774999D01*
X772499Y1130050D01*
G01X779499Y1131050D02*
X784439Y1126110D01*
Y1125300D01*
G01X760799Y1141490D02*
X763439D01*
X763999Y1142050D01*
Y1147900D01*
X760800Y1151099D01*
Y1151330D01*
X760798Y1151332D01*
Y1153468D01*
X761880Y1154550D01*
X765999D01*
X766583Y1155134D01*
Y1156892D01*
G01X768199Y1146610D02*
X771890D01*
X774608Y1143892D01*
X776833D01*
G01X766583Y1152392D02*
Y1148226D01*
X768199Y1146610D01*
G01X777950Y1138200D02*
Y1142775D01*
X776833Y1143892D01*
G01X774450Y1138200D02*
Y1140450D01*
X770850Y1144050D01*
X768199D01*
G01X774450Y1138200D02*
X774200Y1138000D01*
Y1133700D01*
G01X762898Y1152400D02*
X766300D01*
X766583Y1152392D01*
G01X774542Y1530050D02*
X773356Y1531236D01*
X770077D01*
G01X777431Y1527893D02*
X776699D01*
X774542Y1530050D01*
G01X777431Y1531893D02*
X776480D01*
X774577Y1533796D01*
G01D02*
X770077D01*
G01X761627Y1543736D02*
X764285D01*
X764999Y1544450D01*
Y1553972D01*
X769077Y1558050D01*
Y1559296D01*
G01X769027Y1548856D02*
X779267D01*
X779327Y1548796D01*
G01X769077Y1554796D02*
X769027Y1554746D01*
Y1548856D01*
G01X780550Y1543100D02*
Y1547573D01*
X779327Y1548796D01*
G01X769027Y1546296D02*
X773854D01*
X777050Y1543100D01*
G01D02*
Y1539200D01*
G01X776149Y1806414D02*
X771269D01*
X768549Y1809134D01*
Y1816634D01*
G01X776149Y1803854D02*
X785019D01*
X785799Y1804634D01*
G01Y1800634D02*
X785139Y1801294D01*
X776149D01*
G01X774299Y1817634D02*
X769549D01*
X768549Y1816634D01*
G01X771499Y1936550D02*
X770896Y1937153D01*
X766564D01*
G01X774749Y1935050D02*
X773499D01*
X771999Y1936550D01*
X771499D01*
G01Y1940050D02*
X771162Y1939713D01*
X766564D01*
G01X774749Y1939050D02*
X772499D01*
X771499Y1940050D01*
G01X759114Y1949653D02*
X762102D01*
X762499Y1950050D01*
Y1958100D01*
X760500Y1960099D01*
Y1960100D01*
X759900Y1960700D01*
Y1963400D01*
X761500Y1965000D01*
X766351D01*
X766564Y1965213D01*
G01X766514Y1954773D02*
X776754D01*
X776814Y1954713D01*
G01X766564Y1960713D02*
X766514Y1960663D01*
Y1954773D01*
G01X779749Y1949050D02*
Y1951778D01*
X776814Y1954713D01*
G01X776249Y1949050D02*
X772249D01*
X769086Y1952213D01*
X766514D01*
G01X776249Y1949050D02*
X776100Y1948900D01*
Y1944200D01*
G01X762700Y1961800D02*
X763700Y1960800D01*
X766200D01*
X766564Y1960713D01*
G01X822873Y307471D02*
X816694D01*
X815273Y306050D01*
Y288491D01*
X812332Y285550D01*
X785999D01*
G01X780499Y330050D02*
X781999D01*
X782999Y329050D01*
Y323050D01*
X784749Y321300D01*
X785439D01*
G01X791499Y333050D02*
X790559Y332110D01*
Y327800D01*
G01X797249Y332050D02*
X796249Y333050D01*
X791499D01*
G01X789999Y336550D02*
X787999Y334550D01*
Y327800D01*
G01X797249Y336050D02*
X796249Y337050D01*
X790499D01*
X789999Y336550D01*
G01X788999Y736050D02*
X787499Y734550D01*
Y728800D01*
G01X791999Y733050D02*
X790059Y731110D01*
Y728800D01*
G01X781999Y725550D02*
X784939Y722610D01*
Y722300D01*
G01X795749Y736050D02*
X788999D01*
G01X795749Y732050D02*
X794249Y733550D01*
X792499D01*
X791999Y733050D01*
G01X820841Y1116216D02*
X818685D01*
X816099Y1113630D01*
Y1089050D01*
X812099Y1085050D01*
X781999D01*
G01X792154Y1135926D02*
X790375D01*
X789559Y1135110D01*
Y1131800D01*
G01X795749Y1133050D02*
Y1133800D01*
X793623Y1135926D01*
X792154D01*
G01X789499Y1138050D02*
X786999Y1135550D01*
Y1131800D01*
G01X795749Y1137050D02*
X794749Y1138050D01*
X789499D01*
G01X822245Y1518722D02*
X817843D01*
X816171Y1517050D01*
Y1501222D01*
X807499Y1492550D01*
X791499D01*
G01X784499Y1529050D02*
X784577Y1529128D01*
X787693D01*
G01X791499Y1543550D02*
X790253Y1542304D01*
Y1535628D01*
G01X798431Y1542893D02*
X797774Y1543550D01*
X791499D01*
G01X793999Y1541050D02*
X792813Y1539864D01*
Y1535628D01*
G01X798431Y1538893D02*
X796274Y1541050D01*
X793999D01*
G01X781904Y1538188D02*
Y1541746D01*
X780550Y1543100D01*
G01X789299Y1804634D02*
X790649Y1803284D01*
X792784D01*
X793000Y1803500D01*
G01X789299Y1800634D02*
X790049Y1801384D01*
X793572D01*
X795849Y1803661D01*
Y1805500D01*
G01X785799Y1804634D02*
Y1808034D01*
X786699Y1808934D01*
G01X785799Y1795634D02*
Y1800634D01*
G01X821436Y1925365D02*
X816501D01*
X815536Y1924400D01*
Y1905087D01*
X809999Y1899550D01*
X790499D01*
G01X792499Y1949050D02*
X788999D01*
X788499Y1948550D01*
Y1942300D01*
G01X796931Y1948393D02*
X793156D01*
X792499Y1949050D01*
G01X794499Y1941050D02*
X793249Y1942300D01*
X791059D01*
G01X796931Y1944393D02*
Y1943482D01*
X794499Y1941050D01*
G01X782999Y1937050D02*
X784249Y1935800D01*
X785939D01*
G01X825333Y176949D02*
X825320Y176936D01*
X821885D01*
X818013Y173064D01*
G01X816749Y167050D02*
Y171800D01*
X818013Y173064D01*
G01X816499Y162800D02*
Y166800D01*
X816749Y167050D01*
G01X817999Y182050D02*
X826499D01*
X827893Y180656D01*
Y176949D01*
G01X814700Y267500D02*
X822100D01*
G01D02*
X827450D01*
X827500Y267450D01*
G01X813200Y670100D02*
X820600D01*
G01D02*
X826050D01*
X826100Y670150D01*
G01X812900Y1072900D02*
X820300D01*
G01D02*
X822850D01*
X825700Y1075750D01*
G01X878937Y1119961D02*
X878924Y1119948D01*
X869601D01*
X867448Y1122100D01*
X834760D01*
X834060Y1122800D01*
X826938D01*
X826738Y1122600D01*
X819499D01*
X814449Y1117550D01*
Y1092500D01*
X811499Y1089550D01*
X807499D01*
G01X814700Y1480600D02*
X822100D01*
G01D02*
X827650D01*
X827700Y1480650D01*
G01X878937Y1525473D02*
X864556D01*
X863381Y1526648D01*
X857921D01*
X856619Y1527950D01*
X820399D01*
X814117Y1521668D01*
Y1501431D01*
X808736Y1496050D01*
X803499D01*
G01X824499Y1783800D02*
X823749Y1783050D01*
X820356D01*
X819599Y1783807D01*
X819593D01*
G01X824749Y1788050D02*
X824644D01*
X822244Y1785650D01*
X821099D01*
X819597Y1784148D01*
Y1783811D01*
X819593Y1783807D01*
G01X814999Y1783800D02*
X817249Y1786050D01*
Y1788050D01*
G01X825333Y1798997D02*
X819445D01*
X818824Y1798376D01*
X817249Y1796800D01*
Y1793050D01*
G01Y1788050D02*
Y1793050D01*
G01X827893Y1815177D02*
X827892Y1815176D01*
Y1810443D01*
X826999Y1809550D01*
X814999D01*
X814499Y1809050D01*
G01X807000Y1822300D02*
X807750Y1821550D01*
X813749D01*
G01Y1825550D02*
X806342D01*
X803500Y1822708D01*
G01X817249Y1825550D02*
X817749Y1825050D01*
X823499D01*
G01X830453Y1815177D02*
Y1818806D01*
X826959Y1822300D01*
X817999D01*
X817249Y1821550D01*
G01D02*
Y1818800D01*
X815499Y1817050D01*
G01X815300Y1885000D02*
X822700D01*
G01X878937Y1930985D02*
X868564D01*
X865999Y1933550D01*
X820499D01*
X813836Y1926887D01*
Y1907285D01*
X810101Y1903550D01*
X806499D01*
G01X840499Y182550D02*
X831999D01*
X830453Y181004D01*
Y176949D01*
G01X831749Y167050D02*
X830452Y168347D01*
Y171300D01*
X830453Y171301D01*
Y176949D01*
G01X831499Y162800D02*
X831749Y163050D01*
Y167050D01*
G01X824249D02*
Y168800D01*
X827893Y172444D01*
Y176949D01*
G01X823999Y162800D02*
Y166800D01*
X824249Y167050D01*
G01X827893Y193129D02*
X827892Y193130D01*
Y197157D01*
X825499Y199550D01*
Y204050D01*
X824499Y205050D01*
G01X833999Y204800D02*
X833013Y203814D01*
Y193129D01*
G01X830453D02*
Y196700D01*
X829999Y197154D01*
Y200550D01*
G01X829499Y208300D02*
Y211458D01*
X827774Y213183D01*
G01D02*
Y214057D01*
X829917Y216200D01*
G01X833999Y208300D02*
Y210662D01*
X836499Y213162D01*
G01X833576Y215432D02*
X834167D01*
X836437Y213162D01*
X836499D01*
G01X838299Y204800D02*
X833999D01*
G01X829499D02*
X829999Y204300D01*
Y200550D01*
G01X927649Y158500D02*
Y156900D01*
X928749Y155800D01*
X939477D01*
X948999Y165322D01*
Y169120D01*
X940544Y177575D01*
X940474D01*
X936499Y181550D01*
X910999D01*
X894499Y198050D01*
X861999D01*
X840499Y219550D01*
X837999D01*
G01X836700Y267450D02*
Y261100D01*
X836600Y261000D01*
G01X847200Y267200D02*
X840575Y273825D01*
Y274950D01*
G01D02*
X843900D01*
X845750Y276800D01*
G01X827500Y267450D02*
X836700D01*
G01X878937Y308937D02*
X878924Y308924D01*
X846976D01*
X843700Y312200D01*
G01X835300Y670150D02*
Y663200D01*
G01X826100Y670150D02*
X835300D01*
G01X839175Y677650D02*
X844400D01*
X844450Y677700D01*
G01X878937Y714449D02*
X867378D01*
X862079Y709150D01*
X845350D01*
X841500Y713000D01*
G01X835000Y1075750D02*
Y1068100D01*
X834500Y1067600D01*
G01X825700Y1075750D02*
X835000D01*
G01X838875Y1083250D02*
X838925Y1083200D01*
X844050D01*
G01X827700Y1480650D02*
X829300Y1479050D01*
X836900D01*
G01D02*
Y1471400D01*
X836600Y1471100D01*
G01X845700Y1477100D02*
X840775Y1482025D01*
Y1486550D01*
G01D02*
X842325Y1488100D01*
X846050D01*
G01X833499Y1783800D02*
X829799D01*
X829749Y1783750D01*
X829199D01*
G01D02*
Y1785000D01*
X832249Y1788050D01*
G01D02*
Y1789955D01*
X830612Y1791592D01*
Y1793937D01*
X830452Y1794097D01*
Y1798996D01*
X830453Y1798997D01*
G01X827893D02*
Y1795944D01*
X824749Y1792800D01*
Y1788050D01*
G01X833013Y1815177D02*
Y1818934D01*
X826897Y1825050D01*
X823499D01*
G01X847700Y1881900D02*
Y1884900D01*
X841374Y1891226D01*
Y1892300D01*
G01D02*
X842924Y1893850D01*
X846549D01*
G01X828000Y1884750D02*
X837449D01*
X837499Y1884800D01*
G01X822700Y1885000D02*
X827750D01*
X828000Y1884750D01*
G01X837499Y1884800D02*
Y1876900D01*
G01X878937Y223937D02*
X875891D01*
G02X874477Y224523I0J1999D01*
G01X873562Y225438D01*
G03X872148Y226024I-1414J-1413D01*
G01X862802D01*
G03X861474Y225474I0J-1878D01*
G02X860146Y224924I-1328J1328D01*
G01X859228D01*
G01X878937Y228937D02*
X875265D01*
G03X873851Y228351I0J-1999D01*
G01X873410Y227910D01*
G02X871996Y227324I-1414J1413D01*
G01X863378D01*
G02X862050Y227874I0J1878D01*
G03X860722Y228424I-1328J-1328D01*
G01X859228D01*
G01X855728Y252924D02*
X854841D01*
G03X847878Y250040I0J-9847D01*
G01X855728Y249424D02*
G03X854400Y249974I-1328J-1328D01*
G01X851278D01*
G01X859228Y249424D02*
G02X861640Y250423I2412J-2412D01*
G01X881651D01*
G02X882585Y250036I0J-1321D01*
G03X882826Y249837I1164J1164D01*
G03X883509Y249554I683J683D01*
G01X883522Y249567D01*
X887401D01*
G01X859228Y252924D02*
X859319Y252833D01*
G03X861850Y251725I2681J2680D01*
G03X861999Y251723I125J3789D01*
G01X881499D01*
G03X882501Y252138I0J1417D01*
G01X882689Y252326D01*
G02X883599Y252703I910J-910D01*
G01X883612Y252716D01*
X887401D01*
G01X854200Y269500D02*
Y264800D01*
X854400Y264600D01*
G01X853978Y274924D02*
Y269722D01*
X854200Y269500D01*
G01X849250Y276800D02*
X849228Y276822D01*
Y280924D01*
G01D02*
X853978D01*
G01D02*
X858228D01*
X858478Y281174D01*
G01D02*
X860728Y278924D01*
X878924D01*
X878937Y278937D01*
G01X849250Y276800D02*
X849200Y276400D01*
Y273754D01*
X847577Y272131D01*
G01X859446Y630382D02*
G02X861499Y631286I2053J-1879D01*
G01X872074D01*
G02X872999Y630361I0J-925D01*
G03X873924Y629436I925J0D01*
G01X878924D01*
X878937Y629449D01*
G01X859446Y633882D02*
G03X861499Y632586I2053J978D01*
G01X871574D01*
G03X872499Y633511I0J925D01*
G02X873424Y634436I925J0D01*
G01X878924D01*
X878937Y634449D01*
G01X855946Y654882D02*
X855261Y655567D01*
G03X854199Y656007I-1062J-1062D01*
G01X852560D01*
G03X851172Y655432I0J-1963D01*
G01X855946Y658382D02*
X855417Y657853D01*
G02X854099Y657307I-1318J1318D01*
G01X850676D01*
G03X849025Y656623I0J-2335D01*
G01X847772Y655370D01*
G01X859446Y654882D02*
X859706Y655141D01*
G02X861899Y656050I2194J-2193D01*
G01X882233D01*
G02X883199Y655650I0J-1366D01*
G03X884609Y655066I1410J1410D01*
G01X884622Y655079D01*
X887401D01*
G01X859446Y658382D02*
X859473Y658355D01*
G03X861899Y657350I2426J2426D01*
G01X882206D01*
G03X882534Y657421I0J792D01*
G03X882766Y657582I-328J721D01*
G02X882880Y657688I1528J-1529D01*
G02X884152Y658215I1272J-1272D01*
G01X884165Y658228D01*
X887401D01*
G01X846400Y665500D02*
X844700Y667200D01*
Y677450D01*
X844450Y677700D01*
G01X847200Y672000D02*
X847900Y672700D01*
Y677100D01*
X847950Y677700D01*
G01X852696Y681882D02*
X856946D01*
X857196Y682132D01*
G01X847950Y677700D02*
X847946Y677704D01*
Y681882D01*
G01D02*
X852696D01*
G01X857196Y682132D02*
X862581D01*
X864898Y684449D01*
X878937D01*
G01X852696Y675882D02*
Y671197D01*
G01D02*
X852700Y671193D01*
Y667500D01*
X852703Y667497D01*
G01X878937Y1034961D02*
X874867D01*
G02X873453Y1035547I0J1999D01*
G01X872594Y1036406D01*
G03X871180Y1036992I-1414J-1413D01*
G01X862770D01*
G03X861442Y1036442I0J-1878D01*
G02X860114Y1035892I-1328J1328D01*
G01X859083D01*
G01Y1039392D02*
X860330D01*
G02X861658Y1038842I0J-1878D01*
G03X862986Y1038292I1328J1328D01*
G01X871003D01*
G03X872417Y1038878I0J1999D01*
G01X872914Y1039375D01*
G02X874328Y1039961I1414J-1413D01*
G01X878937D01*
G01X855583Y1060892D02*
X855320Y1061155D01*
G03X853299Y1061992I-2021J-2021D01*
G01X851384D01*
G03X850833Y1061441I0J-551D01*
G01X855583Y1064392D02*
X855108Y1063917D01*
G02X853599Y1063292I-1509J1509D01*
G01X850399D01*
G03X848067Y1062326I0J-3298D01*
G01X847233Y1061492D01*
G01X859083Y1060892D02*
G02X860558Y1061503I1475J-1475D01*
G01X881711D01*
G02X882447Y1061198I0J-1041D01*
G01X882747Y1060898D01*
G03X883520Y1060578I773J773D01*
G01X883533Y1060591D01*
X887401D01*
G01X859083Y1064392D02*
G03X862919Y1062803I3836J3836D01*
G01X881489D01*
G03X882604Y1063265I0J1576D01*
G02X883719Y1063727I1115J-1115D01*
G01X883732Y1063740D01*
X887401D01*
G01X851600Y1073300D02*
X852300Y1074000D01*
Y1077300D01*
X852333Y1077716D01*
G01Y1081392D02*
Y1077716D01*
G01Y1087392D02*
X856583D01*
X856833Y1087642D01*
G01X847550Y1083200D02*
Y1087359D01*
X847583Y1087392D01*
G01D02*
X852333D01*
G01X856833Y1087642D02*
X857241Y1088050D01*
X864499D01*
X866397Y1089948D01*
X878924D01*
X878937Y1089961D01*
G01X847550Y1083200D02*
Y1079850D01*
X846400Y1078700D01*
G01X844050Y1083200D02*
Y1074650D01*
X845200Y1073500D01*
X846500D01*
G01X863949Y1362800D02*
X867749D01*
X868499Y1363550D01*
X869749D01*
G01Y1367550D02*
X863499D01*
X861849Y1369200D01*
Y1372200D01*
G01D02*
Y1376050D01*
G01X856449Y1366675D02*
Y1370300D01*
X858349Y1372200D01*
G01X856449Y1366675D02*
X847825D01*
X847500Y1367000D01*
G01X860577Y1440796D02*
X860742Y1440961D01*
G02X863999Y1442310I3257J-3257D01*
G01X872399D01*
G02X872999Y1441710I0J-600D01*
G01Y1441060D01*
G03X873599Y1440460I600J0D01*
G01X873612Y1440473D01*
X878937D01*
G01X860577Y1444296D02*
G03X862999Y1443610I2422J3933D01*
G01X872399D01*
G03X872999Y1444210I0J600D01*
G01Y1444860D01*
G02X873599Y1445460I600J0D01*
G01X873612Y1445473D01*
X878937D01*
G01X857077Y1469296D02*
X856994Y1469213D01*
G02X854599Y1468221I-2395J2395D01*
G01X852799D01*
G03X849227Y1466742I-1J-5051D01*
G01X848888Y1466402D01*
G01X857077Y1465796D02*
X856908Y1465964D01*
G03X854599Y1466921I-2310J-2309D01*
G01X853676D01*
G03X852288Y1466346I0J-1963D01*
G01X860577Y1465796D02*
X860661Y1465880D01*
G02X863399Y1467014I2738J-2738D01*
G01X881279D01*
G02X882752Y1466404I0J-2083D01*
G03X883510Y1466090I758J758D01*
G01X883523Y1466103D01*
X887401D01*
G01X860577Y1469296D02*
X860612Y1469262D01*
G03X862899Y1468314I2288J2287D01*
G01X881582D01*
G03X882538Y1468710I0J1352D01*
G02X883815Y1469239I1277J-1277D01*
G01X883828Y1469252D01*
X887401D01*
G01X854327Y1486296D02*
Y1481596D01*
G01D02*
Y1477550D01*
G01X848300Y1483000D02*
Y1486300D01*
X849550Y1487550D01*
Y1488100D01*
G01D02*
Y1492269D01*
X849577Y1492296D01*
G01X854327D02*
X858577D01*
X858827Y1492546D01*
G01X849577Y1492296D02*
X854327D01*
G01X858827Y1492546D02*
X867495D01*
X870422Y1495473D01*
X878937D01*
G01X862564Y1846613D02*
G02X865483Y1847822I2919J-2919D01*
G01X872074D01*
G02X872999Y1846897I0J-925D01*
G03X873924Y1845972I925J0D01*
G01X878924D01*
X878937Y1845985D01*
G01X862564Y1850113D02*
G03X864956Y1849122I2392J2392D01*
G01X872574D01*
G03X873499Y1850047I0J925D01*
G02X874424Y1850972I925J0D01*
G01X874437Y1850985D01*
X878937D01*
G01X859064Y1871113D02*
X857999D01*
G02X856688Y1871656I0J1854D01*
G01X856396Y1871948D01*
G03X855756Y1872213I-640J-640D01*
G01X854676D01*
G03X853499Y1871036I0J-1177D01*
G01X859064Y1874613D02*
X857743D01*
G03X856869Y1874251I0J-1236D01*
G01X856578Y1873960D01*
G02X855499Y1873513I-1079J1079D01*
G01X853999D01*
G03X851535Y1872493I-1J-3484D01*
G01X850099Y1871056D01*
G01X862564Y1871113D02*
G02X865975Y1872526I3411J-3411D01*
G01X881766D01*
G02X882408Y1872260I0J-908D01*
G01X882708Y1871960D01*
G03X883572Y1871602I864J864D01*
G01X887388D01*
X887401Y1871615D01*
G01X850049Y1893850D02*
X849800Y1893400D01*
Y1888300D01*
G01X862564Y1874613D02*
G03X863351Y1873826I787J0D01*
G01X881732D01*
G03X882432Y1874116I0J990D01*
G01X882632Y1874316D01*
G02X883682Y1874751I1050J-1050D01*
G01X887388D01*
X887401Y1874764D01*
G01X854814Y1892113D02*
Y1887250D01*
G01D02*
Y1883550D01*
G01Y1898113D02*
X859064D01*
X859314Y1898363D01*
G01X850049Y1893850D02*
X850551D01*
X854814Y1898113D01*
G01X850064D02*
Y1893865D01*
X850049Y1893850D01*
G01X859314Y1898363D02*
X860664Y1899713D01*
X867240D01*
X868512Y1900985D01*
X878937D01*
G01X892794Y160447D02*
X892781Y160434D01*
X882999D01*
G01X874978Y159924D02*
X875488Y160434D01*
X882999D01*
G01X892794Y163647D02*
X892781Y163634D01*
X886915D01*
X885499Y165050D01*
G01X874978Y163924D02*
X884373D01*
X885499Y165050D01*
G01X878078Y240103D02*
X878160Y240186D01*
G02X880199Y241030I2038J-2039D01*
G01X881886D01*
G02X882325Y240848I0J-621D01*
G01X882760Y240412D01*
X882761Y240410D01*
G03X883499Y240105I737J738D01*
G01X883512Y240118D01*
X887401D01*
G01X878078Y243878D02*
X879192Y242764D01*
G03X880230Y242334I1038J1038D01*
G01X880399Y242330D01*
X881805D01*
G03X882381Y242568I1J814D01*
G01X882900Y243089D01*
G02X883298Y243254I398J-398D01*
G01X883311Y243267D01*
X887401D01*
G01X886749Y570550D02*
Y568800D01*
X885499Y567550D01*
X876999D01*
X876806Y567743D01*
X876787D01*
G01X878596Y645573D02*
X879436Y646413D01*
G02X880250Y646750I814J-814D01*
G01X882004D01*
G02X882849Y646400I0J-1195D01*
G01X883149Y646100D01*
G03X884315Y645617I1166J1166D01*
G01X884328Y645630D01*
X887401D01*
G01X878596Y649348D02*
X879496Y648448D01*
G03X880376Y648052I961J961D01*
G03X880457Y648050I74J1357D01*
G01X882075D01*
G03X882799Y648350I0J1024D01*
G02X883803Y648766I1004J-1004D01*
G01X883816Y648779D01*
X887401D01*
G01X877499Y977050D02*
X881499Y981050D01*
X884999D01*
X886583Y979466D01*
Y975892D01*
G01X878233Y1051095D02*
G02X879814Y1051750I1581J-1581D01*
G01X883048D01*
G02X883475Y1051573I0J-604D01*
G03X883651Y1051422I1072J1072D01*
G03X884358Y1051129I707J707D01*
G01X884371Y1051142D01*
X887401D01*
G01X877964Y1054485D02*
X878339Y1054111D01*
G03X880899Y1053050I2561J2560D01*
G01X881933D01*
G03X882017Y1053052I9J1366D01*
G03X882216Y1053079I-84J1364D01*
G03X882748Y1053300I-1J753D01*
G01X883149Y1053700D01*
X883349Y1053900D01*
G02X884262Y1054278I913J-913D01*
G01X884275Y1054291D01*
X887401D01*
G01X869749Y1363550D02*
Y1359550D01*
G01D02*
Y1354212D01*
X869587Y1354050D01*
G01X891999Y1363550D02*
X873249D01*
G01X880499Y1367550D02*
X873249D01*
G01X898544Y1376983D02*
X901066D01*
X901999Y1376050D01*
Y1370707D01*
X898842Y1367550D01*
X880499D01*
G01X873577Y1375796D02*
X874823Y1374550D01*
X882999D01*
G01X892794Y1376983D02*
X885432D01*
X882999Y1374550D01*
G01X873577Y1379796D02*
X873951Y1380170D01*
X879999D01*
G01X892794Y1380183D02*
X880012D01*
X879999Y1380170D01*
G01X878054Y1456450D02*
G02X879170Y1457566I1116J0D01*
G01X881667D01*
G02X882478Y1457230I0J-1147D01*
G01X882778Y1456930D01*
G03X883476Y1456641I698J698D01*
G01X883489Y1456654D01*
X887401D01*
G01X877853Y1459991D02*
G03X878978Y1458866I1125J0D01*
G01X881760D01*
G03X882412Y1459136I0J922D01*
G01X882689Y1459413D01*
G02X883599Y1459790I910J-910D01*
G01X883612Y1459803D01*
X887401D01*
G01X866914Y1861840D02*
G02X868151Y1863077I1237J0D01*
G01X880999D01*
G02X882226Y1862803I-1J-2890D01*
G02X882684Y1862535I-1224J-2618D01*
G03X883499Y1862153I815J678D01*
G01X887388D01*
X887401Y1862166D01*
G01X866914Y1865615D02*
G03X869099Y1864377I2185J1309D01*
G01X880999D01*
G03X882406Y1864669I1J3532D01*
G03X882457Y1864692I-1426J3231D01*
G01X882757Y1864992D01*
G02X883399Y1865302I642J-510D01*
G01X887388D01*
X887401Y1865315D01*
G01X898544Y163647D02*
X898557Y163634D01*
X910083D01*
X914873Y168424D01*
X916999D01*
G01X898544Y160447D02*
X898557Y160434D01*
X907499D01*
G01X898544Y565959D02*
X898543Y565958D01*
Y560506D01*
X899457Y559592D01*
X899685D01*
G01X905196Y562882D02*
X901906Y559592D01*
X899685D01*
G01X902999Y556050D02*
X905999D01*
X906999Y557050D01*
G01X908696Y562882D02*
Y558747D01*
X906999Y557050D01*
G01X892794Y565959D02*
X887658D01*
X886749Y565050D01*
G01D02*
Y560500D01*
G01X892794Y569159D02*
X888140D01*
X886749Y570550D01*
G01X894200Y560400D02*
X894251D01*
X895499Y561648D01*
Y567550D01*
X897108Y569159D01*
X898544D01*
G01D02*
X902919D01*
X905196Y566882D01*
G01X913149Y962100D02*
X910099Y959050D01*
X903549D01*
X900499Y962100D01*
G01X898544Y971471D02*
X900004D01*
X905083Y966392D01*
G01D02*
Y962966D01*
X905999Y962050D01*
G01X892794Y971471D02*
X892781Y971458D01*
X887017D01*
X886583Y971892D01*
G01D02*
Y967600D01*
G01X892794Y974671D02*
X891573Y975892D01*
X886583D01*
G01X905083Y970392D02*
X900804Y974671D01*
X898544D01*
G01D02*
X896120D01*
X895499Y974050D01*
Y963550D01*
X894999Y963050D01*
G01X898544Y1380183D02*
X901246D01*
X903999Y1377430D01*
Y1367050D01*
X900499Y1363550D01*
X891999D01*
G01X886200Y1776200D02*
Y1782099D01*
X886314Y1782213D01*
G01X892794Y1782494D02*
X892513Y1782213D01*
X886314D01*
G01X898544Y1782494D02*
Y1779096D01*
X898024Y1778576D01*
X897499Y1778050D01*
X897239Y1777790D01*
Y1771500D01*
G01D02*
X897869Y1770870D01*
X902819D01*
X904814Y1772865D01*
Y1777613D01*
G01X886350Y1786300D02*
X886956Y1785694D01*
X892794D01*
G01D02*
X893855D01*
X895500Y1784049D01*
Y1778551D01*
X892999Y1776050D01*
G01X898544Y1785694D02*
X900734D01*
X902364Y1784064D01*
X904814Y1781613D01*
G01D02*
X899805Y1776604D01*
X899599D01*
G01X916999Y168424D02*
X922478D01*
G01Y164424D02*
X913373D01*
X909383Y160434D01*
X907499D01*
G01X925978Y164424D02*
X922999Y161445D01*
Y158550D01*
G01D02*
X927599D01*
X927649Y158500D01*
G01X925749Y172550D02*
X925978Y172321D01*
Y168424D01*
G01D02*
X926702Y167700D01*
X932049D01*
G01X912649Y557800D02*
Y558929D01*
X908696Y562882D01*
G01X922049Y563025D02*
X921999Y562975D01*
Y557050D01*
G01X916149Y557800D02*
X916899Y557050D01*
X921999D01*
G01X914549Y566900D02*
X916849D01*
X917499Y567550D01*
X926999D01*
X927999Y568550D01*
G01X908696Y566882D02*
X914531D01*
X914549Y566900D01*
G01X908696Y570882D02*
Y566882D01*
G01X922049Y967225D02*
Y961050D01*
G01X916649Y962100D02*
X917699Y961050D01*
X922049D01*
G01X929499Y971100D02*
X914549D01*
G01X908583Y970392D02*
X913841D01*
X914549Y971100D01*
G01X908583Y974392D02*
Y970392D01*
G01Y966392D02*
X908857D01*
X913149Y962100D01*
G01X914999Y1791500D02*
Y1781950D01*
X914049Y1781000D01*
G01X908314Y1781613D02*
X913436D01*
X914049Y1781000D01*
G01X908314Y1785613D02*
Y1781613D01*
G01X912649Y1771700D02*
Y1773278D01*
X908314Y1777613D01*
G01D02*
X915402D01*
X917499Y1779710D01*
Y1796550D01*
G01X921499Y1770050D02*
X917799D01*
X916149Y1771700D01*
G01X921499Y1770050D02*
Y1777075D01*
X921549Y1777125D01*
G01X945999Y166550D02*
X944849Y167700D01*
X932049D01*
G01X931149Y158500D02*
X937499D01*
G01X939549Y163825D02*
Y159600D01*
X938449Y158500D01*
X937499D01*
G01X1005807Y1636102D02*
X993000D01*
X992102Y1637000D01*
X985498D01*
X984600Y1636102D01*
X961702D01*
G01X1005807Y1641102D02*
X966752D01*
X965150Y1639500D01*
G01X1005807Y1656102D02*
X984602D01*
X981500Y1653000D01*
G01X980800Y1659600D02*
X982302Y1661102D01*
X1005807D01*
G01Y1651102D02*
X983850D01*
X982050Y1649302D01*
G01X971200Y1660500D02*
X977500D01*
G01X971200Y1665500D02*
X975500D01*
X978000Y1668000D01*
G01X1005807Y1671102D02*
X974402D01*
X974000Y1670700D01*
G01X1005807Y1666102D02*
X985898D01*
X984500Y1667500D01*
X984211D01*
G54D10*
X-38666Y47522D03*
X-37468Y1947630D03*
X21499Y17050D03*
X1010999Y18550D03*
X1008999Y1968550D03*
X1073242Y50048D03*
G54D104*
G01X-53190Y-209897D02*
Y-192397D01*
G01X-44894D02*
X-53190Y-203189D01*
G01X-43584Y-209897D02*
X-49479Y-198231D01*
G01X-35909Y-209897D02*
Y-192397D01*
X-25865Y-209897D01*
Y-192397D01*
G01X-13387Y-209897D02*
X-15134Y-209605D01*
X-16662Y-208439D01*
X-17972Y-206689D01*
X-18846Y-204647D01*
X-19282Y-202314D01*
Y-199980D01*
X-18846Y-197647D01*
X-17972Y-195605D01*
X-16662Y-193856D01*
X-15134Y-192689D01*
X-13387Y-192397D01*
X-11641Y-192689D01*
X-10112Y-193856D01*
X-8802Y-195605D01*
X-7928Y-197647D01*
X-7492Y-199980D01*
Y-202314D01*
X-7928Y-204647D01*
X-8802Y-206689D01*
X-10112Y-208439D01*
X-11641Y-209605D01*
X-13387Y-209897D01*
G01X-472D02*
X8698Y-192397D01*
G01X-472D02*
X8698Y-209897D01*
G01X34310D02*
Y-192397D01*
X38676D01*
X40423Y-193272D01*
X41733Y-194439D01*
X42825Y-196188D01*
X43698Y-198231D01*
X43916Y-201147D01*
X43698Y-204064D01*
X42825Y-206106D01*
X41733Y-207856D01*
X40423Y-209022D01*
X38676Y-209897D01*
X34310D01*
G01X52246D02*
Y-192397D01*
X57705D01*
X59451Y-193272D01*
X60543Y-194439D01*
X60980Y-196772D01*
X60543Y-199106D01*
X59233Y-200564D01*
X57705Y-201439D01*
X52246D01*
G01X57705D02*
X60980Y-209897D01*
G01X71493Y-192397D02*
X76733D01*
G01X74113D02*
Y-209897D01*
G01X71493D02*
X76733D01*
G01X86154Y-192397D02*
X91613Y-209897D01*
X97072Y-192397D01*
G01X113480Y-209897D02*
X104746D01*
Y-192397D01*
X113480D01*
G01X109986Y-200855D02*
X104746D01*
G01X139746Y-209897D02*
Y-192397D01*
X144986D01*
X146733Y-193272D01*
X148043Y-195314D01*
X148480Y-197647D01*
X148043Y-199980D01*
X146951Y-201730D01*
X144986Y-202606D01*
X139746D01*
G01X157246Y-192397D02*
Y-209897D01*
X165980D01*
G01X173654D02*
X179113Y-192397D01*
X184572Y-209897D01*
G01X182606Y-203772D02*
X175619D01*
G01X191591Y-209897D02*
Y-192397D01*
X201635Y-209897D01*
Y-192397D01*
G01X218480Y-209897D02*
X209746D01*
Y-192397D01*
X218480D01*
G01X214986Y-200855D02*
X209746D01*
G01X250859Y-200564D02*
X251733Y-199689D01*
X252388Y-198231D01*
X252825Y-196188D01*
X252388Y-194439D01*
X251515Y-193272D01*
X249986Y-192397D01*
X244091D01*
Y-209897D01*
X251296D01*
X252825Y-208731D01*
X253698Y-206980D01*
X254135Y-204939D01*
X253698Y-202897D01*
X252388Y-201147D01*
X250859Y-200564D01*
X244091D01*
G01X266613Y-209897D02*
X264866Y-209605D01*
X263338Y-208439D01*
X262028Y-206689D01*
X261154Y-204647D01*
X260718Y-202314D01*
Y-199980D01*
X261154Y-197647D01*
X262028Y-195605D01*
X263338Y-193856D01*
X264866Y-192689D01*
X266613Y-192397D01*
X268359Y-192689D01*
X269888Y-193856D01*
X271198Y-195605D01*
X272072Y-197647D01*
X272508Y-199980D01*
Y-202314D01*
X272072Y-204647D01*
X271198Y-206689D01*
X269888Y-208439D01*
X268359Y-209605D01*
X266613Y-209897D01*
G01X278654D02*
X284113Y-192397D01*
X289572Y-209897D01*
G01X287606Y-203772D02*
X280619D01*
G01X297246Y-209897D02*
Y-192397D01*
X302705D01*
X304451Y-193272D01*
X305543Y-194439D01*
X305980Y-196772D01*
X305543Y-199106D01*
X304233Y-200564D01*
X302705Y-201439D01*
X297246D01*
G01X302705D02*
X305980Y-209897D01*
G01X314310D02*
Y-192397D01*
X318676D01*
X320423Y-193272D01*
X321733Y-194439D01*
X322825Y-196188D01*
X323698Y-198231D01*
X323916Y-201147D01*
X323698Y-204064D01*
X322825Y-206106D01*
X321733Y-207856D01*
X320423Y-209022D01*
X318676Y-209897D01*
X314310D01*
G01X94686Y-164897D02*
Y-147397D01*
X100363Y-161980D01*
X106040Y-147397D01*
Y-164897D01*
G01X117863D02*
X116553Y-164605D01*
X115243Y-163439D01*
X114369Y-161397D01*
X113933Y-159064D01*
X114369Y-156730D01*
X115243Y-154689D01*
X116553Y-153522D01*
X117863Y-153231D01*
X119173Y-153522D01*
X120483Y-154689D01*
X121356Y-156730D01*
X121575Y-159064D01*
X121356Y-161397D01*
X120483Y-163439D01*
X119173Y-164605D01*
X117863Y-164897D01*
G01X139293Y-147397D02*
Y-164897D01*
G01Y-162273D02*
X138420Y-163731D01*
X137109Y-164605D01*
X135581Y-164897D01*
X133835Y-164314D01*
X132525Y-162856D01*
X131651Y-161106D01*
X131433Y-159064D01*
X131651Y-157022D01*
X132525Y-155272D01*
X133835Y-153814D01*
X135581Y-153231D01*
X137109Y-153522D01*
X138201Y-154106D01*
X139293Y-155272D01*
G01X149588Y-157022D02*
X156575D01*
X155920Y-154980D01*
X154828Y-153814D01*
X153300Y-153231D01*
X151771Y-153522D01*
X150461Y-154397D01*
X149588Y-156439D01*
X149151Y-158189D01*
Y-159939D01*
X149588Y-161689D01*
X150680Y-163439D01*
X151990Y-164605D01*
X153518Y-164897D01*
X155046Y-164314D01*
X156575Y-162564D01*
G01X170363Y-164897D02*
Y-147397D01*
G01X376163Y-209897D02*
Y-192397D01*
X373543Y-195897D01*
G01Y-209897D02*
X378783D01*
G01X389515Y-195314D02*
X390825Y-193564D01*
X392353Y-192689D01*
X394100Y-192397D01*
X396283Y-192980D01*
X397811Y-194439D01*
X398248Y-196188D01*
X398030Y-197939D01*
X397156Y-199397D01*
X392790Y-202314D01*
X390825Y-204355D01*
X389515Y-207273D01*
X389078Y-209897D01*
X398248D01*
G01X413783D02*
Y-192397D01*
X405704Y-204939D01*
X416622D01*
G01X423860Y-206397D02*
X425169Y-208439D01*
X426916Y-209605D01*
X428881Y-209897D01*
X430628Y-209605D01*
X432375Y-208147D01*
X433466Y-206397D01*
X433685Y-204647D01*
X433248Y-202606D01*
X431720Y-201147D01*
X430191Y-200564D01*
X428226D01*
G01X430191D02*
X431501Y-199689D01*
X432593Y-198231D01*
X433030Y-196481D01*
X432593Y-194730D01*
X431501Y-193272D01*
X429536Y-192397D01*
X427571Y-192689D01*
X425606Y-193856D01*
G01X442015Y-195314D02*
X443325Y-193564D01*
X444853Y-192689D01*
X446600Y-192397D01*
X448783Y-192980D01*
X450311Y-194439D01*
X450748Y-196188D01*
X450530Y-197939D01*
X449656Y-199397D01*
X445290Y-202314D01*
X443325Y-204355D01*
X442015Y-207273D01*
X441578Y-209897D01*
X450748D01*
G01X363046Y-164897D02*
Y-147397D01*
X368286D01*
X370033Y-148272D01*
X371343Y-150314D01*
X371780Y-152647D01*
X371343Y-154980D01*
X370251Y-156730D01*
X368286Y-157606D01*
X363046D01*
G01X389716Y-148856D02*
X388406Y-147980D01*
X386878Y-147397D01*
X385131D01*
X383166Y-148272D01*
X381638Y-149730D01*
X380546Y-151481D01*
X379673Y-154397D01*
X379454Y-157022D01*
X379891Y-159647D01*
X380546Y-161397D01*
X381856Y-163147D01*
X383385Y-164314D01*
X384913Y-164897D01*
X386441D01*
X387970Y-164314D01*
X389280Y-163439D01*
X390372Y-162273D01*
G01X404159Y-155564D02*
X405033Y-154689D01*
X405688Y-153231D01*
X406125Y-151188D01*
X405688Y-149439D01*
X404815Y-148272D01*
X403286Y-147397D01*
X397391D01*
Y-164897D01*
X404596D01*
X406125Y-163731D01*
X406998Y-161980D01*
X407435Y-159939D01*
X406998Y-157897D01*
X405688Y-156147D01*
X404159Y-155564D01*
X397391D01*
G01X413363Y-170730D02*
X426463D01*
G01X432391Y-164897D02*
Y-147397D01*
X442435Y-164897D01*
Y-147397D01*
G01X454913Y-164897D02*
X453166Y-164605D01*
X451638Y-163439D01*
X450328Y-161689D01*
X449454Y-159647D01*
X449018Y-157314D01*
Y-154980D01*
X449454Y-152647D01*
X450328Y-150605D01*
X451638Y-148856D01*
X453166Y-147689D01*
X454913Y-147397D01*
X456659Y-147689D01*
X458188Y-148856D01*
X459498Y-150605D01*
X460372Y-152647D01*
X460808Y-154980D01*
Y-157314D01*
X460372Y-159647D01*
X459498Y-161689D01*
X458188Y-163439D01*
X456659Y-164605D01*
X454913Y-164897D01*
G01X505754Y-147397D02*
X511213Y-164897D01*
X516672Y-147397D01*
G01X533080Y-164897D02*
X524346D01*
Y-147397D01*
X533080D01*
G01X529586Y-155855D02*
X524346D01*
G01X541846Y-164897D02*
Y-147397D01*
X547305D01*
X549051Y-148272D01*
X550143Y-149439D01*
X550580Y-151772D01*
X550143Y-154106D01*
X548833Y-155564D01*
X547305Y-156439D01*
X541846D01*
G01X547305D02*
X550580Y-164897D01*
G01X563713Y-165480D02*
X563276Y-165189D01*
Y-164605D01*
X563713Y-164314D01*
X564150Y-164605D01*
Y-165189D01*
X563713Y-165480D01*
G01X537463Y-209897D02*
Y-192397D01*
X534843Y-195897D01*
G01Y-209897D02*
X540083D01*
G01X630546Y-147397D02*
Y-164897D01*
X639280D01*
G01X656343D02*
Y-153231D01*
G01Y-155272D02*
X655470Y-154106D01*
X654159Y-153522D01*
X652631Y-153231D01*
X651103Y-153814D01*
X649793Y-154980D01*
X648919Y-156730D01*
X648483Y-159064D01*
X648919Y-161397D01*
X649793Y-163147D01*
X651103Y-164314D01*
X652631Y-164897D01*
X654159Y-164605D01*
X655470Y-163731D01*
X656343Y-162564D01*
G01X665328Y-170147D02*
X666638Y-170730D01*
X668385Y-170147D01*
X669476Y-168981D01*
X670350Y-167522D01*
X671659Y-162856D01*
X674498Y-153231D01*
G01X667511D02*
X671659Y-162856D01*
G01X684138Y-157022D02*
X691125D01*
X690470Y-154980D01*
X689378Y-153814D01*
X687850Y-153231D01*
X686321Y-153522D01*
X685011Y-154397D01*
X684138Y-156439D01*
X683701Y-158189D01*
Y-159939D01*
X684138Y-161689D01*
X685230Y-163439D01*
X686540Y-164605D01*
X688068Y-164897D01*
X689596Y-164314D01*
X691125Y-162564D01*
G01X701856Y-164897D02*
Y-153231D01*
G01Y-155564D02*
X702948Y-154397D01*
X704040Y-153522D01*
X705568Y-153231D01*
X706659Y-153522D01*
X707970Y-154397D01*
G01X719138Y-162856D02*
X720230Y-164022D01*
X721758Y-164897D01*
X723068D01*
X724378Y-164314D01*
X725251Y-163439D01*
X725688Y-162273D01*
X725470Y-160522D01*
X724596Y-159647D01*
X720666Y-157897D01*
X719793Y-155855D01*
X720230Y-154397D01*
X721103Y-153522D01*
X722413Y-153231D01*
X723723Y-153522D01*
X725033Y-154397D01*
G01X665546Y-192397D02*
Y-209897D01*
X674280D01*
G01X687413D02*
Y-192397D01*
X684793Y-195897D01*
G01Y-209897D02*
X690033D01*
G01X781410Y-164897D02*
Y-147397D01*
X785776D01*
X787523Y-148272D01*
X788833Y-149439D01*
X789925Y-151188D01*
X790798Y-153231D01*
X791016Y-156147D01*
X790798Y-159064D01*
X789925Y-161106D01*
X788833Y-162856D01*
X787523Y-164022D01*
X785776Y-164897D01*
X781410D01*
G01X800438Y-157022D02*
X807425D01*
X806770Y-154980D01*
X805678Y-153814D01*
X804150Y-153231D01*
X802621Y-153522D01*
X801311Y-154397D01*
X800438Y-156439D01*
X800001Y-158189D01*
Y-159939D01*
X800438Y-161689D01*
X801530Y-163439D01*
X802840Y-164605D01*
X804368Y-164897D01*
X805896Y-164314D01*
X807425Y-162564D01*
G01X817938Y-162856D02*
X819030Y-164022D01*
X820558Y-164897D01*
X821868D01*
X823178Y-164314D01*
X824051Y-163439D01*
X824488Y-162273D01*
X824270Y-160522D01*
X823396Y-159647D01*
X819466Y-157897D01*
X818593Y-155855D01*
X819030Y-154397D01*
X819903Y-153522D01*
X821213Y-153231D01*
X822523Y-153522D01*
X823833Y-154397D01*
G01X838713Y-153231D02*
Y-164897D01*
G01Y-148564D02*
X838276Y-148272D01*
Y-147689D01*
X838713Y-147397D01*
X839150Y-147689D01*
Y-148272D01*
X838713Y-148564D01*
G01X853156Y-169272D02*
X854685Y-170439D01*
X856431Y-170730D01*
X857959Y-170439D01*
X859270Y-168981D01*
X860143Y-166939D01*
Y-153231D01*
G01Y-155564D02*
X859270Y-154397D01*
X857959Y-153522D01*
X856431Y-153231D01*
X854685Y-153814D01*
X853593Y-154980D01*
X852719Y-157022D01*
X852283Y-159064D01*
X852501Y-160814D01*
X853375Y-162856D01*
X854685Y-164314D01*
X856431Y-164897D01*
X857741Y-164605D01*
X859270Y-163439D01*
X860143Y-162273D01*
G01X870001Y-164897D02*
Y-153231D01*
G01Y-156147D02*
X870875Y-154689D01*
X872185Y-153522D01*
X873931Y-153231D01*
X875459Y-153522D01*
X876770Y-154689D01*
X877425Y-156730D01*
Y-164897D01*
G01X887938Y-157022D02*
X894925D01*
X894270Y-154980D01*
X893178Y-153814D01*
X891650Y-153231D01*
X890121Y-153522D01*
X888811Y-154397D01*
X887938Y-156439D01*
X887501Y-158189D01*
Y-159939D01*
X887938Y-161689D01*
X889030Y-163439D01*
X890340Y-164605D01*
X891868Y-164897D01*
X893396Y-164314D01*
X894925Y-162564D01*
G01X905656Y-164897D02*
Y-153231D01*
G01Y-155564D02*
X906748Y-154397D01*
X907840Y-153522D01*
X909368Y-153231D01*
X910459Y-153522D01*
X911770Y-154397D01*
G01X825596Y-209897D02*
Y-192397D01*
X831055D01*
X832801Y-193272D01*
X833893Y-194439D01*
X834330Y-196772D01*
X833893Y-199106D01*
X832583Y-200564D01*
X831055Y-201439D01*
X825596D01*
G01X831055D02*
X834330Y-209897D01*
G01X847463D02*
X846153Y-209605D01*
X844843Y-208439D01*
X843969Y-206397D01*
X843533Y-204064D01*
X843969Y-201730D01*
X844843Y-199689D01*
X846153Y-198522D01*
X847463Y-198231D01*
X848773Y-198522D01*
X850083Y-199689D01*
X850956Y-201730D01*
X851175Y-204064D01*
X850956Y-206397D01*
X850083Y-208439D01*
X848773Y-209605D01*
X847463Y-209897D01*
G01X861033D02*
Y-192397D01*
G01Y-201147D02*
X862125Y-199397D01*
X863435Y-198522D01*
X864745Y-198231D01*
X866709Y-198814D01*
X868020Y-199980D01*
X868893Y-202022D01*
Y-204355D01*
X868456Y-206689D01*
X867583Y-208439D01*
X866055Y-209605D01*
X864745Y-209897D01*
X863435Y-209605D01*
X862125Y-208731D01*
X861033Y-207273D01*
G01X952413Y-209897D02*
Y-192397D01*
X949793Y-195897D01*
G01Y-209897D02*
X955033D01*
G01X969913Y-192397D02*
X968166Y-192980D01*
X966856Y-194439D01*
X965983Y-196188D01*
X965328Y-198522D01*
X965110Y-201147D01*
X965328Y-203772D01*
X965983Y-206106D01*
X966856Y-207856D01*
X968166Y-209314D01*
X969913Y-209897D01*
X971659Y-209314D01*
X972970Y-207856D01*
X973843Y-206106D01*
X974498Y-203772D01*
X974716Y-201147D01*
X974498Y-198522D01*
X973843Y-196188D01*
X972970Y-194439D01*
X971659Y-192980D01*
X969913Y-192397D01*
G01X983483Y-210480D02*
X991343Y-192397D01*
G01X1004913Y-209897D02*
Y-192397D01*
X1002293Y-195897D01*
G01Y-209897D02*
X1007533D01*
G01X1018265Y-202606D02*
X1019793Y-200564D01*
X1021103Y-199397D01*
X1022850Y-198814D01*
X1024378Y-199397D01*
X1025470Y-200564D01*
X1026343Y-202314D01*
X1026561Y-204355D01*
X1026343Y-206106D01*
X1025470Y-207856D01*
X1024159Y-209314D01*
X1022631Y-209897D01*
X1020885Y-209314D01*
X1019356Y-207564D01*
X1018483Y-204939D01*
X1018265Y-202022D01*
X1018701Y-198231D01*
X1019356Y-196188D01*
X1020448Y-194147D01*
X1021976Y-192689D01*
X1023505Y-192397D01*
X1025033Y-192980D01*
X1026125Y-194439D01*
G01X1035983Y-210480D02*
X1043843Y-192397D01*
G01X1053265Y-195314D02*
X1054575Y-193564D01*
X1056103Y-192689D01*
X1057850Y-192397D01*
X1060033Y-192980D01*
X1061561Y-194439D01*
X1061998Y-196188D01*
X1061780Y-197939D01*
X1060906Y-199397D01*
X1056540Y-202314D01*
X1054575Y-204355D01*
X1053265Y-207273D01*
X1052828Y-209897D01*
X1061998D01*
G01X1074913Y-192397D02*
X1073166Y-192980D01*
X1071856Y-194439D01*
X1070983Y-196188D01*
X1070328Y-198522D01*
X1070110Y-201147D01*
X1070328Y-203772D01*
X1070983Y-206106D01*
X1071856Y-207856D01*
X1073166Y-209314D01*
X1074913Y-209897D01*
X1076659Y-209314D01*
X1077970Y-207856D01*
X1078843Y-206106D01*
X1079498Y-203772D01*
X1079716Y-201147D01*
X1079498Y-198522D01*
X1078843Y-196188D01*
X1077970Y-194439D01*
X1076659Y-192980D01*
X1074913Y-192397D01*
G01X1092413Y-209897D02*
Y-192397D01*
X1089793Y-195897D01*
G01Y-209897D02*
X1095033D01*
G01X1105765Y-195314D02*
X1107075Y-193564D01*
X1108603Y-192689D01*
X1110350Y-192397D01*
X1112533Y-192980D01*
X1114061Y-194439D01*
X1114498Y-196188D01*
X1114280Y-197939D01*
X1113406Y-199397D01*
X1109040Y-202314D01*
X1107075Y-204355D01*
X1105765Y-207273D01*
X1105328Y-209897D01*
X1114498D01*
G01X1000110Y-164897D02*
Y-147397D01*
X1004476D01*
X1006223Y-148272D01*
X1007533Y-149439D01*
X1008625Y-151188D01*
X1009498Y-153231D01*
X1009716Y-156147D01*
X1009498Y-159064D01*
X1008625Y-161106D01*
X1007533Y-162856D01*
X1006223Y-164022D01*
X1004476Y-164897D01*
X1000110D01*
G01X1026343D02*
Y-153231D01*
G01Y-155272D02*
X1025470Y-154106D01*
X1024159Y-153522D01*
X1022631Y-153231D01*
X1021103Y-153814D01*
X1019793Y-154980D01*
X1018919Y-156730D01*
X1018483Y-159064D01*
X1018919Y-161397D01*
X1019793Y-163147D01*
X1021103Y-164314D01*
X1022631Y-164897D01*
X1024159Y-164605D01*
X1025470Y-163731D01*
X1026343Y-162564D01*
G01X1039913Y-147397D02*
Y-164897D01*
G01X1036856Y-153231D02*
X1042970D01*
G01X1054138Y-157022D02*
X1061125D01*
X1060470Y-154980D01*
X1059378Y-153814D01*
X1057850Y-153231D01*
X1056321Y-153522D01*
X1055011Y-154397D01*
X1054138Y-156439D01*
X1053701Y-158189D01*
Y-159939D01*
X1054138Y-161689D01*
X1055230Y-163439D01*
X1056540Y-164605D01*
X1058068Y-164897D01*
X1059596Y-164314D01*
X1061125Y-162564D01*
G54D20*
X18299Y1948050D03*
Y1952050D03*
Y1940050D03*
X31299Y611550D03*
X55799Y203550D03*
Y207550D03*
Y211550D03*
X56299Y1017050D03*
X56236Y1021050D03*
Y1025050D03*
X52299Y1897050D03*
X77799Y204550D03*
Y208550D03*
X77801Y611450D03*
Y615450D03*
X81300Y1008500D03*
X82549Y1828613D03*
X73799Y1837550D03*
X74049Y1843113D03*
X82549Y1832613D03*
X73799Y1849050D03*
X97300Y1115400D03*
X100549Y1476050D03*
X105550Y972000D03*
X105499Y967850D03*
X124780Y1098482D03*
Y1094482D03*
X112799Y1298113D03*
X108049Y1476050D03*
X114049Y1702613D03*
X143800Y545000D03*
X138700Y1335800D03*
X127799Y1342050D03*
X128300Y1361000D03*
X148299Y517613D03*
X155999Y524850D03*
X163499D03*
X179472Y90572D03*
Y86572D03*
X183199Y152000D03*
X170999Y524850D03*
X183199Y559300D03*
X171299Y916113D03*
X183699Y963100D03*
X170800Y1691200D03*
X182699Y1773200D03*
X199199Y1367400D03*
X230172Y92572D03*
X230299Y105050D03*
X226298Y287114D03*
X226299Y693550D03*
X238299Y95550D03*
X240600Y269700D03*
X240000Y677100D03*
X302299Y86613D03*
X305299Y334050D03*
Y339050D03*
X315000Y365200D03*
X306799Y742050D03*
Y746050D03*
X303299Y1554550D03*
Y1558550D03*
X315000Y1582600D03*
X310521Y1944909D03*
Y1948909D03*
X316200Y105200D03*
X329798Y337114D03*
Y333114D03*
X331299Y745050D03*
Y741050D03*
X316000Y772200D03*
X327799Y1553550D03*
Y1557550D03*
X336021Y1947409D03*
Y1943409D03*
X318200Y1971900D03*
X375400Y42300D03*
X697349Y1801634D03*
Y1808634D03*
X751278Y323924D03*
Y328924D03*
X749996Y724882D03*
Y729882D03*
X750633Y1126392D03*
Y1131392D03*
X753627Y1531296D03*
Y1536296D03*
X750114Y1937713D03*
Y1942213D03*
X776299Y326550D03*
Y322550D03*
X768278Y347924D03*
Y352424D03*
X774299Y724050D03*
Y728550D03*
X766496Y748382D03*
Y752882D03*
X775299Y1127550D03*
Y1123550D03*
X766633Y1152392D03*
Y1156892D03*
X777481Y1527893D03*
Y1531893D03*
X769127Y1554796D03*
Y1559296D03*
X774799Y1935050D03*
Y1939050D03*
X766614Y1960713D03*
Y1965213D03*
X797299Y336050D03*
Y332050D03*
X795799Y736050D03*
Y732050D03*
Y1133050D03*
Y1137050D03*
X798481Y1538893D03*
Y1542893D03*
X796981Y1944393D03*
Y1948393D03*
X813299Y167050D03*
X820799D03*
X813799Y1788050D03*
X821299D03*
X828299Y167050D03*
X844500Y677700D03*
X844100Y1083200D03*
X828799Y1788050D03*
X845800Y276800D03*
X846100Y1488100D03*
X846599Y1893850D03*
X869799Y1359550D03*
Y1363550D03*
Y1367550D03*
X902299Y107050D03*
Y103050D03*
X927699Y158500D03*
X912699Y557800D03*
X913199Y962100D03*
X912699Y1771700D03*
G54D11*
G01X8499Y1937550D02*
X12749Y1933300D01*
X19749D01*
X21749Y1935300D01*
Y1936050D01*
G01X18499Y1929550D02*
X19199D01*
X21037Y1931388D01*
X28150D01*
X30888Y1928650D01*
X33573D01*
G01X18499Y1923550D02*
Y1922750D01*
X21367Y1919882D01*
X24660D01*
X28042Y1916500D01*
X34699D01*
X36249Y1918050D01*
G01D02*
Y1917300D01*
X40899Y1912650D01*
Y1912934D01*
X41597D01*
G01X38462Y1937069D02*
Y1933013D01*
X36499Y1931050D01*
X32499D01*
X27999Y1935550D01*
X26499D01*
G01X36494Y1937069D02*
Y1934045D01*
X35999Y1933550D01*
X33499D01*
X28799Y1938250D01*
Y1939750D01*
X26999Y1941550D01*
G01X42399Y1937069D02*
Y1935468D01*
X42299Y1935368D01*
Y1929754D01*
X39990Y1927445D01*
G01X27030Y1928688D02*
X27830Y1927888D01*
X28150D01*
X29988Y1926050D01*
X38595D01*
X39990Y1927445D01*
G01X40431Y1937069D02*
Y1931482D01*
X37599Y1928650D01*
X33573D01*
G01X36249Y1921550D02*
Y1922800D01*
X37299Y1923850D01*
X43799D01*
X43999Y1924050D01*
G01X21749Y1936050D02*
X25999D01*
X26499Y1935550D01*
G01X34525Y1956355D02*
X33194D01*
X31499Y1958050D01*
X28701D01*
X28389Y1958362D01*
G01X34525Y1937069D02*
X33980D01*
X30999Y1940050D01*
Y1942550D01*
X26499Y1947050D01*
G01X21749Y1948050D02*
X25499D01*
X26499Y1947050D01*
G01X40431Y1956355D02*
Y1966318D01*
X37999Y1968750D01*
G01X38462Y1956355D02*
Y1961716D01*
X36878Y1963300D01*
X36699D01*
G01X31999Y1964800D02*
X32249Y1964550D01*
X35499D01*
X36699Y1963350D01*
Y1963300D01*
G01X32999Y1960555D02*
X35489D01*
X36494Y1959550D01*
Y1956355D01*
G01X27999Y1964800D02*
X32244Y1960555D01*
X32999D01*
G01X19999Y1964800D02*
X23999D01*
G01D02*
X24499Y1964300D01*
X24934D01*
X26485Y1962749D01*
Y1960266D01*
X28389Y1958362D01*
G01X43462Y1961160D02*
Y1960918D01*
X42399Y1959855D01*
Y1956355D01*
G01X43999Y1964800D02*
X44499Y1964300D01*
Y1961955D01*
X43704Y1961160D01*
X43462D01*
G01X182922Y86572D02*
X187999Y81495D01*
Y79550D01*
X191499Y76050D01*
Y74497D01*
G01X185999Y95050D02*
X188999Y92050D01*
Y88550D01*
G01X201033Y82371D02*
Y84050D01*
X202999Y86016D01*
X206965D01*
X208999Y88050D01*
Y92050D01*
G01X209499Y97800D02*
X208999Y97300D01*
Y92050D01*
G01X201033Y74497D02*
X191499D01*
G01X197226Y90428D02*
Y97527D01*
X197499Y97800D01*
G01X201033Y78434D02*
X195615D01*
X193999Y80050D01*
Y87201D01*
X197226Y90428D01*
G01X201033Y80402D02*
X197647D01*
X196499Y81550D01*
Y83902D01*
X198647Y86050D01*
Y86198D01*
X202999Y90550D01*
G01X201499Y97800D02*
Y95050D01*
X202999Y93550D01*
Y90550D01*
G01X201033Y76465D02*
X194584D01*
X190499Y80550D01*
Y87050D01*
X188999Y88550D01*
G01X205499Y97800D02*
X201499D01*
G01X220319Y78434D02*
X225383D01*
X226896Y79947D01*
Y82045D01*
X226999Y82148D01*
Y84750D01*
X227022Y84773D01*
Y85278D01*
G01X230122Y92572D02*
X226999Y89449D01*
Y85478D01*
X227022Y85455D01*
Y85278D01*
G01X220319Y76465D02*
X226914D01*
X229296Y78847D01*
Y81050D01*
G01X240999Y89850D02*
X238199Y87050D01*
X233884D01*
X233834Y87000D01*
X233722D01*
X229296Y82574D01*
Y81050D01*
G01X230749Y76300D02*
X228946Y74497D01*
X220319D01*
G01X235499Y84800D02*
X234634D01*
X232999Y83165D01*
Y80800D01*
X231999Y79800D01*
Y77550D01*
X230749Y76300D01*
G01X230249Y97050D02*
X226499D01*
X224499Y95050D01*
Y92050D01*
G01X220319Y80402D02*
X223851D01*
X224499Y81050D01*
Y92050D01*
G01X220319Y82371D02*
Y96870D01*
X223499Y100050D01*
X225499D01*
G01X217499Y97800D02*
X213499D01*
G01D02*
X209499D01*
G01X230249Y105050D02*
Y101050D01*
G01D02*
X229249Y100050D01*
X225499D01*
G01X233622Y92572D02*
Y90974D01*
X230874Y88226D01*
X230811D01*
G01X238249Y95550D02*
X236600D01*
X233622Y92572D01*
G01X835749Y167550D02*
X833012Y170287D01*
Y176948D01*
X833013Y176949D01*
G01X905749Y99050D02*
X905499Y98800D01*
Y94550D01*
G01X907999Y88300D02*
Y89438D01*
X905499Y91938D01*
Y94550D01*
G01X904499Y88300D02*
Y89050D01*
X901499Y92050D01*
G01X906499Y115050D02*
Y110323D01*
X908999Y107823D01*
Y103550D01*
X910499Y102050D01*
Y98550D01*
G01X905749Y103050D02*
X907999Y100800D01*
Y92550D01*
X912399Y88150D01*
G01X918856Y91456D02*
X915593D01*
X912999Y94050D01*
Y101050D01*
X914999Y103050D01*
G01X918856Y93424D02*
X916499D01*
X915499Y94424D01*
Y97550D01*
X920999Y103050D01*
G01X918856Y89487D02*
X914762D01*
X910499Y93750D01*
Y98550D01*
G01X918856Y87519D02*
X913030D01*
X912399Y88150D01*
G01X912499Y108300D02*
X911699Y109100D01*
X911379D01*
X909799Y110680D01*
Y118299D01*
X920550Y129050D01*
X947499D01*
X958499Y118050D01*
Y111050D01*
X955749Y108300D01*
X952499D01*
G01X912499D02*
Y105550D01*
X914999Y103050D01*
G01X918856Y95393D02*
Y96907D01*
X920499Y98550D01*
X923499D01*
X926499Y101550D01*
Y103050D01*
G01X924499Y108300D02*
Y105050D01*
X926499Y103050D01*
G01X951249Y96050D02*
X949999Y94800D01*
Y91250D01*
X946268Y87519D01*
X938142D01*
G01Y89487D02*
X944436D01*
X946999Y92050D01*
Y99350D01*
X949199Y101550D01*
G01X938142Y91456D02*
X942405D01*
X944499Y93550D01*
Y95050D01*
G01X938142Y93424D02*
X940873D01*
X941873Y94424D01*
Y103050D01*
G01X949199Y101550D02*
Y102250D01*
X952249Y105300D01*
X960068D01*
X964042Y101326D01*
Y96050D01*
G01X948499Y108300D02*
X945749Y105550D01*
X945499D01*
X944499Y104550D01*
Y95050D01*
G01Y108300D02*
X941873Y105674D01*
Y103050D01*
G01X938142Y95393D02*
Y100407D01*
X935999Y102550D01*
Y104050D01*
G01X940499Y108300D02*
X936499D01*
G01D02*
X935999Y107800D01*
Y104050D01*
G01X961499Y93350D02*
X953699D01*
X952049Y95000D01*
Y95250D01*
X951249Y96050D01*
G01X958499Y89550D02*
X961999D01*
X964042Y91593D01*
Y96050D01*
X-38436Y23633D03*
X-36811Y1104775D03*
X-35919Y1969497D03*
X9843Y353144D03*
Y717711D03*
Y762617D03*
Y875216D03*
Y1337396D03*
Y1701963D03*
Y1746869D03*
Y1859468D03*
X78150Y28858D03*
Y178464D03*
Y434370D03*
Y583976D03*
Y839882D03*
Y989488D03*
Y1245394D03*
Y1395000D03*
Y1650906D03*
Y1800512D03*
X158071Y191614D03*
Y341220D03*
Y597126D03*
Y746732D03*
Y1002638D03*
Y1152244D03*
Y1408150D03*
Y1557756D03*
Y1813662D03*
Y1963268D03*
X886417Y191614D03*
Y341220D03*
Y597126D03*
Y746732D03*
Y1002638D03*
Y1152244D03*
Y1408150D03*
Y1557756D03*
Y1813662D03*
Y1963268D03*
X1019291Y1416024D03*
Y1694212D03*
X1072493Y21507D03*
X1075940Y1769358D03*
G54D30*
X30499Y1588660D03*
X31999Y1918850D03*
X23999Y1964850D03*
X27999D03*
X46800Y408900D03*
X42900Y601400D03*
X103999Y1468600D03*
X119499Y1106350D03*
X109499Y1198413D03*
X105499D03*
X106999Y1223913D03*
X111999D03*
X111499Y1468600D03*
X115599Y1468550D03*
X141499Y440413D03*
X146499D03*
X136000Y528800D03*
X135999Y1703350D03*
X131999D03*
X159199Y517150D03*
X167199D03*
X166499Y808913D03*
X167499Y833413D03*
X152600Y1681200D03*
X174999Y71350D03*
X185499Y117350D03*
X174199Y517150D03*
X170499Y808913D03*
X172499Y833413D03*
X184600Y1373100D03*
X180500D03*
X201499Y97850D03*
X209499D03*
X192800Y1651100D03*
X217499Y97850D03*
X223436Y1893665D03*
X644049Y1803934D03*
Y1792934D03*
X708549Y1808634D03*
X710549Y1797934D03*
X754978Y335724D03*
X753196Y735182D03*
X755499Y1140350D03*
X756327Y1543096D03*
X753314Y1948513D03*
X816499Y159350D03*
X814999Y1780350D03*
X823999Y159350D03*
X831499D03*
X826100Y666700D03*
X833499Y1780350D03*
X824499D03*
X828000Y1881300D03*
X900499Y84850D03*
X903499Y128350D03*
X924499Y108350D03*
X916499D03*
X932499D03*
X944499D03*
X940499D03*
X952499D03*
G54D21*
X20799Y1973700D03*
X946999Y116300D03*
G54D12*
X17600Y5604D03*
X10000Y16500D03*
X11999Y53550D03*
X11499Y34050D03*
X11999Y69050D03*
Y88550D03*
X11499Y106050D03*
X11999Y124550D03*
X11499Y142050D03*
X11999Y177050D03*
Y161550D03*
Y196550D03*
X11499Y214050D03*
X9499Y229050D03*
X8999Y246550D03*
X9499Y281550D03*
Y266050D03*
Y301050D03*
X15499Y328050D03*
X8999Y318550D03*
X15499Y342550D03*
Y360050D03*
X14799Y751450D03*
X8599Y751650D03*
X17299Y773950D03*
X10999Y774050D03*
X8999Y889550D03*
X8499Y907050D03*
X8999Y942050D03*
Y926550D03*
Y961550D03*
X8499Y979050D03*
X8999Y988550D03*
Y1025550D03*
X8499Y1006050D03*
X8999Y1041050D03*
Y1060550D03*
X8499Y1089050D03*
Y1078050D03*
X7999Y1106550D03*
X8499Y1126050D03*
Y1141550D03*
Y1161050D03*
X7999Y1192550D03*
Y1178550D03*
X7499Y1210050D03*
X7999Y1229550D03*
Y1245050D03*
Y1264550D03*
X7499Y1282050D03*
X8299Y1320050D03*
X8799Y1302550D03*
X18099Y1343550D03*
X9399Y1347350D03*
X15299Y1723450D03*
X15399Y1708350D03*
X7099Y1717750D03*
X7199Y1731450D03*
X14899Y1736250D03*
X15299Y1753250D03*
X6099Y1753750D03*
X11299Y1850050D03*
X9099Y1881550D03*
X8499Y1979550D03*
X11500Y1987000D03*
X36000Y5604D03*
X23499Y27050D03*
X40999Y27550D03*
X27799Y38450D03*
X40999Y42050D03*
X25799Y64050D03*
X28399Y94950D03*
X34999Y108550D03*
X41399Y134150D03*
X27999Y131050D03*
Y145550D03*
Y163050D03*
X23999Y243550D03*
Y229050D03*
Y261050D03*
X39999Y327550D03*
Y342050D03*
Y359550D03*
Y576550D03*
X28586Y600248D03*
X34700Y623000D03*
X39499Y615550D03*
X28519Y605048D03*
X36999Y725050D03*
Y719550D03*
X37499Y714050D03*
X41499Y719550D03*
X26399Y750850D03*
X36499Y740050D03*
Y732550D03*
X39899Y754850D03*
X39399Y768750D03*
X27199Y764950D03*
X28599Y775450D03*
X40734Y802473D03*
X26799Y874550D03*
X26099Y891650D03*
X25699Y916150D03*
X25099Y942150D03*
X23899Y957950D03*
X24799Y992250D03*
X33899Y1005950D03*
X21499Y1073250D03*
X22300Y1069100D03*
X21399Y1090850D03*
X21299Y1300250D03*
X21799Y1282750D03*
X38499Y1601050D03*
X31499Y1849750D03*
X39399Y1864350D03*
X23999Y1857950D03*
X27199Y1874350D03*
X34799Y1890050D03*
X39990Y1927445D03*
X33573Y1928650D03*
X26499Y1947050D03*
X36699Y1963300D03*
X26999Y1973550D03*
X28389Y1958362D03*
X26500Y1987000D03*
X55700Y5900D03*
X50999Y21150D03*
Y47750D03*
X59499Y90550D03*
Y76050D03*
Y108050D03*
X52499Y130550D03*
Y145050D03*
Y162550D03*
X41699Y183250D03*
X52499Y198550D03*
X61757Y216415D03*
X56999Y217050D03*
X41499Y219050D03*
X48499Y243050D03*
Y228550D03*
Y260550D03*
X42999Y275650D03*
X51099Y300050D03*
X52199Y342350D03*
X52730Y406470D03*
X42299Y564150D03*
X62055Y561550D03*
X49555Y563550D03*
X61099Y603236D03*
X60400Y616000D03*
X55500Y618500D03*
X41367Y639102D03*
X53400Y630500D03*
X52333Y641295D03*
X43500Y631500D03*
X61999Y661550D03*
X43499Y657550D03*
X47800Y692800D03*
X53210Y701486D03*
X50999Y720050D03*
X46499Y719550D03*
X51499Y724550D03*
X46499D03*
X41999D03*
X46499Y730550D03*
X41999Y735050D03*
Y731050D03*
X46499Y735050D03*
X41999Y739550D03*
X46499Y739050D03*
X51999Y767050D03*
X47999Y767550D03*
X52499Y771550D03*
X47999D03*
X53999Y791000D03*
X52499Y1013550D03*
X60172Y1566828D03*
X42449Y1588600D03*
X57999Y1830050D03*
X46499Y1850050D03*
X46999Y1832550D03*
X52999Y1871550D03*
X57499Y1871050D03*
X45699Y1875550D03*
X47499Y1915050D03*
X41597Y1912934D03*
X47499Y1930550D03*
X43999Y1924050D03*
X62499Y1939550D03*
X58999Y1958050D03*
X44624Y1974886D03*
X61500Y1987500D03*
X44500Y1987000D03*
X55999Y1982550D03*
X73900Y6200D03*
X65499Y27050D03*
Y41550D03*
Y59050D03*
X77165Y110799D03*
X71015Y123666D03*
X78165Y137116D03*
X69510Y217221D03*
X77749Y213500D03*
X75299Y261750D03*
X76099Y414250D03*
X75300Y454100D03*
X67300Y450200D03*
X68899Y445450D03*
X66099Y500950D03*
X77165Y514650D03*
X70800Y540300D03*
X75999Y556640D03*
X72599Y578236D03*
X71800Y622700D03*
X62500Y633300D03*
X66023Y638100D03*
X76499Y637550D03*
X79299Y794150D03*
X67999Y790400D03*
X76399Y820450D03*
X70100Y818900D03*
X77499Y921550D03*
X77002Y952079D03*
X76711Y948089D03*
X77499Y962152D03*
X72799Y982950D03*
X65799Y994050D03*
X67000Y1011500D03*
X68000Y1028800D03*
X74999Y1126550D03*
X77165Y1327335D03*
X77166Y1353400D03*
X76499Y1507050D03*
Y1498050D03*
Y1512050D03*
Y1503050D03*
X76999Y1528050D03*
Y1519050D03*
X63014Y1560986D03*
X81499Y1589050D03*
X83499Y1594050D03*
X78999Y1593550D03*
X74999D03*
X74499Y1602050D03*
Y1598050D03*
X83499D03*
Y1602050D03*
X78999Y1598050D03*
Y1602050D03*
X83599Y1744750D03*
X77165Y1759550D03*
X78529Y1788113D03*
X78099Y1827250D03*
X81499Y1847550D03*
X77999Y1832350D03*
X78999Y1891550D03*
X82999D03*
Y1887550D03*
X78999D03*
X62999Y1914550D03*
X78999Y1896050D03*
X78433Y1900010D03*
X78999Y1904050D03*
X83499Y1896050D03*
X83433Y1904010D03*
X62999Y1926050D03*
X81499Y1915550D03*
X82499Y1957050D03*
X73499D03*
X66499D03*
X73499Y1945550D03*
X79500Y1987500D03*
X65499Y1982550D03*
X73499D03*
X82999D03*
X90900Y5800D03*
X90899Y14850D03*
X96999Y49550D03*
X92999Y52050D03*
X97800Y36000D03*
X96900Y40400D03*
X93000Y44900D03*
X92900Y39700D03*
X95814Y136065D03*
X96184Y151065D03*
Y166065D03*
X97999Y199050D03*
X92899Y231450D03*
X86899Y242750D03*
X93199Y279650D03*
X84899Y289250D03*
X90899Y309550D03*
X94199Y325550D03*
X93499Y337450D03*
X89899Y368350D03*
X95499Y355450D03*
X89999Y396450D03*
X87599Y403950D03*
X95399Y416350D03*
X89099Y426150D03*
X99399Y437450D03*
X93500Y445300D03*
X97699Y449850D03*
X93199D03*
X97999Y445550D03*
X94500Y456800D03*
X100500Y456700D03*
X98999Y488050D03*
X94499Y486550D03*
X93499Y477050D03*
X97699Y481550D03*
Y477050D03*
X93499Y481550D03*
X101500Y536500D03*
X93599Y581236D03*
X93100Y571640D03*
X92599Y606236D03*
X98001Y856950D03*
X97800Y851800D03*
X93808Y852063D03*
X94001Y856895D03*
X97499Y862050D03*
X93299D03*
X93499Y897152D03*
X93900Y882400D03*
X97900D03*
X97700Y887400D03*
X93690Y887139D03*
X97499Y892550D03*
X93499Y892050D03*
X93000Y907165D03*
X83988Y934028D03*
X86700Y982100D03*
X100999Y1101050D03*
X104999D03*
X100999Y1096550D03*
X94735Y1110135D03*
X102999Y1188050D03*
X99999Y1202550D03*
X100999Y1213550D03*
X100499Y1226050D03*
X104999Y1231050D03*
X100999Y1231032D03*
X103499Y1305050D03*
X93316Y1351000D03*
X96000Y1369000D03*
X96100Y1384650D03*
X97999Y1486550D03*
X95899Y1475350D03*
X97300Y1564100D03*
X92499Y1589050D03*
X86999D03*
X90999Y1628550D03*
Y1624550D03*
X91121Y1632549D03*
X86299Y1632550D03*
X85999Y1628550D03*
Y1624550D03*
X84099Y1737150D03*
X93499Y1759550D03*
X94336Y1773113D03*
X104417Y1791480D03*
X97999Y1815050D03*
X104500Y1813400D03*
X89499Y1843113D03*
X83499Y1841550D03*
X90800Y1832500D03*
X83999Y1900050D03*
Y1945050D03*
X98433Y1940510D03*
X98999Y1944550D03*
X102433Y1940555D03*
X103433Y1944510D03*
X92499Y1959050D03*
X101699Y1983850D03*
X98000Y1987500D03*
X91499Y1983050D03*
X107000Y6000D03*
X116400Y56000D03*
X114800Y68500D03*
X123499Y149050D03*
Y140050D03*
X117500Y162300D03*
X124300Y167800D03*
X109499Y410250D03*
X124899Y409050D03*
X126099Y396150D03*
X111299Y425850D03*
X122499Y427900D03*
X108599Y557236D03*
X108900Y587600D03*
X112200Y762200D03*
X112000Y773000D03*
X106499Y834550D03*
X111299Y821050D03*
X112999Y901150D03*
X106500Y943000D03*
X105300Y960300D03*
X105006Y1096866D03*
X124999Y1110550D03*
X110999Y1130550D03*
X115200Y1130300D03*
X110999Y1126050D03*
Y1122050D03*
Y1118050D03*
X114999Y1126050D03*
Y1122050D03*
Y1118050D03*
X106999Y1114960D03*
X121999Y1117050D03*
X114499Y1135050D03*
X120999Y1188050D03*
X111999D03*
X115499Y1197550D03*
X117499Y1214050D03*
X123299Y1206900D03*
X121657Y1224604D03*
X120999Y1228550D03*
X120499Y1264550D03*
X123938Y1267623D03*
X117149Y1267550D03*
X105999Y1311050D03*
X116499Y1335050D03*
X112499Y1329050D03*
X115499Y1364550D03*
X123500Y1360300D03*
X113999Y1380550D03*
X123500Y1372000D03*
X120499Y1470550D03*
X121499Y1511050D03*
X108000Y1517000D03*
X122600Y1565000D03*
X124999Y1616050D03*
Y1620050D03*
Y1629050D03*
Y1633050D03*
X119999Y1629050D03*
X120100Y1633100D03*
X122499Y1668550D03*
Y1672550D03*
X118999Y1670550D03*
X105749Y1712749D03*
X121499Y1708050D03*
X117499Y1745050D03*
X109249Y1725800D03*
X123499Y1747050D03*
X120299Y1796150D03*
X111499Y1877550D03*
Y1882550D03*
X122999Y1883050D03*
X115999Y1882550D03*
X116499Y1877550D03*
X122999Y1889050D03*
X124433Y1908510D03*
X124999Y1912550D03*
X119999Y1978550D03*
X119499Y1972550D03*
X108499Y1981750D03*
X115000Y1987000D03*
X129100Y55900D03*
X127499Y65050D03*
X141999Y65550D03*
X129999Y78050D03*
X127999Y99550D03*
X133999Y149050D03*
X142999Y141050D03*
X132999Y141550D03*
X144499Y149050D03*
X131799Y201950D03*
X142688Y218861D03*
X143110Y203861D03*
X133000Y240500D03*
X135399Y277050D03*
X130799Y300250D03*
X130099Y326150D03*
X134699Y356050D03*
X139399Y372350D03*
X127999Y425050D03*
Y421050D03*
Y429550D03*
X144999Y419550D03*
X137500Y444600D03*
X133499Y445050D03*
X128999Y445550D03*
X130000Y452000D03*
X135999Y472550D03*
X132999Y475550D03*
X135140Y478930D03*
X139200Y484300D03*
X134499Y488050D03*
X145649Y509550D03*
X136349Y509050D03*
X140499Y499050D03*
X136299D03*
X147300Y526700D03*
X135300Y524329D03*
X134899Y538200D03*
X135300Y549500D03*
X140000Y587700D03*
X140499Y600550D03*
X143999Y605550D03*
X140499Y626050D03*
X131099Y700450D03*
X139099Y707150D03*
X141234Y1029885D03*
X140864Y1044885D03*
X125999Y1087550D03*
X137900Y1103400D03*
X139100Y1097100D03*
X134500Y1108100D03*
X143200Y1116300D03*
X133200Y1132100D03*
X126999Y1143550D03*
X126400Y1138100D03*
X127800Y1163400D03*
X145900Y1163200D03*
X144399Y1171150D03*
X141499Y1185550D03*
X128400Y1188600D03*
X143899Y1196750D03*
X142499Y1205550D03*
X130999Y1198050D03*
X140911Y1201878D03*
X135400Y1205700D03*
X144149Y1230113D03*
Y1226113D03*
Y1222113D03*
X143900Y1262600D03*
X126499Y1264550D03*
X146300Y1277900D03*
X129699Y1315605D03*
X136200Y1342600D03*
X145999Y1353050D03*
X143199Y1412050D03*
X140799Y1435460D03*
X129100Y1564700D03*
X127200Y1569800D03*
X135400Y1624100D03*
X126562Y1670613D03*
X143500Y1702900D03*
X144999Y1711050D03*
X130499Y1730050D03*
X128000Y1735000D03*
X144499Y1729550D03*
X139500Y1730500D03*
X133000Y1734500D03*
X144499Y1745550D03*
X137999Y1747723D03*
X129999Y1747050D03*
X126599Y1789650D03*
X142144Y1801644D03*
X143490Y1855972D03*
X127499Y1889050D03*
X126999Y1882550D03*
X142499Y1905972D03*
X141499Y1895972D03*
X129999Y1908550D03*
X129433Y1912510D03*
X127499Y1978550D03*
X133499D03*
X132999Y1972550D03*
X126999D03*
X146899Y1961750D03*
X146000Y1987500D03*
X128500D03*
X157299Y5150D03*
X167499Y43550D03*
X156499Y66050D03*
X166999Y88050D03*
X166499Y83550D03*
Y79050D03*
X158499D03*
Y84050D03*
Y88550D03*
Y93550D03*
X166999Y92550D03*
X165499Y106050D03*
X166999Y97050D03*
Y155550D03*
X152999Y141050D03*
X167499Y149550D03*
X163499Y140050D03*
X160999Y149550D03*
X162177Y154550D03*
X155999Y181050D03*
X166800Y240800D03*
X158999Y259800D03*
X152808Y246341D03*
X157740Y273924D03*
X167299Y369350D03*
X150699Y411050D03*
X152499Y395950D03*
X161999Y426450D03*
X156959Y426292D03*
X149700Y471600D03*
X154100Y476500D03*
X164600Y476700D03*
X153499Y502550D03*
X148999D03*
X147590Y521500D03*
X151699Y524650D03*
X154099Y529236D03*
X155999Y535775D03*
X167200Y561000D03*
X156499Y548550D03*
X157749Y562000D03*
X162500Y623400D03*
X152400Y643300D03*
X152124Y651868D03*
X159054Y665400D03*
X161999Y768050D03*
X152499Y810550D03*
Y816050D03*
Y820550D03*
Y825050D03*
X166499Y841550D03*
X161999Y843550D03*
Y848050D03*
X156499Y846050D03*
X156999Y850050D03*
X156499Y870550D03*
Y876050D03*
X163999Y863050D03*
X159999D03*
X155999Y859050D03*
Y863050D03*
X158114Y883290D03*
X156499Y886950D03*
X159459Y896616D03*
X163499Y896550D03*
X155499Y891050D03*
Y896050D03*
X156969Y917050D03*
X157499Y904550D03*
Y909050D03*
X151999Y936550D03*
X152499Y931550D03*
X153299Y943750D03*
X160999Y942550D03*
X159186Y946117D03*
X158800Y967500D03*
X164999Y965050D03*
X156499Y985950D03*
X149499Y997650D03*
X162499Y1023550D03*
X158300Y1015000D03*
X163499Y1035050D03*
X159499Y1044579D03*
X151300Y1049300D03*
X165600Y1057428D03*
X168099Y1083550D03*
X164999Y1075550D03*
X159055Y1070400D03*
X167999Y1092850D03*
X167499Y1118550D03*
X167999Y1130550D03*
X163499Y1171650D03*
X151699Y1158550D03*
X151499Y1173050D03*
X150999Y1181150D03*
X148499Y1222113D03*
Y1226113D03*
X148486Y1230113D03*
X164999Y1305550D03*
X153500Y1326700D03*
X148000Y1346500D03*
X167499Y1389050D03*
X156999Y1397750D03*
X166799Y1409350D03*
X157915Y1420460D03*
X163499Y1433350D03*
X165499Y1453550D03*
X166799Y1487450D03*
X159054Y1476200D03*
X151499Y1673550D03*
X148100Y1683400D03*
X167499Y1714113D03*
X162499D03*
X158499Y1729050D03*
X165499Y1730613D03*
X167999Y1726613D03*
X163499D03*
X158027Y1778300D03*
X166999Y1774550D03*
X157500Y1797400D03*
X158000Y1825400D03*
X157999Y1840972D03*
X167200Y1868000D03*
X159054Y1855050D03*
X163599Y1892050D03*
X168299Y1879850D03*
X159054Y1881800D03*
X159173Y1935972D03*
X148499Y1977250D03*
X163500Y1987500D03*
X189499Y4550D03*
Y39150D03*
X183499Y45550D03*
X168499Y65550D03*
X188999Y88550D03*
X187024Y76235D03*
X169999Y103050D03*
X176499Y140050D03*
X171499Y153550D03*
X177899Y199250D03*
X185999Y250550D03*
X181299Y267350D03*
X187199Y359050D03*
X181599Y396250D03*
X168999Y413050D03*
X188499Y413550D03*
X176900Y424600D03*
X168900Y419100D03*
X179999Y442550D03*
X179649Y438550D03*
X183999D03*
Y442550D03*
Y447050D03*
X179999D03*
X168500Y472000D03*
X171300Y476700D03*
X168299Y503150D03*
X179000Y535500D03*
X187499Y531613D03*
Y536113D03*
X179499Y542550D03*
X172199Y557108D03*
X177999Y559300D03*
X188999Y541113D03*
Y549613D03*
Y545613D03*
X181999Y624050D03*
Y609550D03*
Y641550D03*
X182599Y688350D03*
X171999Y672450D03*
X170799Y689150D03*
X178899Y765250D03*
X172599Y774250D03*
X179999Y826050D03*
X179499Y820550D03*
X168499Y846713D03*
X173899Y846550D03*
X172099Y877450D03*
X171000Y927000D03*
X169299Y956350D03*
X178999Y961550D03*
X188499Y982050D03*
X171499Y965050D03*
Y998650D03*
X169299Y1067150D03*
X171599Y1139950D03*
X180400Y1202800D03*
X181700Y1219900D03*
X173499Y1217050D03*
X179800Y1244100D03*
X179500Y1262000D03*
X175823Y1297070D03*
X179999Y1301550D03*
Y1292550D03*
X175499D03*
X179999Y1296613D03*
X175499Y1302113D03*
X179999Y1306050D03*
X175499Y1306113D03*
X186000Y1382400D03*
X176999Y1367550D03*
X171499Y1370550D03*
X178200Y1393400D03*
X180599Y1424050D03*
X180000Y1439500D03*
X176599Y1447450D03*
X172299Y1465850D03*
X181500Y1479000D03*
X176299Y1500150D03*
X180299Y1626550D03*
X180000Y1619600D03*
X180299Y1634550D03*
X179733Y1630590D03*
X171999Y1658550D03*
X168999Y1651050D03*
X181900Y1675300D03*
X174800Y1670800D03*
X178900Y1700113D03*
X180701Y1716050D03*
X179701Y1724550D03*
X172499Y1714050D03*
X180000Y1731000D03*
X170499Y1731050D03*
X172499Y1726613D03*
X185999Y1746050D03*
X172999Y1775050D03*
X177314Y1772050D03*
X182299Y1801350D03*
X173899Y1813250D03*
X177599Y1866750D03*
X168499Y1855550D03*
X181099Y1885850D03*
X168699Y1957150D03*
X183999Y1968150D03*
X188199Y1978250D03*
X183000Y1987500D03*
X206999Y5050D03*
X197999Y39900D03*
X193999D03*
X208499Y45650D03*
X199999Y46050D03*
X194499Y44050D03*
X191999Y68050D03*
X191499Y74497D03*
X192499Y57550D03*
X208999Y92050D03*
X200999Y159050D03*
X191449Y152000D03*
X201561Y164541D03*
X206899Y171650D03*
X190199Y178650D03*
X191999Y221550D03*
X203499Y250550D03*
X201199Y266750D03*
X209199Y365050D03*
X209499Y412550D03*
X209999Y426150D03*
X207128Y440421D03*
X194999Y490050D03*
X190499Y487550D03*
X191199Y491550D03*
X205300Y508100D03*
X190499Y507513D03*
X199499Y545550D03*
X193499Y541113D03*
Y549613D03*
X193999Y545550D03*
Y558050D03*
X200999Y565050D03*
X200417Y569815D03*
X206499Y623550D03*
Y609050D03*
X207300Y639400D03*
X199199Y659150D03*
X190399Y689050D03*
X209500Y759000D03*
X208799Y766750D03*
X190699Y778350D03*
X197099Y795050D03*
X208299Y805350D03*
X202900Y811900D03*
X198199Y805950D03*
X204000Y823000D03*
Y817500D03*
X204496Y846111D03*
X204649Y838050D03*
X208999D03*
X209000Y846113D03*
X204649Y842113D03*
X208986D03*
X198499Y884113D03*
X203000Y918000D03*
X204699Y929450D03*
X194800Y925500D03*
X206699Y953050D03*
X203999Y943350D03*
X193549Y962550D03*
X199999Y971050D03*
X205999Y978250D03*
X206299Y990250D03*
X207299Y1008150D03*
X202100Y1028100D03*
X199499Y1093850D03*
X209900Y1093600D03*
X208199Y1145850D03*
X210199Y1173450D03*
X204199Y1163850D03*
X201600Y1205900D03*
X196499Y1215550D03*
Y1196550D03*
X196399Y1236650D03*
X196499Y1224550D03*
X195499Y1251050D03*
X202199Y1276850D03*
X195499Y1279050D03*
Y1270050D03*
X202899Y1291450D03*
X207699Y1337950D03*
X195500Y1352500D03*
X197999Y1359050D03*
X208049Y1385550D03*
X190499Y1367550D03*
X208999Y1366550D03*
X203199Y1393250D03*
X204699Y1418350D03*
X201000Y1408500D03*
X194200Y1457900D03*
X204999Y1472650D03*
X208999Y1491250D03*
X202399Y1500750D03*
X195700Y1619100D03*
X195600Y1623700D03*
X209200Y1624000D03*
X200900Y1657200D03*
X194999Y1640613D03*
X198300Y1649800D03*
X200600Y1663600D03*
X199900Y1670600D03*
X193499Y1674050D03*
X197600Y1694900D03*
X204400Y1688200D03*
X209901Y1691850D03*
X201801Y1701450D03*
X195001Y1708150D03*
X205200Y1708000D03*
X195500Y1717000D03*
X195000Y1725500D03*
X206900Y1726700D03*
X199699Y1761450D03*
X201499Y1784750D03*
X192999Y1771550D03*
X205199Y1801950D03*
X209999Y1825050D03*
X192100Y1813500D03*
X204399Y1855450D03*
X206999Y1867550D03*
X207199Y1892850D03*
X191599Y1891550D03*
X199599Y1879850D03*
X205499Y1968650D03*
X190199Y1957650D03*
X199600Y1974900D03*
X209699Y1978750D03*
X199000Y1987500D03*
X226499Y5050D03*
X225499Y52550D03*
Y46550D03*
Y63550D03*
Y58050D03*
X227022Y85278D03*
X229296Y81050D03*
X230811Y88226D03*
X224499Y92050D03*
X225499Y100050D03*
X229099Y161350D03*
X227999Y178050D03*
X218499Y183050D03*
X227499Y192050D03*
X227999Y187050D03*
Y182550D03*
X210999Y221550D03*
X217999Y250550D03*
X231400Y262800D03*
X221799Y276150D03*
X212578Y287448D03*
X212499Y296050D03*
Y307050D03*
X211999Y327550D03*
X223799Y365350D03*
X217599Y396450D03*
X218499Y474850D03*
X224299Y494650D03*
X215400Y516400D03*
X220499Y560050D03*
Y545550D03*
Y577550D03*
X224999Y613450D03*
X219999Y632550D03*
Y647050D03*
X226399Y677550D03*
X212999Y677350D03*
X218800Y668700D03*
X213299Y693800D03*
X212499Y701550D03*
X216999Y713050D03*
X212499Y736050D03*
X224099Y770250D03*
X214799Y774750D03*
X227199Y795050D03*
X217300Y816800D03*
X215999Y887550D03*
X220499D03*
X215499Y883550D03*
X225499Y941550D03*
X219499Y939613D03*
X214999D03*
X219499Y926613D03*
X214999D03*
X225299Y957650D03*
X213999Y958650D03*
X219499Y948613D03*
Y943813D03*
X214999Y944113D03*
Y948613D03*
X217499Y981050D03*
X216999Y967550D03*
X217499Y998550D03*
X217999Y1012050D03*
X215999Y1039550D03*
X216499Y1053050D03*
X227028Y1071148D03*
X223700Y1078500D03*
X212600Y1089961D03*
X210999Y1100550D03*
X214499Y1154250D03*
X223099Y1182750D03*
X212499Y1184550D03*
Y1212550D03*
X221599Y1237250D03*
X220999Y1224350D03*
X222299Y1251850D03*
X229899Y1250550D03*
X211499Y1258050D03*
Y1239050D03*
X216300Y1274800D03*
X211499Y1267050D03*
X219099Y1325950D03*
X226599Y1340250D03*
X213199Y1350050D03*
X227399Y1363050D03*
X216499Y1377550D03*
X217499Y1387450D03*
X230599Y1400250D03*
X217999Y1408850D03*
X227999Y1421550D03*
X226300Y1447800D03*
X230899Y1437350D03*
X212400Y1433700D03*
X223501Y1487433D03*
X213399Y1500300D03*
X211914Y1504015D03*
X212000Y1512500D03*
X217749Y1522300D03*
X212249Y1544800D03*
X212899Y1535550D03*
X230999D03*
X211999Y1568550D03*
X231499Y1575050D03*
X224499D03*
X217999Y1574550D03*
X211999D03*
X218000Y1614300D03*
X228999Y1637550D03*
X211999Y1653550D03*
X230600Y1670500D03*
X213000Y1672500D03*
X216601Y1684350D03*
X226800Y1684200D03*
X220100Y1691700D03*
X212000Y1701300D03*
X222700Y1710100D03*
X222499Y1743850D03*
X221499Y1760950D03*
X220799Y1791550D03*
X215299Y1813950D03*
X224800Y1867000D03*
X228999Y1856050D03*
X212399Y1885850D03*
X218499Y1897050D03*
X226999Y1941050D03*
X227499Y1971050D03*
X221300Y1971200D03*
X225199Y1978750D03*
X216999Y1987550D03*
X241999Y5050D03*
X247499Y37550D03*
X246999Y46550D03*
Y56050D03*
X247499Y65050D03*
X244499Y136550D03*
Y122050D03*
X244900Y149100D03*
X231999Y178050D03*
Y192050D03*
Y187050D03*
Y182550D03*
X232400Y220700D03*
X249800Y248800D03*
X235399Y263350D03*
X236800Y283500D03*
X237699Y426050D03*
X232999Y414550D03*
X252499Y415050D03*
X251499Y446050D03*
X231999Y445550D03*
X251999Y462050D03*
X232499Y461550D03*
X244199Y483350D03*
X242099Y511750D03*
X244999Y559550D03*
Y545050D03*
Y577050D03*
X244499Y632050D03*
X246500Y663300D03*
X245000Y647000D03*
X234200Y668300D03*
X239300Y669600D03*
X234500Y690652D03*
X244700Y743100D03*
X247000Y768500D03*
X245599Y773450D03*
X234299Y773750D03*
X247099Y795050D03*
X233799Y806350D03*
X245399Y823550D03*
X232300Y834200D03*
X244099Y857450D03*
X252399Y838250D03*
X245199Y878050D03*
X232399Y886550D03*
X252899Y886350D03*
X245399Y907450D03*
X237499Y900050D03*
X243899Y923650D03*
X242199Y938750D03*
X252499Y948850D03*
X244199Y973250D03*
X232299Y981950D03*
X233499Y966050D03*
X245899Y995250D03*
X233999Y997050D03*
Y1012550D03*
X232499Y1038050D03*
X244400Y1110200D03*
X249499Y1104150D03*
X233500Y1113100D03*
X250500Y1127500D03*
X250499Y1165550D03*
X232599Y1195750D03*
X251999Y1184550D03*
X242199Y1210050D03*
X242599Y1198350D03*
X247899Y1208650D03*
X234299Y1232650D03*
X250900Y1248500D03*
X242900Y1263000D03*
X232799Y1276150D03*
X241399Y1303250D03*
X239099Y1314150D03*
X252399Y1326350D03*
X245999Y1339050D03*
Y1358050D03*
X234300Y1375700D03*
X246499Y1370050D03*
X249800Y1388400D03*
X244999Y1412550D03*
X245499Y1424550D03*
X238899Y1453750D03*
X248000Y1482000D03*
X250199Y1473550D03*
X247500Y1499000D03*
X242700Y1499400D03*
X236999Y1535550D03*
X238300Y1575100D03*
X246200Y1617600D03*
X239400Y1624300D03*
X242999Y1658050D03*
X237400Y1663800D03*
X235499Y1697050D03*
X249199Y1743150D03*
X237999Y1730550D03*
X244999Y1755050D03*
X252199Y1793050D03*
X238699Y1801850D03*
X241199Y1867150D03*
X244700Y1878700D03*
X240100Y1875000D03*
X241255Y1896055D03*
X245249Y1896283D03*
X238999Y1970550D03*
X232999Y1971050D03*
X240900Y1979000D03*
X236500Y1987500D03*
X261499Y4550D03*
X253999Y48050D03*
X264999Y55350D03*
X261299Y75950D03*
X258699Y104550D03*
X265299Y96250D03*
X262299Y164050D03*
X262699Y208550D03*
X271999Y216050D03*
X265999Y245050D03*
X267498Y305114D03*
Y300114D03*
Y295114D03*
X265499Y322050D03*
X257000Y316214D03*
X267498Y310114D03*
X253999Y370050D03*
X258999Y396650D03*
X266699Y425050D03*
X269999Y415050D03*
X272499Y445050D03*
X266199Y472350D03*
X272999Y461050D03*
X257499Y498050D03*
Y512550D03*
Y530050D03*
X256499Y577050D03*
Y591550D03*
Y609050D03*
X269499Y616550D03*
X257199Y640050D03*
X269499Y631050D03*
Y648550D03*
X268499Y701550D03*
Y706550D03*
X258200Y722300D03*
X268499Y716550D03*
Y711550D03*
X268099Y795450D03*
X254699Y807650D03*
X264499Y829050D03*
X264999Y842550D03*
Y858450D03*
X265799Y901850D03*
X256199Y916250D03*
X254899Y929250D03*
X253499Y938050D03*
X269599Y923950D03*
X267199Y935350D03*
X264799Y946850D03*
X263299Y959350D03*
X272999Y981050D03*
Y965550D03*
X256499Y967050D03*
X262499Y995850D03*
X254499Y984550D03*
X258999Y1011550D03*
X269999Y1037050D03*
X253499Y1038550D03*
X269999Y1052550D03*
X253999Y1052050D03*
X272999Y1102850D03*
X255999Y1112150D03*
X262499Y1129150D03*
X260349Y1139200D03*
X272499Y1153050D03*
X268499D03*
X263999D03*
X259999Y1152992D03*
X271999Y1161550D03*
X267999D03*
X263499D03*
X259499D03*
X272999Y1214150D03*
X261199Y1227950D03*
X264800Y1261300D03*
X254899Y1289950D03*
X264799Y1313850D03*
X265299Y1339650D03*
X263699Y1359550D03*
X265499Y1376950D03*
X258999Y1396950D03*
X270599Y1408550D03*
X259299Y1438750D03*
X268499Y1453550D03*
X260999Y1503550D03*
X266999Y1512550D03*
X258800Y1534000D03*
X267349Y1518150D03*
Y1522550D03*
Y1527172D03*
X260500Y1540800D03*
X253399Y1586550D03*
X265700Y1635100D03*
X258700Y1645100D03*
X270999Y1660550D03*
X253999Y1676550D03*
X273499Y1694050D03*
X268499Y1706550D03*
X255699Y1722550D03*
X256499Y1710050D03*
X263499Y1734550D03*
X270599Y1748950D03*
X259499Y1760650D03*
X270599Y1801450D03*
X253899Y1813250D03*
X261499Y1825050D03*
X255999Y1855950D03*
X270299Y1867250D03*
X266999Y1915550D03*
Y1920050D03*
Y1924550D03*
Y1929050D03*
Y1933550D03*
X254500Y1987500D03*
X272000D03*
X278999Y5050D03*
X292999Y4550D03*
X294100Y28000D03*
X286499Y43613D03*
X289499Y39050D03*
X286603Y34928D03*
X289999Y72550D03*
X290999Y67550D03*
X287100Y86363D03*
X288499Y76550D03*
X289499Y80550D03*
X283599Y106250D03*
X274700Y131500D03*
X280999Y120050D03*
Y152050D03*
X290999Y216050D03*
X283499Y245050D03*
X279998Y304114D03*
Y299614D03*
Y295114D03*
Y308614D03*
X277799Y338599D03*
X293998Y361114D03*
Y356614D03*
Y352114D03*
X289998Y361114D03*
Y356614D03*
Y352114D03*
X276299Y376050D03*
X289399Y395750D03*
X284499Y415050D03*
X291599Y446150D03*
X286999Y462050D03*
X281999Y497550D03*
X292999Y483550D03*
X281999Y512050D03*
Y529550D03*
X277999Y545350D03*
X280999Y576550D03*
Y591050D03*
Y608550D03*
X293999Y616050D03*
Y630550D03*
Y648050D03*
X283999Y708550D03*
X280999Y701550D03*
Y705550D03*
Y717550D03*
X280433Y713590D03*
X294999Y767050D03*
X290999D03*
X294999Y762550D03*
Y758050D03*
X290999Y762550D03*
Y758050D03*
X287799Y794850D03*
X275299Y806350D03*
X288899Y820550D03*
X280999Y827550D03*
X283599Y857450D03*
X293899Y843850D03*
X280999Y843050D03*
Y870050D03*
X281499Y883550D03*
X274299Y912950D03*
X287299Y901050D03*
X281099Y943550D03*
X278799Y956150D03*
X290099Y948650D03*
X289399Y963350D03*
X277599Y975250D03*
X288099Y971250D03*
X285399Y982950D03*
X294699Y989550D03*
X287099Y1000150D03*
X274999Y996550D03*
X289699Y1021750D03*
X275099Y1024750D03*
X274999Y1012050D03*
X287099Y1035050D03*
X282999Y1099550D03*
X274900Y1115600D03*
X290699Y1122650D03*
X283499Y1113050D03*
X276299Y1134550D03*
X283299Y1144850D03*
X291399Y1174150D03*
X279799Y1191750D03*
X286599Y1203750D03*
X283799Y1249250D03*
X274299Y1276450D03*
X281099Y1302850D03*
X286799Y1326450D03*
X286499Y1364050D03*
Y1345050D03*
X278799Y1386250D03*
X285499Y1399550D03*
X278000Y1422000D03*
X285499Y1418550D03*
Y1427550D03*
X286600Y1449700D03*
X279499Y1510550D03*
X286700Y1516100D03*
X279499Y1521050D03*
Y1515050D03*
X279075Y1525957D03*
X278567Y1529925D03*
X293998Y1573614D03*
Y1569114D03*
X289998Y1573614D03*
Y1569114D03*
X293998Y1578114D03*
X289998D03*
X278499Y1621550D03*
X289000Y1641800D03*
X284300Y1676900D03*
X291099Y1707450D03*
X280499Y1718550D03*
X285499Y1742550D03*
X290699Y1760750D03*
X286599Y1791850D03*
X284299Y1811150D03*
X295299Y1870250D03*
X283999Y1856050D03*
X293999Y1933050D03*
X281999Y1918550D03*
Y1923550D03*
Y1928550D03*
X278999Y1950550D03*
X293999Y1971050D03*
Y1966550D03*
Y1962050D03*
X289499Y1961550D03*
Y1966550D03*
Y1971050D03*
X291499Y1987550D03*
X310499Y5050D03*
X304500Y44500D03*
X303300Y39500D03*
X308700Y39800D03*
X308800Y46400D03*
X306999Y55450D03*
X311299D03*
X315799Y55350D03*
X308499Y72550D03*
X303999Y74050D03*
X307999Y78550D03*
X307300Y113300D03*
X295500Y101900D03*
X306100Y126500D03*
X305999Y141050D03*
X307199Y205550D03*
X310499Y216550D03*
X297999Y245050D03*
X313199Y270350D03*
X313000Y313900D03*
X299000Y340500D03*
X312912Y345936D03*
X305998Y352114D03*
X314400Y370100D03*
X299899Y376650D03*
X310999Y396250D03*
X300899Y431850D03*
X303999Y415550D03*
X306100Y462000D03*
X312499Y484050D03*
X298599Y501250D03*
X309399Y513450D03*
X297599Y519350D03*
X307499Y555550D03*
Y541050D03*
X297499Y551050D03*
X296199Y568550D03*
X307499Y573050D03*
X302899Y607950D03*
X307499Y661550D03*
Y647050D03*
X297699Y681850D03*
X307499Y679050D03*
X308899Y705150D03*
X298399Y703450D03*
X296399Y716950D03*
X301099Y750750D03*
X306999Y758050D03*
X314499Y754550D03*
X311999Y773550D03*
X307999Y803150D03*
X307899Y794550D03*
X300199Y835250D03*
X304899Y856150D03*
X313499Y847850D03*
X315199Y869450D03*
X297499Y868550D03*
X302499Y899050D03*
X297499Y884050D03*
X302199Y914650D03*
X301499Y927050D03*
X315199Y925950D03*
X310699Y943550D03*
X299399Y965950D03*
X298099Y977250D03*
X307999Y970650D03*
X306699Y981250D03*
X304399Y997550D03*
X298399Y1008150D03*
X306399Y1020750D03*
X303699Y1038050D03*
X299999Y1052350D03*
X304699Y1057050D03*
X312299Y1093550D03*
X299499Y1098050D03*
Y1113550D03*
X316499Y1124550D03*
X307999Y1142050D03*
X304499Y1156650D03*
X313499Y1170150D03*
X300699Y1185150D03*
X315408Y1202663D03*
X311999Y1213850D03*
X300699Y1227350D03*
X310299Y1240050D03*
X304699Y1265850D03*
X312499Y1280350D03*
X295399Y1292950D03*
X300499Y1305350D03*
X311500Y1316300D03*
X297899Y1336150D03*
X298099Y1357250D03*
X311900Y1344900D03*
X301699Y1377950D03*
X312900Y1366900D03*
X301699Y1395750D03*
X313600Y1391300D03*
X303499Y1411250D03*
X312100Y1420700D03*
X300899Y1433350D03*
X313600Y1442700D03*
X304699Y1457550D03*
X312800Y1467400D03*
X296599Y1497150D03*
X312000Y1514600D03*
X304499Y1549550D03*
X305998Y1569114D03*
X307749Y1583300D03*
X307000Y1619600D03*
X302399Y1662950D03*
X299999Y1696050D03*
X303999Y1722050D03*
X297099Y1733850D03*
X303499Y1753550D03*
X303999Y1800850D03*
X297499Y1797050D03*
X315499Y1812250D03*
X298999Y1855950D03*
X313599Y1870250D03*
X308099Y1880550D03*
X313599Y1889250D03*
X314099Y1901250D03*
X305999Y1913050D03*
X306999Y1932550D03*
X302499D03*
X298499D03*
X302499Y1922050D03*
X306199Y1937010D03*
X296858Y1956228D03*
X305999Y1964050D03*
Y1969550D03*
X309999Y1976191D03*
X311500Y1987500D03*
X329999Y5050D03*
X328500Y71500D03*
X332200Y94200D03*
X321799Y173950D03*
X317499Y192950D03*
X331499Y193250D03*
X325499Y249450D03*
X337499Y282550D03*
X316999Y312576D03*
X321748Y343299D03*
X319102Y346300D03*
X322200Y369300D03*
X328799Y372350D03*
X336099Y417550D03*
X322099Y426850D03*
X324999Y414550D03*
X328599Y442250D03*
X327900Y463200D03*
X333499Y483050D03*
X329999Y510450D03*
X321999Y533150D03*
X331999Y555050D03*
Y540550D03*
X321999Y550550D03*
X321299Y565250D03*
X320799Y582050D03*
X331999Y572550D03*
X328599Y602450D03*
X328499Y635650D03*
X317999Y627850D03*
X331999Y661050D03*
Y646550D03*
Y678550D03*
X324599Y696150D03*
X330799Y712450D03*
X330249Y750050D03*
X318499Y752050D03*
X324499Y753050D03*
X327000Y772300D03*
X318999Y814350D03*
X325599Y823950D03*
X330299Y871850D03*
X323799Y859850D03*
X321099Y899650D03*
X323099Y885050D03*
X322099Y913650D03*
X331099Y923650D03*
X328099Y937250D03*
X323499Y956950D03*
X329799Y970650D03*
X333099Y983450D03*
X320999Y997250D03*
X331299Y1017150D03*
X321299Y1012450D03*
Y1024750D03*
X331599Y1028750D03*
X329599Y1040750D03*
X318299Y1038750D03*
X329599Y1057050D03*
X319999Y1066950D03*
X317699Y1054650D03*
X329299Y1098550D03*
X326599Y1112350D03*
X332999Y1123050D03*
X323999Y1153250D03*
X332999Y1138550D03*
X317999Y1137550D03*
X329799Y1182750D03*
X328999Y1200550D03*
X326649Y1227850D03*
Y1218850D03*
X327999Y1255050D03*
X333349Y1270500D03*
Y1288900D03*
Y1307000D03*
Y1332800D03*
Y1363500D03*
Y1393100D03*
Y1429500D03*
Y1481900D03*
X332500Y1519700D03*
X317499Y1549050D03*
X328600Y1566100D03*
X329100Y1582600D03*
X337199Y1636350D03*
X320299Y1642950D03*
X316799Y1657450D03*
X335767Y1662735D03*
X318499Y1675550D03*
X334399Y1691650D03*
X329999Y1716950D03*
X320999Y1706050D03*
X321999Y1733050D03*
X326301Y1766030D03*
X321499Y1772550D03*
X327299Y1791850D03*
X322299Y1802150D03*
X334999Y1797050D03*
X337499Y1855950D03*
X316999D03*
X336799Y1869950D03*
X326399Y1876250D03*
X336799Y1888950D03*
X326899Y1907250D03*
X326399Y1895250D03*
X336799Y1897950D03*
X335799Y1916450D03*
X335520Y1953650D03*
X323999Y1938550D03*
X326799Y1977050D03*
X331999Y1957550D03*
X329999Y1962550D03*
X330000Y1971600D03*
X329999Y1987550D03*
X345499Y5050D03*
X358059Y55550D03*
X356499Y113050D03*
X351999D03*
X347499D03*
X355999Y100550D03*
X350999D03*
X345999D03*
X354099Y175350D03*
X343399Y161350D03*
X343999Y190050D03*
X343799Y204550D03*
X355499Y219050D03*
X337999D03*
X355999Y242750D03*
X343499Y253550D03*
X347699Y269050D03*
X354999Y282550D03*
X347399Y301950D03*
X339399Y358050D03*
X357999Y359050D03*
X354099Y373050D03*
X338399Y395650D03*
X338899Y433850D03*
X354699Y426650D03*
X356399Y451750D03*
X351399Y470750D03*
X340799Y512050D03*
X358399Y498650D03*
X341399Y535850D03*
X357399Y521250D03*
Y530550D03*
X341399Y558950D03*
X357399Y543850D03*
X357999Y559450D03*
X340299Y586550D03*
X342199Y613050D03*
X342099Y646350D03*
X341899Y664950D03*
X342599Y678850D03*
X345399Y698950D03*
X357699Y707750D03*
X341399Y715050D03*
X355999Y752850D03*
X353999Y787750D03*
X347699Y773450D03*
X338099Y811650D03*
X338599Y821650D03*
Y840450D03*
X340099Y887350D03*
X338399Y901050D03*
X340099Y910350D03*
X340399Y931250D03*
X340099Y952850D03*
X339599Y1081550D03*
X344399Y1338150D03*
X343599Y1360050D03*
X344099Y1393750D03*
Y1421150D03*
Y1449550D03*
X343699Y1475950D03*
X351899Y1570850D03*
X344500Y1583600D03*
X350600Y1610900D03*
X349099Y1634550D03*
X351099Y1691150D03*
X352000Y1700400D03*
X343899Y1752650D03*
X357999Y1796050D03*
X355699Y1810750D03*
X351999Y1855450D03*
X348999Y1879050D03*
X349499Y1910050D03*
X348999Y1898050D03*
X347999Y1925550D03*
X348499Y1956550D03*
X347999Y1944550D03*
X347699Y1972250D03*
X345499Y1987550D03*
X364999Y4550D03*
X371999Y15550D03*
X376499D03*
X369999Y23550D03*
Y19050D03*
X370500Y42900D03*
X378700Y47300D03*
X376999Y65550D03*
Y70050D03*
X360999Y113050D03*
Y100550D03*
X363999Y136050D03*
Y121550D03*
Y153550D03*
X362999Y190050D03*
X369999Y219050D03*
X362499Y253550D03*
X369499Y282550D03*
X359399Y307250D03*
X368299Y386350D03*
X359399Y576050D03*
Y599650D03*
X360399Y615550D03*
X359699Y627550D03*
X358899Y657150D03*
X359399Y669450D03*
X359199Y690650D03*
X377499Y1182050D03*
Y1210050D03*
Y1201050D03*
X376499Y1236550D03*
Y1255550D03*
Y1264550D03*
X376599Y1293950D03*
X375599Y1323350D03*
X374499Y1347550D03*
Y1375550D03*
Y1366550D03*
X373499Y1402050D03*
Y1421050D03*
X376299Y1437650D03*
X373499Y1430050D03*
X373099Y1456550D03*
X374799Y1491250D03*
X374099Y1554550D03*
X376099Y1572850D03*
X375099Y1608250D03*
X377700Y1629000D03*
X374999Y1656750D03*
X377099Y1696350D03*
X359499Y1736850D03*
X376799Y1734050D03*
X376499Y1775550D03*
X369499Y1855950D03*
X359999Y1878550D03*
X369799Y1880050D03*
X359999Y1897550D03*
Y1906550D03*
X369999Y1901950D03*
X358999Y1925050D03*
X369199Y1919750D03*
X367299Y1956950D03*
X367999Y1940250D03*
X367299Y1972950D03*
X364999Y1987050D03*
X382499Y5050D03*
X395999Y5550D03*
X380999Y15550D03*
X382499Y20050D03*
X381499Y65550D03*
Y70050D03*
X389599Y90950D03*
X380599Y103550D03*
X381299Y136750D03*
X400499Y134050D03*
Y119550D03*
Y151550D03*
X389299Y161650D03*
X382499Y190550D03*
X387599Y220150D03*
X385999Y207250D03*
X381999Y254050D03*
X382999Y276650D03*
X386899Y299250D03*
X383299Y310250D03*
X386599Y348450D03*
X394899Y357750D03*
X380599Y381050D03*
X380099Y1709650D03*
X393499Y1759550D03*
X393999Y1784550D03*
X387899Y1802850D03*
X391499Y1855950D03*
X389499Y1885050D03*
Y1913050D03*
Y1904050D03*
X388499Y1932950D03*
Y1950550D03*
X385099Y1975950D03*
X399299Y1976750D03*
X388499Y1959550D03*
X382499Y1987550D03*
X413499Y6050D03*
X416999Y25050D03*
X417499Y46550D03*
X404499Y39300D03*
X402999Y46550D03*
X409999Y54050D03*
X416999Y63550D03*
X417499Y79050D03*
Y93550D03*
Y108050D03*
Y125550D03*
X416999Y145050D03*
Y164050D03*
X417999Y185050D03*
X412999Y275550D03*
Y307550D03*
Y290050D03*
X410379Y328650D03*
X422199Y363350D03*
X420199Y391350D03*
X415099Y422550D03*
X410799Y431150D03*
X419599Y458550D03*
X415999Y518550D03*
X420199Y638550D03*
X418799Y877050D03*
Y896050D03*
X409499Y1102550D03*
X419999Y1115550D03*
X415499Y1161550D03*
X416099Y1183550D03*
X415499Y1176050D03*
X419499Y1234050D03*
Y1219550D03*
X420099Y1241550D03*
X416699Y1342650D03*
X416199Y1367550D03*
X414799Y1532350D03*
X418299Y1561250D03*
X415999Y1603250D03*
X416199Y1625250D03*
X414799Y1653750D03*
X414399Y1678350D03*
X414499Y1707250D03*
X410757Y1772872D03*
X417799Y1790850D03*
X414499Y1810450D03*
X406999Y1855950D03*
X421399Y1888050D03*
X406499Y1893050D03*
Y1874050D03*
X421399Y1907050D03*
X406999Y1905050D03*
X420399Y1934550D03*
X421399Y1916050D03*
X405499Y1920550D03*
X420399Y1953550D03*
X405999Y1951550D03*
X405499Y1939550D03*
X420399Y1962550D03*
X420799Y1977250D03*
X420500Y1987000D03*
X403500D03*
X432999Y6050D03*
X436499Y31350D03*
Y50350D03*
X437499Y71350D03*
X441799Y102450D03*
Y121450D03*
X442799Y142450D03*
X430499Y217050D03*
X423799Y259750D03*
X437499Y275050D03*
Y307050D03*
Y289550D03*
X422499Y348150D03*
X438999Y381550D03*
X426599Y415350D03*
X443199Y440850D03*
X440099Y459250D03*
X431099Y479350D03*
X435499Y519050D03*
X430099Y551450D03*
X427999Y580050D03*
Y565550D03*
Y597550D03*
X427499Y624550D03*
X437299Y744650D03*
X435299Y763150D03*
X424999Y766550D03*
X435299Y777650D03*
X422999Y785050D03*
X434799Y814650D03*
X435299Y795150D03*
X422999Y799550D03*
X434799Y833650D03*
X422999Y817050D03*
X422499Y855550D03*
Y836550D03*
X442599Y905650D03*
Y924650D03*
X423299Y994050D03*
Y1013050D03*
X424299Y1034050D03*
X432599Y1064550D03*
X433599Y1085550D03*
X428999Y1102550D03*
X439499Y1115550D03*
X436999Y1128050D03*
X437599Y1150050D03*
X436999Y1142550D03*
X443199Y1224250D03*
Y1238750D03*
X424999Y1278550D03*
Y1259550D03*
X425499Y1290550D03*
X428499Y1325350D03*
X434499Y1360250D03*
X422299Y1394950D03*
X441499Y1399550D03*
X426799Y1416050D03*
X441499Y1414050D03*
X423299Y1430350D03*
X425799Y1447950D03*
X441499Y1431550D03*
X427099Y1469150D03*
X424299Y1541350D03*
X439599Y1552150D03*
X434500Y1579500D03*
X432499Y1617550D03*
X431999Y1605550D03*
X425499Y1635050D03*
X432400Y1680100D03*
X427499Y1662050D03*
X428600Y1691200D03*
X435300Y1715300D03*
X429499Y1748050D03*
X441499Y1758050D03*
X436799Y1772550D03*
X422999Y1778550D03*
X426499Y1855450D03*
X434299Y1876050D03*
Y1904050D03*
Y1895050D03*
X433299Y1922550D03*
Y1950550D03*
Y1941550D03*
X436299Y1977250D03*
X438999Y1987550D03*
X448499Y6050D03*
X445799Y165650D03*
Y184650D03*
X446799Y205650D03*
X449999Y217050D03*
X448999Y255550D03*
X444499Y283050D03*
X463999Y283550D03*
X443499Y354050D03*
X464499Y353050D03*
X458499Y382050D03*
X450300Y404200D03*
X453999Y417550D03*
X454999Y438550D03*
X454499Y472550D03*
Y458050D03*
Y490050D03*
X456499Y518050D03*
X453999Y509550D03*
X452499Y579550D03*
Y565050D03*
Y597050D03*
X463999Y659550D03*
X450399Y672750D03*
X444799Y687350D03*
X463999Y674050D03*
Y691550D03*
X451099Y711650D03*
X452099Y762450D03*
Y781450D03*
X453399Y807950D03*
Y826950D03*
X462999Y865050D03*
Y884050D03*
X464499Y896050D03*
X462499Y914550D03*
Y929050D03*
X443599Y945650D03*
X462499Y946550D03*
X461999Y966050D03*
Y985050D03*
X462499Y1043850D03*
Y1062850D03*
X463499Y1083850D03*
X463999Y1102050D03*
X444499Y1102550D03*
X454999Y1115550D03*
X453499Y1140550D03*
X454499Y1161550D03*
X443799Y1246250D03*
Y1274250D03*
Y1265250D03*
X448099Y1341250D03*
X444899Y1377950D03*
X464199Y1401450D03*
X459999Y1424050D03*
X456399Y1445950D03*
X459699Y1468050D03*
X445099Y1464250D03*
X444299Y1532650D03*
X461399Y1541650D03*
X452199Y1550650D03*
X449199Y1579050D03*
X443799Y1612250D03*
X460199Y1632850D03*
X449599Y1656950D03*
X448399Y1699450D03*
X447699Y1682850D03*
X458499Y1742050D03*
X463999Y1772050D03*
X445499Y1792550D03*
X448099Y1809450D03*
X459999Y1862050D03*
X443999Y1855950D03*
X460299Y1892350D03*
X446999Y1880050D03*
X460299Y1911350D03*
X446999Y1908050D03*
Y1899050D03*
X460299Y1920350D03*
X445999Y1926550D03*
X459299Y1938850D03*
X445999Y1954550D03*
Y1945550D03*
X459299Y1966850D03*
Y1957850D03*
X455799Y1976750D03*
X456500Y1987500D03*
X467999Y5550D03*
X485499Y6050D03*
X465799Y24750D03*
Y43750D03*
X466799Y64750D03*
X470399Y84550D03*
Y103550D03*
X471399Y124550D03*
X473099Y141050D03*
X483599Y179350D03*
X473099Y160050D03*
X474099Y181050D03*
X472999Y214550D03*
X469999Y254550D03*
X481499Y283550D03*
X466399Y304950D03*
X479299Y297250D03*
X483499Y353050D03*
X485000Y373200D03*
X484900Y394700D03*
X468799Y414250D03*
X472499Y458050D03*
X471499Y493950D03*
X485299Y534550D03*
X479999Y581050D03*
Y566550D03*
Y598550D03*
X472999Y736550D03*
X467699Y772750D03*
X468699Y788350D03*
X479599Y847550D03*
X475699Y880450D03*
X483499Y1064850D03*
X478599Y1075450D03*
X484499Y1085850D03*
X481499Y1102550D03*
X474499Y1115050D03*
X473099Y1144550D03*
X474099Y1165550D03*
X465499Y1265550D03*
Y1284550D03*
Y1293550D03*
X468999Y1323950D03*
X473999Y1342450D03*
X468699Y1362850D03*
X485599Y1367550D03*
X466699Y1378150D03*
X481499Y1402550D03*
Y1417050D03*
X482599Y1449950D03*
X478299Y1464850D03*
X466999Y1530650D03*
X474299Y1544750D03*
X472299Y1572050D03*
X484200Y1579900D03*
X465999Y1603450D03*
X472499Y1611550D03*
X484999Y1636550D03*
X472499Y1620550D03*
X483599Y1662550D03*
X467999Y1668050D03*
X485599Y1694850D03*
X467999Y1687050D03*
Y1696050D03*
X468499Y1712550D03*
X480999Y1756050D03*
X484999Y1779050D03*
X472699Y1792150D03*
X481299Y1811150D03*
X480499Y1855450D03*
X464999D03*
X476199Y1877450D03*
Y1905450D03*
Y1896450D03*
X475199Y1923950D03*
Y1951950D03*
Y1942950D03*
X473299Y1977250D03*
X476000Y1987000D03*
X498999Y6050D03*
X499999Y25550D03*
X500499Y47050D03*
X499999Y64050D03*
X500499Y79550D03*
Y94050D03*
Y108550D03*
Y126050D03*
X499999Y145550D03*
Y164550D03*
X504199Y193250D03*
X502899Y217150D03*
X488999Y254550D03*
X495999Y283550D03*
X502999Y353550D03*
X490999Y412550D03*
X503699Y419250D03*
X490999Y427050D03*
Y444550D03*
X498399Y470050D03*
X490499Y464050D03*
Y483050D03*
X491499Y504050D03*
X504499Y580550D03*
Y566050D03*
Y598050D03*
X503379Y621150D03*
X488499Y659050D03*
Y673550D03*
Y691050D03*
X506599Y711650D03*
X487299Y716950D03*
X490299Y734550D03*
X489599Y752450D03*
X495999Y795050D03*
X493999Y813550D03*
Y828050D03*
Y845550D03*
X493499Y865050D03*
Y884050D03*
X485799Y920050D03*
Y901050D03*
X486799Y941050D03*
X493099Y996350D03*
X494099Y1017350D03*
X501499Y1102550D03*
X491999Y1115550D03*
X504399Y1132250D03*
X505399Y1153250D03*
X486499Y1210550D03*
Y1196050D03*
X506599Y1202350D03*
Y1216850D03*
X487099Y1218050D03*
X498299Y1323350D03*
X499199Y1350550D03*
X498899Y1386450D03*
Y1408350D03*
X500899Y1434350D03*
X505899Y1466250D03*
X496379Y1492150D03*
X488299Y1531050D03*
X499699Y1538950D03*
X502199Y1566250D03*
X487099Y1606250D03*
X501399Y1634550D03*
X502899Y1709650D03*
X496999Y1799550D03*
X499999Y1854950D03*
X505799Y1893050D03*
X492999Y1878050D03*
X505799Y1912050D03*
X493499Y1909050D03*
X492999Y1897050D03*
X505799Y1921050D03*
X491999Y1924550D03*
X504799Y1939550D03*
X492499Y1955550D03*
X491999Y1943550D03*
X504799Y1967550D03*
Y1958550D03*
X493799Y1977250D03*
X492500Y1987500D03*
X516499Y6550D03*
X522899Y45350D03*
Y64350D03*
X523899Y85350D03*
X520299Y122450D03*
Y141450D03*
X521299Y162450D03*
X508499Y255050D03*
X525999D03*
X515499Y284050D03*
X516899Y306950D03*
X520499Y353550D03*
X509999Y382550D03*
X518999Y416550D03*
X511299Y449150D03*
X519499Y471550D03*
Y489050D03*
X508699Y498950D03*
X518999Y508550D03*
X514499Y546050D03*
X509999Y640550D03*
Y655050D03*
Y672550D03*
X527499Y747150D03*
X525499Y772450D03*
X511199Y782050D03*
X512899Y823550D03*
X526499Y851150D03*
X512899Y842550D03*
X510899Y868150D03*
X522499Y876050D03*
X521999Y895550D03*
X506899Y919950D03*
Y900950D03*
X521999Y914550D03*
X516499Y957050D03*
X514499Y975550D03*
Y990050D03*
Y1007550D03*
X513999Y1046050D03*
Y1027050D03*
X518999Y1103050D03*
X511999Y1115550D03*
X527499Y1181550D03*
X527999Y1212550D03*
X527499Y1200550D03*
X507199Y1224350D03*
X525999Y1231050D03*
X507199Y1252350D03*
Y1243350D03*
X525999Y1245550D03*
X527499Y1278150D03*
X525999Y1263050D03*
X518499Y1346950D03*
X523499Y1360050D03*
X508599Y1370550D03*
X523499Y1379050D03*
X523999Y1391050D03*
X516999Y1418050D03*
Y1437050D03*
X517499Y1449050D03*
X518899Y1530150D03*
X510100Y1579800D03*
X508199Y1610450D03*
X518499Y1643950D03*
X509199Y1660550D03*
X507399Y1683350D03*
X522300Y1739200D03*
X508200Y1758200D03*
X515499Y1779050D03*
X526499Y1801150D03*
X514199Y1815750D03*
X517499Y1855450D03*
X519399Y1876750D03*
Y1904750D03*
Y1895750D03*
X518399Y1923250D03*
Y1951250D03*
Y1942250D03*
X509299Y1977250D03*
X511999Y1987550D03*
X535999Y6550D03*
X541499Y25050D03*
X541999Y46550D03*
X541499Y63550D03*
X541999Y79050D03*
Y93550D03*
Y108050D03*
Y125550D03*
X541499Y145050D03*
Y164050D03*
X528799Y199950D03*
X542499Y185050D03*
X533499Y217550D03*
X540499Y255050D03*
X536499Y283050D03*
X544799Y293950D03*
X540099Y306550D03*
X548100Y362200D03*
X530999Y381550D03*
X538799Y445050D03*
X539799Y466050D03*
X539299Y485550D03*
X535499Y545050D03*
X538999Y562050D03*
X534499Y640050D03*
Y654550D03*
Y672050D03*
X547999Y728550D03*
Y743050D03*
Y760550D03*
X547499Y780050D03*
X534499Y805950D03*
X547499Y799050D03*
X541399Y854450D03*
Y873450D03*
X539299Y935850D03*
X540299Y956850D03*
X540899Y981450D03*
Y1000450D03*
X541899Y1021450D03*
X534599Y1048550D03*
X535599Y1069550D03*
X538499Y1103050D03*
X548999Y1116050D03*
X529499D03*
X546499Y1180750D03*
Y1195250D03*
X547099Y1202750D03*
Y1230750D03*
Y1221750D03*
X548799Y1252850D03*
Y1267350D03*
X530499Y1297050D03*
X545099Y1355250D03*
X540399Y1382150D03*
X538799Y1409750D03*
X536799Y1436350D03*
X528499Y1460250D03*
X546099Y1467550D03*
X538999Y1528350D03*
X529799Y1555050D03*
X533800Y1575500D03*
X529499Y1616550D03*
X528999Y1604550D03*
X532499Y1635550D03*
X532599Y1655650D03*
X532499Y1669550D03*
Y1688550D03*
X532999Y1700550D03*
X538299Y1721050D03*
X532499Y1763050D03*
X539499Y1788150D03*
X544300Y1784638D03*
X531799Y1818450D03*
X538999Y1855950D03*
X547999Y1892350D03*
X533499Y1884050D03*
X547999Y1911350D03*
X533499Y1912050D03*
Y1903050D03*
X547999Y1920350D03*
X532499Y1930550D03*
X546999Y1938850D03*
X532499Y1949550D03*
X546999Y1966850D03*
Y1957850D03*
X546299Y1977250D03*
X528799Y1976750D03*
X532499Y1958550D03*
X531500Y1987500D03*
X551499Y6550D03*
X568099Y72550D03*
Y91550D03*
X569099Y112550D03*
X562799Y127750D03*
Y146750D03*
X563799Y167750D03*
X565999Y199950D03*
X568499Y217550D03*
X552999D03*
X557999Y322550D03*
Y326550D03*
X558099Y335050D03*
X557933Y331010D03*
X555999Y412550D03*
X556499Y467550D03*
Y485050D03*
X555999Y504550D03*
X558499Y562550D03*
Y616050D03*
X554304Y615840D03*
X554499Y624550D03*
X558699D03*
X554499Y620050D03*
X558709Y620245D03*
X565699Y710650D03*
X549999Y710050D03*
X562999Y898050D03*
X560999Y916550D03*
Y931050D03*
Y948550D03*
X560499Y968050D03*
Y987050D03*
X560999Y999050D03*
X558999Y1017550D03*
Y1032050D03*
X558499Y1069050D03*
X558999Y1049550D03*
X558499Y1088050D03*
X568499Y1101550D03*
X553999Y1103050D03*
X564499Y1116050D03*
X567999Y1187550D03*
Y1215550D03*
Y1206550D03*
X565999Y1234050D03*
Y1248550D03*
X566399Y1273850D03*
X549399Y1274850D03*
X561099Y1301050D03*
X549399Y1293850D03*
Y1302850D03*
X555699Y1322950D03*
X559099Y1343250D03*
X557499Y1424050D03*
Y1443050D03*
Y1452050D03*
X563499Y1486550D03*
Y1492050D03*
Y1497550D03*
Y1503550D03*
X567999Y1549950D03*
X552199Y1576650D03*
X552099Y1601950D03*
X569499Y1610550D03*
X553399Y1624550D03*
X569499Y1619550D03*
X554199Y1651950D03*
X555199Y1674750D03*
X555399Y1689350D03*
X555899Y1706750D03*
X556199Y1727050D03*
X560399Y1792550D03*
X555500Y1802700D03*
X554499Y1855950D03*
X562599Y1893450D03*
Y1874450D03*
Y1902450D03*
X561599Y1920950D03*
Y1948950D03*
Y1939950D03*
X570299Y1976250D03*
X568999Y1987050D03*
X553499D03*
X570999Y6050D03*
X588499Y6550D03*
X587999Y25050D03*
X588499Y46550D03*
X587999Y63550D03*
X588499Y125550D03*
X587999Y145050D03*
Y164050D03*
X588999Y185050D03*
X587999Y217050D03*
X572999Y255050D03*
Y269550D03*
Y287050D03*
X572499Y306550D03*
Y325550D03*
X573499Y346550D03*
X579899Y375750D03*
X577399Y420050D03*
X578399Y441050D03*
X577899Y460550D03*
X576099Y481850D03*
X577099Y502850D03*
X576599Y522350D03*
X579499Y561550D03*
X573499Y658550D03*
Y673050D03*
Y690550D03*
X586299Y711250D03*
X577999Y732050D03*
X575999Y750550D03*
Y765050D03*
Y782550D03*
X575499Y802050D03*
Y821050D03*
X576499Y842050D03*
X578299Y895650D03*
Y914650D03*
X583299Y961450D03*
X570899Y946850D03*
X583299Y980450D03*
X570899Y965850D03*
X571899Y986850D03*
X573499Y1036550D03*
Y1055550D03*
X574499Y1076550D03*
X588499Y1101550D03*
X578999Y1114550D03*
X582699Y1233250D03*
X583299Y1255250D03*
X582699Y1247750D03*
X583299Y1274250D03*
X579299Y1300750D03*
X583299Y1283250D03*
X581999Y1370150D03*
X580999Y1412750D03*
X575699Y1438950D03*
X582999Y1461250D03*
X590599Y1483450D03*
X582299Y1534150D03*
X588099Y1572050D03*
X573400Y1577600D03*
X588000Y1604000D03*
X590799Y1627850D03*
X580799Y1646150D03*
X572999Y1675550D03*
X590599Y1694450D03*
X572999Y1694550D03*
Y1703550D03*
X580299Y1722550D03*
X582599Y1740050D03*
X573999Y1855450D03*
X588899Y1882350D03*
X575999Y1888050D03*
X588899Y1910350D03*
Y1901350D03*
X575999Y1907050D03*
X587899Y1928850D03*
X576499Y1919050D03*
X574999Y1934550D03*
X587899Y1956850D03*
Y1947850D03*
X574999Y1953550D03*
X585799Y1976250D03*
X575499Y1965550D03*
X588499Y1986550D03*
X608499Y6550D03*
X603999Y35350D03*
Y54350D03*
X599499Y79550D03*
X604999Y75350D03*
X603999Y133750D03*
Y152750D03*
X604999Y173750D03*
X605499Y217550D03*
X599299Y344650D03*
X600299Y365650D03*
X599799Y385150D03*
X607399Y380250D03*
X592999Y407550D03*
Y422050D03*
Y439550D03*
X592499Y459050D03*
Y478050D03*
X593499Y499050D03*
X606499Y584550D03*
X595999Y624050D03*
Y609550D03*
Y641550D03*
X605299Y661750D03*
X609499Y708050D03*
X597999Y690050D03*
X607499Y726550D03*
Y741050D03*
Y758550D03*
X606999Y778050D03*
Y797050D03*
X603499Y904050D03*
X601499Y922550D03*
Y937050D03*
Y954550D03*
X600999Y1002050D03*
X611399Y1026650D03*
X598999Y1020550D03*
X611399Y1045650D03*
X598999Y1035050D03*
X612399Y1066650D03*
X598999Y1052550D03*
X598499Y1072050D03*
X605999Y1102050D03*
X598499Y1091050D03*
X598999Y1114550D03*
X603899Y1157850D03*
X597599Y1196050D03*
X596599Y1215050D03*
X600899Y1238650D03*
X598499Y1280550D03*
Y1261550D03*
X598999Y1292550D03*
X608899Y1305050D03*
X605599Y1326350D03*
X606199Y1338250D03*
X599499Y1351550D03*
X599999Y1382550D03*
X599499Y1370550D03*
X604899Y1407750D03*
X601299Y1447650D03*
X610899Y1496750D03*
X599799Y1544650D03*
X611900Y1577900D03*
X612499Y1615550D03*
X611999Y1603550D03*
X600599Y1645450D03*
X593399Y1668850D03*
X609499Y1675050D03*
Y1692050D03*
X607599Y1716450D03*
X606999Y1745550D03*
X593299Y1760950D03*
X608599Y1810750D03*
X595199Y1820910D03*
X611999Y1855950D03*
X591499D03*
X602799Y1887350D03*
Y1906350D03*
X601799Y1933850D03*
X602799Y1915350D03*
X601799Y1952850D03*
Y1961850D03*
X605299Y1975750D03*
X605999Y1987050D03*
X625999Y7050D03*
X624499Y23050D03*
X624999Y44550D03*
X624499Y61550D03*
X624999Y123550D03*
X624499Y143050D03*
Y162050D03*
X625499Y183050D03*
X623899Y202550D03*
X625499Y217550D03*
X627999Y262550D03*
Y248050D03*
Y280050D03*
X627499Y299550D03*
X628200Y320000D03*
X628499Y339550D03*
X632399Y358750D03*
X620999Y411550D03*
X621999Y432550D03*
X621499Y452050D03*
Y466550D03*
Y484050D03*
X613700Y504600D03*
X625999Y585050D03*
X620499Y623550D03*
Y609050D03*
X631999Y639650D03*
X622999Y672050D03*
Y689550D03*
X629099Y714050D03*
X633499Y750150D03*
X621499Y767150D03*
X621999Y835050D03*
X612999Y854550D03*
X629499Y853050D03*
Y868550D03*
X613499Y868050D03*
X616699Y948250D03*
Y967250D03*
X617699Y988250D03*
X631999Y1001550D03*
X629999Y1020050D03*
Y1034550D03*
Y1052050D03*
X629499Y1071550D03*
Y1090550D03*
X616499Y1115050D03*
X627699Y1143550D03*
X628699Y1164550D03*
X626199Y1183450D03*
X630499Y1243950D03*
X617599Y1246250D03*
X618199Y1268250D03*
X617599Y1260750D03*
X618199Y1296250D03*
Y1287250D03*
X631799Y1322650D03*
X617899Y1360850D03*
X632499Y1347950D03*
X625499Y1383450D03*
X627499Y1406050D03*
X626799Y1432350D03*
X625199Y1489150D03*
X617699Y1530350D03*
X623499Y1564050D03*
X633499Y1615450D03*
X628499Y1636650D03*
X627299Y1659550D03*
X625499Y1725050D03*
X619499Y1803150D03*
X627273Y1793905D03*
X626999Y1800050D03*
X632799Y1820450D03*
X627494Y1829068D03*
X627499Y1855950D03*
X630699Y1872750D03*
Y1891750D03*
Y1900750D03*
X616499Y1913050D03*
Y1894050D03*
X629699Y1919250D03*
X616499Y1922050D03*
X629699Y1947250D03*
Y1938250D03*
X615499Y1940550D03*
X622799Y1976250D03*
X615499Y1959550D03*
Y1968550D03*
X626999Y1987050D03*
X645499Y7050D03*
X651799Y40650D03*
Y59650D03*
X652799Y80650D03*
X649899Y138350D03*
Y157350D03*
X650899Y178350D03*
X642999Y218050D03*
X653999Y286550D03*
X635399Y376250D03*
X643599Y395950D03*
X644599Y416950D03*
X644099Y450950D03*
Y436450D03*
X642499Y525750D03*
X643499Y546750D03*
X642999Y566250D03*
X646999Y584550D03*
X640599Y604650D03*
X645099Y639150D03*
X647499Y657050D03*
Y671550D03*
X648999Y702350D03*
X647499Y689050D03*
X651999Y718350D03*
X647399Y742150D03*
X653099Y803350D03*
X645799Y816650D03*
X641599Y843250D03*
Y862250D03*
X642599Y883250D03*
X639499Y952150D03*
Y971150D03*
X633999Y1103050D03*
X641799Y1137650D03*
X650299Y1153150D03*
X651299Y1174150D03*
X650599Y1182050D03*
X651599Y1203050D03*
X638999Y1267550D03*
Y1286550D03*
Y1295550D03*
X654499Y1354050D03*
Y1373050D03*
X652999Y1403550D03*
Y1418050D03*
Y1435550D03*
X636799Y1461250D03*
X643099Y1541350D03*
X652399Y1575850D03*
X639200Y1576200D03*
X635500Y1603900D03*
X652499Y1618550D03*
Y1609550D03*
X649399Y1644950D03*
X635099Y1691150D03*
X642499Y1709050D03*
X650399Y1771250D03*
X642400Y1800100D03*
X634999Y1803050D03*
X633931Y1795465D03*
X633837Y1807384D03*
X640999Y1815550D03*
X644049Y1810834D03*
X645099Y1877550D03*
X645399Y1906150D03*
X646799Y1926450D03*
X644999Y1934050D03*
Y1953050D03*
X643799Y1976250D03*
X645499Y1965050D03*
X642499Y1987050D03*
X660999Y7050D03*
X674999Y20550D03*
X675499Y42050D03*
Y74550D03*
X674999Y59050D03*
X675499Y89050D03*
Y103550D03*
Y121050D03*
X674999Y140550D03*
Y159550D03*
X675999Y180550D03*
X662499Y218050D03*
X656499Y307050D03*
Y324550D03*
X655999Y344050D03*
X659899Y363250D03*
X666999Y476550D03*
Y491050D03*
Y508550D03*
X666499Y528050D03*
Y547050D03*
X667499Y568050D03*
X674999Y601550D03*
X665999Y623550D03*
X673999Y645150D03*
X665499Y766550D03*
X664999Y786050D03*
Y805050D03*
X665999Y826050D03*
X663999Y844550D03*
Y876550D03*
Y859050D03*
X663499Y896050D03*
Y915050D03*
X664499Y936050D03*
X658999Y959050D03*
X656999Y977550D03*
Y992050D03*
X673999Y1017550D03*
X656999Y1009550D03*
X673999Y1036550D03*
X656499Y1029050D03*
X674699Y1061450D03*
X656499Y1048050D03*
X674699Y1080450D03*
X669499Y1116550D03*
X674999Y1134950D03*
X667199Y1152850D03*
X668199Y1173850D03*
X670199Y1192750D03*
X671199Y1213750D03*
X668699Y1227650D03*
X657099Y1272850D03*
X657799Y1288450D03*
X672999Y1303450D03*
X656399Y1307050D03*
X671999Y1324950D03*
X665699Y1337250D03*
X654999Y1385050D03*
X659699Y1445950D03*
X665699Y1462250D03*
X656099Y1479550D03*
X672399Y1508750D03*
X673699Y1535350D03*
X662099Y1549650D03*
X670699Y1603150D03*
X671399Y1625350D03*
X657099Y1668850D03*
X674999Y1676550D03*
X656499Y1697050D03*
X675499Y1738050D03*
X665399Y1752350D03*
X675499Y1757050D03*
X675999Y1769050D03*
X659159Y1792278D03*
X659949Y1803670D03*
X664549Y1797436D03*
X659549Y1815384D03*
X661549Y1822634D03*
X667999Y1870950D03*
X669399Y1855350D03*
X674899Y1892350D03*
X661299Y1890050D03*
X674899Y1911350D03*
X661299Y1909050D03*
X674899Y1920350D03*
X661299Y1918050D03*
X673899Y1938850D03*
X660299Y1936550D03*
Y1955550D03*
X673899Y1966850D03*
Y1957850D03*
X660299Y1964550D03*
X659299Y1976250D03*
X661999Y1986550D03*
X680499Y6550D03*
X694999Y62650D03*
Y81650D03*
X695999Y102650D03*
X688999Y196550D03*
X677999Y218050D03*
X683499Y263050D03*
Y248550D03*
X680500Y280700D03*
X682999Y300050D03*
Y319050D03*
X683999Y340050D03*
X694999Y480550D03*
X695999Y501550D03*
X695499Y521050D03*
X691399Y548350D03*
X692399Y569350D03*
X691899Y588850D03*
X690499Y623050D03*
X693999Y648150D03*
X678499Y671050D03*
X679299Y703050D03*
X678499Y688550D03*
X681899Y713650D03*
X696299Y741850D03*
X694599Y763450D03*
X685999Y780050D03*
X687099Y804650D03*
Y823650D03*
X688099Y844650D03*
X687099Y896350D03*
Y915350D03*
X688099Y936350D03*
X678299Y978350D03*
Y997350D03*
X694999Y993050D03*
X692999Y1011550D03*
Y1026050D03*
Y1043550D03*
X692499Y1063050D03*
Y1082050D03*
X689999Y1105550D03*
X695999Y1203050D03*
Y1235050D03*
Y1217550D03*
X684299Y1249550D03*
X690999Y1295550D03*
X695999Y1323350D03*
X677999Y1347550D03*
X694999Y1360050D03*
X680299Y1365850D03*
X694999Y1379050D03*
X681299Y1393150D03*
X692999Y1406550D03*
X694999Y1388050D03*
X678299Y1425050D03*
X692999Y1421050D03*
X686999Y1468850D03*
X685299Y1551950D03*
X681299Y1579150D03*
X693599Y1602450D03*
X686699Y1638650D03*
X691999Y1660550D03*
X693099Y1722350D03*
X690499Y1744950D03*
X694599Y1768450D03*
X693549Y1793134D03*
X685549Y1799134D03*
X686473Y1818375D03*
X681549Y1825234D03*
X687049Y1822334D03*
X686999Y1870250D03*
X690899Y1855850D03*
X696299Y1898850D03*
X676399Y1901150D03*
X695299Y1926450D03*
X685499Y1940050D03*
X696299Y1976250D03*
X678799Y1975750D03*
X685499Y1959050D03*
Y1968050D03*
X679499Y1987050D03*
X697999Y7050D03*
X712499Y6050D03*
X699699Y141750D03*
Y160750D03*
X700699Y181750D03*
X711999Y218050D03*
X711499Y252550D03*
X711999Y307550D03*
Y293050D03*
Y325050D03*
X711499Y344550D03*
X712699Y434450D03*
X713699Y455450D03*
X713199Y474950D03*
Y489450D03*
X712599Y521050D03*
X713599Y542050D03*
X713099Y561550D03*
X699999Y610050D03*
X717099Y636050D03*
X702999Y656050D03*
Y688050D03*
Y670550D03*
X710899Y751150D03*
X716599Y736850D03*
X706999Y792550D03*
X707499Y773050D03*
X706999Y811550D03*
X707999Y832550D03*
X705999Y851050D03*
Y865550D03*
X707399Y899550D03*
Y918550D03*
X706499Y942550D03*
X713999Y1017050D03*
Y1031550D03*
X713499Y1068550D03*
X713999Y1049050D03*
X709999Y1105550D03*
X700499Y1118550D03*
X704299Y1132650D03*
X716999Y1148150D03*
X697499Y1153550D03*
X717999Y1169150D03*
X697499Y1172550D03*
X713399Y1178750D03*
X697999Y1184550D03*
X713599Y1214650D03*
X714399Y1199750D03*
X708699Y1243550D03*
X709699Y1264550D03*
X707899Y1346250D03*
X702299Y1404450D03*
X713899Y1386450D03*
X716899Y1459850D03*
X700899Y1450250D03*
X716199Y1503050D03*
X714599Y1533950D03*
X708899Y1549250D03*
X698599Y1568550D03*
X706700Y1579900D03*
X717099Y1702450D03*
X702599Y1730550D03*
X715999Y1744050D03*
X709099Y1751850D03*
X715999Y1763050D03*
Y1772050D03*
X706549Y1793634D03*
X715549Y1799634D03*
X717564Y1804045D03*
X717000Y1812384D03*
X705000Y1811900D03*
X711500Y1817700D03*
X704300Y1828400D03*
X697999Y1844550D03*
X706399Y1855850D03*
X705599Y1891850D03*
X716599Y1918450D03*
X698299Y1948050D03*
X711899Y1944050D03*
X709199Y1962950D03*
X717999Y1987550D03*
X702499D03*
X729999Y6550D03*
X725499Y23550D03*
X725999Y45050D03*
X725499Y62050D03*
X725999Y77550D03*
Y92050D03*
Y106550D03*
X738199Y137450D03*
X725999Y124050D03*
X725499Y143550D03*
Y162550D03*
X726499Y183550D03*
X728899Y204550D03*
X729499Y218550D03*
X723200Y275500D03*
X737999Y467050D03*
X738999Y488050D03*
X738499Y507550D03*
Y539550D03*
Y522050D03*
X737999Y559050D03*
X731499Y572050D03*
Y586550D03*
Y604050D03*
X721499Y617550D03*
X729699Y640350D03*
X723499Y654850D03*
X739399Y688150D03*
X720899Y712250D03*
X732499Y729250D03*
X727099Y715050D03*
X733799Y761450D03*
X723999Y783350D03*
Y802350D03*
X724999Y823350D03*
X728499Y841850D03*
X729999Y862850D03*
Y881850D03*
X730999Y902850D03*
X723699Y936250D03*
Y955250D03*
X724699Y976250D03*
X734999Y1030550D03*
Y1045050D03*
Y1062550D03*
X727499Y1106050D03*
X737999Y1119050D03*
X720499Y1118550D03*
X727499Y1132650D03*
X737999Y1159550D03*
Y1187550D03*
Y1178550D03*
X735999Y1206050D03*
X725499Y1231650D03*
X735999Y1220550D03*
X725499Y1250650D03*
X723499Y1278150D03*
X725499Y1259650D03*
X723499Y1292650D03*
X719199Y1322350D03*
X739199Y1348950D03*
X734199Y1373850D03*
X736199Y1399050D03*
X737799Y1428350D03*
X721899Y1419050D03*
X719499Y1446650D03*
X729199Y1492750D03*
X735799Y1533650D03*
X734499Y1563550D03*
X722199Y1564250D03*
X719999Y1605050D03*
X732999Y1620050D03*
X738799Y1677250D03*
X727399Y1694350D03*
X739199Y1716750D03*
X721199Y1723750D03*
X729999Y1756450D03*
X729499Y1778750D03*
X732549Y1802934D03*
X738049Y1793884D03*
X720300Y1808884D03*
X728099Y1844750D03*
X723199Y1867950D03*
X725899Y1855350D03*
X732999Y1868550D03*
X728299Y1888850D03*
X732199Y1878750D03*
X728799Y1908150D03*
Y1933050D03*
X736799Y1919450D03*
X730499Y1954650D03*
X721499Y1974550D03*
X737499Y1987050D03*
X749499Y6550D03*
X751499Y48350D03*
X757499Y44050D03*
Y63050D03*
X758499Y84050D03*
X752099Y112150D03*
X757999Y154550D03*
Y159050D03*
X753999Y154550D03*
Y159050D03*
X749499Y218550D03*
X746999Y325550D03*
X755499Y314550D03*
X755346Y319149D03*
X751539Y313984D03*
X751499Y318050D03*
X752999Y343550D03*
X750099Y333550D03*
X749899Y398550D03*
X750899Y419550D03*
X750399Y453550D03*
Y439050D03*
X755199Y488150D03*
X756199Y509150D03*
X755699Y528650D03*
X754499Y564650D03*
X755499Y585650D03*
X754999Y605150D03*
X744999Y626550D03*
X751499Y679148D03*
X757400Y686300D03*
X747999Y670750D03*
X754999Y694050D03*
X749999Y700050D03*
X745696Y725050D03*
X749499Y716050D03*
X744999Y715550D03*
X749999Y720050D03*
X745499D03*
X746999Y741050D03*
X747499Y733762D03*
X749799Y767450D03*
X743099Y785350D03*
X751999Y817050D03*
X751499Y855550D03*
Y836550D03*
X751599Y887350D03*
Y906350D03*
X752599Y927350D03*
X749999Y946550D03*
Y965550D03*
X751399Y1004550D03*
X750999Y986550D03*
X751399Y1023550D03*
X752399Y1052550D03*
X753999Y1100050D03*
X745599Y1129050D03*
X755499Y1119050D03*
X749999Y1119550D03*
X748999Y1115550D03*
X748499Y1111550D03*
X749499Y1142550D03*
X754151Y1135982D03*
X758799Y1171150D03*
Y1190150D03*
Y1199150D03*
X756799Y1232150D03*
Y1217650D03*
X757399Y1258650D03*
Y1239650D03*
X740499Y1252550D03*
X757399Y1267650D03*
X740499Y1270050D03*
X740799Y1298750D03*
X755399Y1300650D03*
Y1286150D03*
X742099Y1320650D03*
X754999Y1420050D03*
Y1437550D03*
X741099Y1450250D03*
Y1498150D03*
X747199Y1509150D03*
X755499Y1507550D03*
X745600Y1531296D03*
X751000Y1517000D03*
X757500Y1522500D03*
X751000Y1521000D03*
Y1525000D03*
X754999Y1550788D03*
X752099Y1540568D03*
X755499Y1568550D03*
X743400Y1578700D03*
X751300Y1604900D03*
X756299Y1679050D03*
X750099Y1694950D03*
X756499Y1712150D03*
X747499Y1734350D03*
X756900Y1766000D03*
X752900D03*
X751899Y1752150D03*
X747799Y1766750D03*
X751999Y1775550D03*
X756617Y1780067D03*
X752657Y1779496D03*
X755999Y1775550D03*
X753558Y1769946D03*
X757518Y1770517D03*
X744049Y1791634D03*
X740549Y1802634D03*
X753949Y1798194D03*
X741549Y1818384D03*
X740549Y1810384D03*
X747599Y1844250D03*
X744699Y1868450D03*
X758399Y1868350D03*
X743399Y1855850D03*
X743799Y1888850D03*
X753699Y1879250D03*
X755299Y1902150D03*
X739799D03*
X755500Y1914500D03*
X749499Y1933050D03*
X751096Y1955250D03*
X748299Y1946363D03*
X746499Y1974250D03*
X754999Y1987550D03*
X764999Y6550D03*
X763399Y24150D03*
X774399Y54050D03*
X775399Y80250D03*
X778399Y105250D03*
X767399Y140150D03*
X760799Y181950D03*
X779399Y200550D03*
X766999Y219050D03*
X763937Y348257D03*
X775650Y331900D03*
X781478Y363924D03*
X776978D03*
X772478Y359924D03*
Y363924D03*
X774999Y476550D03*
Y462050D03*
Y494050D03*
X774499Y513550D03*
Y532550D03*
X775499Y553550D03*
X777499Y638050D03*
X764599Y655750D03*
X777499Y664550D03*
X771800Y686600D03*
X766499Y699050D03*
Y705550D03*
X776999Y690050D03*
X779200Y732800D03*
X774350Y732900D03*
X771196Y764382D03*
Y760382D03*
X775696Y764382D03*
X780196D03*
X778999Y806950D03*
X763099Y796350D03*
X775199Y839250D03*
Y858250D03*
X776199Y879250D03*
X772199Y920650D03*
Y939650D03*
X773199Y960650D03*
X776899Y988050D03*
Y1007050D03*
X777899Y1028050D03*
X760999Y1095550D03*
X773499Y1101050D03*
X769499D03*
X773499Y1105050D03*
X769499D03*
X762898Y1152400D03*
X774200Y1133700D03*
X780333Y1165892D03*
X775833D03*
X771333Y1161892D03*
Y1165892D03*
X762499Y1335550D03*
X779399Y1361850D03*
X762499Y1353050D03*
X773999Y1393450D03*
X763399Y1401450D03*
X769300Y1488100D03*
X779000Y1488400D03*
X771399Y1474550D03*
X770999Y1500050D03*
X780499D03*
X773499Y1509050D03*
X769499D03*
X777050Y1539200D03*
X778327Y1569796D03*
X773327Y1565796D03*
X773827Y1569796D03*
X768500Y1577500D03*
X776999Y1647650D03*
X765099Y1664950D03*
X770399Y1699650D03*
X779999Y1717050D03*
X770099Y1730350D03*
X779899Y1748150D03*
X765600Y1756800D03*
X768379Y1778150D03*
X767159Y1792364D03*
X768549Y1816634D03*
X765099Y1844750D03*
X779699Y1867950D03*
X779399Y1855850D03*
X763899D03*
X780799Y1888850D03*
X763299Y1888350D03*
X769199Y1879250D03*
X774499Y1908050D03*
X765999D03*
X773999Y1923550D03*
X767999Y1923050D03*
X774499Y1930050D03*
X768999D03*
X775999Y1916050D03*
X768499Y1917550D03*
X776100Y1944200D03*
X779900Y1976200D03*
X775814Y1975699D03*
X770814Y1971713D03*
X771814Y1975713D03*
X762700Y1961800D03*
X777499Y1987550D03*
X784499Y6050D03*
X801999Y6550D03*
X796999Y27050D03*
X797499Y48550D03*
X796999Y65550D03*
X797499Y81050D03*
Y95550D03*
Y110050D03*
X796599Y123450D03*
X797499Y127550D03*
X796999Y147050D03*
Y166050D03*
X797999Y187050D03*
X786499Y219050D03*
X800999Y216550D03*
X785999Y285550D03*
X796873Y307571D03*
Y303071D03*
Y298571D03*
Y294071D03*
X784478Y355424D03*
Y359924D03*
X789999Y570050D03*
Y602050D03*
Y584550D03*
X785499Y641050D03*
X794999Y664550D03*
X786500Y686100D03*
X798000Y686400D03*
X782999Y699550D03*
X794331Y698353D03*
Y702853D03*
Y707353D03*
Y711853D03*
X799385Y761436D03*
X783196Y760382D03*
Y755882D03*
X802499Y814550D03*
X801999Y834050D03*
Y853050D03*
X800999Y892550D03*
Y907050D03*
Y924550D03*
X800499Y944050D03*
Y963050D03*
X801499Y984050D03*
X800999Y1005550D03*
Y1020050D03*
Y1037550D03*
X781999Y1085050D03*
X783999Y1096550D03*
X789499Y1099550D03*
X802499Y1097566D03*
X798499D03*
X783333Y1157392D03*
Y1161892D03*
X790999Y1194550D03*
Y1175550D03*
X791499Y1206550D03*
X789499Y1225050D03*
Y1257050D03*
Y1239550D03*
X788999Y1278150D03*
X791999Y1294450D03*
X795299Y1326650D03*
X799999Y1340550D03*
X798299Y1344250D03*
X799999Y1358050D03*
X781999Y1434650D03*
X786500Y1488600D03*
X801300Y1489000D03*
X786999Y1506550D03*
X791499Y1492550D03*
X795999Y1509550D03*
Y1504550D03*
Y1518550D03*
Y1514050D03*
X781904Y1538188D03*
X785827Y1561296D03*
Y1565796D03*
X782827Y1569796D03*
X797299Y1646650D03*
X802899Y1670550D03*
X782999Y1668050D03*
Y1687050D03*
X783499Y1699050D03*
X794499Y1734550D03*
X787900Y1758800D03*
X786699Y1808934D03*
X785799Y1795634D03*
X801099Y1844750D03*
X785599D03*
X791799Y1855850D03*
X797199Y1868450D03*
X788699Y1878750D03*
X783499Y1907050D03*
X790499Y1913050D03*
Y1899550D03*
X795526Y1909696D03*
X795493Y1913696D03*
X795501Y1917696D03*
X795499Y1922050D03*
X783814Y1967213D03*
Y1971713D03*
X784016Y1975708D03*
X789299Y1983850D03*
X792999Y1987550D03*
X818999Y6050D03*
X817599Y43750D03*
X813299Y49350D03*
Y68350D03*
X814299Y89350D03*
X813299Y110850D03*
X821199Y137450D03*
X805899Y126150D03*
X818013Y173064D03*
X817999Y182050D03*
X809373Y307571D03*
Y297571D03*
Y292571D03*
X808999Y303050D03*
X821499Y314050D03*
X806499Y364152D03*
X819299Y413250D03*
Y394250D03*
X820299Y434250D03*
X802999Y466050D03*
X803999Y487050D03*
X803499Y506550D03*
Y538550D03*
Y521050D03*
X802999Y558050D03*
X814499Y569550D03*
Y601550D03*
Y584050D03*
X815000Y687500D03*
X809700Y686300D03*
X806300Y670600D03*
X806831Y701853D03*
Y706853D03*
X806999Y697050D03*
X806831Y711853D03*
X811499Y767550D03*
Y782050D03*
Y799550D03*
X802999Y874050D03*
X811499Y1097050D03*
X807499D03*
X807341Y1111216D03*
Y1101216D03*
X806999Y1106050D03*
X807341Y1116216D03*
X808299Y1175850D03*
X806599Y1189750D03*
X803599Y1211050D03*
X810199Y1229350D03*
Y1248350D03*
Y1257350D03*
X808199Y1275850D03*
Y1290350D03*
X822199Y1335250D03*
X819199Y1353550D03*
X806499Y1390550D03*
X803299Y1426650D03*
X806499Y1408050D03*
X805899Y1464250D03*
X822100Y1470700D03*
X809245Y1508722D03*
Y1503722D03*
Y1518722D03*
X808999Y1513550D03*
X813300Y1604100D03*
X803599Y1618350D03*
X814599Y1642650D03*
X823499Y1674050D03*
X808899Y1698450D03*
X823499Y1693050D03*
Y1702050D03*
X824100Y1719900D03*
X819400Y1721900D03*
X819200Y1727100D03*
X808299Y1755250D03*
X819593Y1783807D03*
X817249Y1793050D03*
X823499Y1825050D03*
X815499Y1817050D03*
X809299Y1856350D03*
X818900Y1870800D03*
X806199Y1879250D03*
X822700Y1875100D03*
X809600Y1887560D03*
X807936Y1914865D03*
Y1910365D03*
X807997Y1922865D03*
X808005Y1918865D03*
X813599Y1979950D03*
X812499Y1987050D03*
X836499Y6550D03*
X824899Y25150D03*
X844799Y19850D03*
X839999Y46050D03*
X840499Y55050D03*
X840999Y62550D03*
X841499Y71550D03*
X843499Y82550D03*
X838999Y85050D03*
X837999Y91050D03*
X838499Y107050D03*
Y99550D03*
X839499Y119050D03*
X837499Y138550D03*
X838499Y145050D03*
X840499Y182550D03*
X829999Y200550D03*
X827774Y213183D03*
X836499Y213162D03*
X838299Y204800D03*
X836600Y261000D03*
X830000Y294500D03*
X838999Y313550D03*
X838499Y352050D03*
X839299Y390950D03*
Y409950D03*
X840299Y430950D03*
X824899Y500450D03*
X825899Y521450D03*
X825399Y540950D03*
X834599Y543050D03*
X835599Y564050D03*
X835099Y583550D03*
X835300Y663200D03*
X841000Y671100D03*
X836149Y714050D03*
X835999Y767050D03*
X837799Y754150D03*
X835999Y781550D03*
Y799050D03*
X825199Y850850D03*
X827699Y873450D03*
Y892450D03*
X828699Y913450D03*
X826999Y963150D03*
Y982150D03*
X827999Y1003150D03*
X834500Y1067600D03*
X827500Y1102000D03*
X841999Y1118550D03*
X836149D03*
X839999Y1157550D03*
X831499Y1181550D03*
Y1209550D03*
Y1200550D03*
X829499Y1228050D03*
Y1242550D03*
X828199Y1267850D03*
X826199Y1294450D03*
X831499Y1324950D03*
X841999Y1341050D03*
Y1358550D03*
X825500Y1379000D03*
X834499Y1397550D03*
X836600Y1416500D03*
Y1471100D03*
X829000Y1505500D03*
X843999Y1523550D03*
X839499D03*
X839899Y1562050D03*
X825999Y1578050D03*
X826499Y1609050D03*
X827199Y1622750D03*
X841499Y1638950D03*
X837199Y1660550D03*
X839199Y1683550D03*
X842799Y1701150D03*
X829200Y1719800D03*
X829199Y1783750D03*
X844499Y1788050D03*
X842500Y1799000D03*
X827999Y1791550D03*
X840400Y1827100D03*
X829799Y1856350D03*
X833199Y1868450D03*
X842199Y1879250D03*
X833100Y1878500D03*
X837499Y1876900D03*
X829000Y1913000D03*
X843999Y1928550D03*
X838999D03*
X840999Y1970550D03*
X829499Y1980250D03*
X829999Y1987550D03*
X855999Y6550D03*
X860799Y24150D03*
X865499Y39550D03*
X854499D03*
X856499Y71050D03*
X855499Y82050D03*
X845999Y111050D03*
X853999Y132550D03*
X865499Y125550D03*
X849999Y145550D03*
X854200Y269500D03*
X847577Y272131D03*
X847200Y267200D03*
X863999Y313550D03*
X858400Y352300D03*
X847999Y352550D03*
X854499Y387550D03*
Y373050D03*
Y405050D03*
X853999Y424550D03*
Y443550D03*
X854999Y464550D03*
X860199Y525050D03*
X861199Y546050D03*
X860699Y565550D03*
X861800Y591200D03*
X860499Y607550D03*
X846400Y665500D03*
X847200Y672000D03*
X860796Y678632D03*
X852703Y667497D03*
X855499Y700550D03*
X860499Y691050D03*
X859999Y713050D03*
X862700Y735300D03*
X859999Y767550D03*
X856299Y753150D03*
X846799Y754150D03*
X865000Y752100D03*
X859999Y782050D03*
Y799550D03*
X847799Y828250D03*
X857099Y873450D03*
X866199Y920350D03*
Y901350D03*
X850999Y962550D03*
Y943550D03*
X851999Y983550D03*
X851600Y1073300D03*
X846400Y1078700D03*
X846500Y1073500D03*
X855500Y1106500D03*
X861500Y1095000D03*
X859999Y1118550D03*
X863000Y1139000D03*
X846499Y1170450D03*
X856400Y1157700D03*
X848999Y1158050D03*
X863300Y1153800D03*
X845799Y1190450D03*
X849799Y1199750D03*
X851999Y1237550D03*
Y1218550D03*
X852499Y1249550D03*
X850499Y1268050D03*
X860099Y1295450D03*
X850499Y1300050D03*
Y1282550D03*
X847500Y1367000D03*
X854327Y1481596D03*
X848300Y1483000D03*
X845700Y1477100D03*
X858499Y1511550D03*
X861999Y1522550D03*
X850099Y1572250D03*
X858400Y1561900D03*
X850499Y1562050D03*
X865300Y1557700D03*
X864000Y1578200D03*
X849900Y1605100D03*
X852499Y1621350D03*
X855799Y1658250D03*
X855350Y1703201D03*
X864099Y1683550D03*
X853799Y1790850D03*
X846000Y1811400D03*
X863099Y1813150D03*
X862499Y1823550D03*
X854977Y1818994D03*
X849800Y1888300D03*
X854814Y1887250D03*
X847700Y1881900D03*
X861414Y1928550D03*
X864414Y1940050D03*
X850499Y1977950D03*
X856999Y1970050D03*
X849999Y1970550D03*
X865200Y1968000D03*
X864999Y1987050D03*
X849499D03*
X871499Y6550D03*
X885999Y21150D03*
X883999Y39050D03*
X881499Y70550D03*
X866999D03*
X876999Y82050D03*
X867499D03*
X886499Y99550D03*
Y104550D03*
X872499Y133050D03*
X875499Y125550D03*
X871499Y146050D03*
X882999Y160434D03*
X885499Y165050D03*
X871786Y218924D03*
Y203924D03*
X887400Y233555D03*
X871786Y233924D03*
X887400Y259700D03*
X879878Y247724D03*
X870600Y346700D03*
X875799Y386250D03*
Y405250D03*
X876799Y426250D03*
X884399Y443450D03*
Y462450D03*
X873999Y484550D03*
X885399Y483450D03*
X886749Y560500D03*
X876787Y567743D03*
X870719Y609705D03*
X870773Y624705D03*
X870719Y639705D03*
X887401Y665000D03*
X881125Y652050D03*
X871786Y679436D03*
Y709482D03*
X871499Y689436D03*
X866499Y724550D03*
X871385Y719436D03*
X884499Y767050D03*
Y781550D03*
Y799050D03*
X873999Y830550D03*
Y845050D03*
Y862550D03*
X886999Y907350D03*
X867199Y941350D03*
X886999Y947250D03*
X886583Y967600D03*
X877499Y977050D03*
X870777Y1014948D03*
X870468Y1030227D03*
X886919Y1044478D03*
X870298Y1045227D03*
X880033Y1058592D03*
X887400Y1070600D03*
X871399Y1182850D03*
Y1201850D03*
Y1210850D03*
X869399Y1229350D03*
Y1243850D03*
X872099Y1268150D03*
X871399Y1291450D03*
X875399Y1322650D03*
X869587Y1354050D03*
X873499Y1356050D03*
X880499Y1367550D03*
X882999Y1374550D03*
X879999Y1380170D03*
X868499Y1392550D03*
Y1410050D03*
X871836Y1420460D03*
X886913Y1449010D03*
X871836Y1435460D03*
X879727Y1463696D03*
X871836Y1450460D03*
X887499Y1476050D03*
X873099Y1572550D03*
X886900Y1604100D03*
X866499Y1603050D03*
Y1612050D03*
X868099Y1635650D03*
X887299Y1620050D03*
X877699Y1646650D03*
X882999Y1678250D03*
X879200Y1698700D03*
X871100Y1690300D03*
X879900Y1709300D03*
X883900Y1709500D03*
X875900D03*
X882700Y1738300D03*
X886900Y1737900D03*
X872950Y1744401D03*
X866699Y1770950D03*
X886200Y1776200D03*
X879399Y1798150D03*
X869634Y1826876D03*
X871836Y1840972D03*
X887499Y1855550D03*
X869999Y1855972D03*
X887401Y1881500D03*
X879399Y1974550D03*
X873399Y1963650D03*
X868699Y1983250D03*
X884499Y1986550D03*
X890999Y6050D03*
X908499Y6550D03*
X902999Y22050D03*
X902499Y35050D03*
X905499Y56550D03*
X904999Y61550D03*
X904499Y74050D03*
X904999Y67550D03*
X905499Y94550D03*
X890459Y100116D03*
X890499Y104550D03*
X889999Y132550D03*
X891999Y146050D03*
X907499Y160434D03*
X906999Y243150D03*
Y224150D03*
X907999Y264150D03*
X906399Y295250D03*
Y314250D03*
X907399Y335250D03*
X904999Y370550D03*
Y385050D03*
Y402550D03*
X904499Y422050D03*
Y441050D03*
X905499Y462050D03*
X899685Y559592D03*
X894200Y560400D03*
X906999Y557050D03*
X903999Y574378D03*
X898999Y622050D03*
Y604550D03*
X894000Y642400D03*
X900999Y652550D03*
Y670050D03*
X895999Y702550D03*
Y720050D03*
X898499Y830050D03*
Y844550D03*
X889699Y876050D03*
X898499Y862050D03*
X905999Y962050D03*
X894999Y963050D03*
X897299Y1182450D03*
X887999Y1209350D03*
X892499Y1224550D03*
Y1252550D03*
Y1243550D03*
X890499Y1271050D03*
Y1285550D03*
X890999Y1336550D03*
Y1354050D03*
X891999Y1363550D03*
X894499Y1423550D03*
Y1441050D03*
X895499Y1488050D03*
X902759Y1509585D03*
X894499Y1522050D03*
Y1539550D03*
X907500Y1604000D03*
X895999Y1661250D03*
X903599Y1686850D03*
X893000Y1695500D03*
X893200Y1721300D03*
X902900Y1709800D03*
X899500Y1720700D03*
X893200Y1730000D03*
X897239Y1771500D03*
X892999Y1776050D03*
X899599Y1776604D03*
X904814Y1789113D03*
X903299Y1814750D03*
X894999Y1829050D03*
X905299Y1852650D03*
X894000Y1868452D03*
X900299Y1876950D03*
X897299Y1904150D03*
X907599Y1930050D03*
X897599Y1938750D03*
X904299Y1954950D03*
X901999Y1987050D03*
X923999Y6050D03*
X917499Y21550D03*
X909499D03*
X909999Y35550D03*
X916499Y36050D03*
X928499Y51550D03*
X920900Y54700D03*
X928999Y56050D03*
X928499Y60550D03*
X928999Y65550D03*
X913999Y58050D03*
X912399Y88150D03*
X910499Y98550D03*
X926499Y103050D03*
X922999Y158550D03*
X916999Y168424D03*
X913699Y484650D03*
Y503650D03*
X914699Y524650D03*
X921999Y557050D03*
X927999Y568550D03*
X918999Y641550D03*
Y656050D03*
Y673550D03*
X918499Y693050D03*
Y712050D03*
X921899Y744850D03*
X919499Y733050D03*
X921899Y759350D03*
Y776850D03*
X921399Y796350D03*
X922399Y836350D03*
X921399Y815350D03*
X920399Y854850D03*
Y869350D03*
Y886850D03*
X919899Y906350D03*
Y925350D03*
X920899Y946350D03*
X922049Y961050D03*
X921499Y999050D03*
Y1013550D03*
Y1031050D03*
X920999Y1050550D03*
Y1069550D03*
X925499Y1103550D03*
X921999Y1090550D03*
X925499Y1118050D03*
Y1135550D03*
X924999Y1174050D03*
Y1155050D03*
X925999Y1195050D03*
Y1207050D03*
Y1221550D03*
Y1239050D03*
X925499Y1258550D03*
Y1277550D03*
X926499Y1298550D03*
X928499Y1325350D03*
X925999Y1365050D03*
Y1379550D03*
Y1397050D03*
X925499Y1416550D03*
Y1435550D03*
X926499Y1456550D03*
X924999Y1485550D03*
Y1471050D03*
Y1503050D03*
X914599Y1521650D03*
X924499Y1522550D03*
X910899Y1549250D03*
X924499Y1541550D03*
X909700Y1576400D03*
X925499Y1562550D03*
X925599Y1612050D03*
X923599Y1634350D03*
X908899Y1630050D03*
X914899Y1657550D03*
X922599Y1682150D03*
X921499Y1770050D03*
X911299Y1800850D03*
X914999Y1791500D03*
X928000Y1818500D03*
X922899Y1853650D03*
X914999Y1868050D03*
Y1887050D03*
X914899Y1912450D03*
X915499Y1899050D03*
X916599Y1942650D03*
X914899Y1972250D03*
X921499Y1986550D03*
X941499Y6550D03*
X929999Y32550D03*
X940499Y33050D03*
X945499Y33550D03*
X943499Y48050D03*
Y55050D03*
Y72550D03*
X942999Y61550D03*
Y66550D03*
X943499Y78050D03*
X944499Y95050D03*
X941873Y103050D03*
X935999Y104050D03*
X939199Y142050D03*
X937499Y158500D03*
X945999Y166550D03*
X932499Y191550D03*
Y206050D03*
Y223550D03*
X931999Y243050D03*
Y262050D03*
X932999Y283050D03*
X933499Y304050D03*
Y318550D03*
Y336050D03*
X932999Y355550D03*
Y374550D03*
X933999Y395550D03*
X933499Y429550D03*
Y415050D03*
Y447050D03*
X932999Y466550D03*
Y485550D03*
X933999Y506550D03*
X935499Y539050D03*
Y524550D03*
Y556550D03*
X934999Y576050D03*
X950299Y599650D03*
X934999Y595050D03*
X950299Y614150D03*
X935999Y616050D03*
X950299Y631650D03*
X949799Y651150D03*
Y670150D03*
X950799Y691150D03*
X944499Y750050D03*
Y735550D03*
Y767550D03*
X943999Y787050D03*
Y806050D03*
X944999Y827050D03*
X942999Y845550D03*
Y877550D03*
Y860050D03*
X942499Y897050D03*
Y916050D03*
X943499Y937050D03*
X929499Y971100D03*
X949299Y977450D03*
Y991950D03*
Y1009450D03*
X948799Y1047950D03*
Y1028950D03*
X949799Y1068950D03*
Y1080950D03*
X950699Y1107750D03*
Y1122250D03*
Y1139750D03*
X950199Y1159250D03*
Y1178250D03*
X950699Y1262750D03*
Y1281750D03*
X943799Y1342950D03*
Y1380850D03*
X944000Y1391900D03*
X946700Y1426500D03*
X944000Y1511300D03*
X943199Y1531650D03*
X933199Y1577550D03*
X944499Y1632650D03*
X950100Y1626100D03*
X940499Y1656950D03*
X941499Y1679550D03*
X931499Y1702050D03*
X949799Y1756250D03*
X941800Y1787700D03*
X941499Y1776250D03*
X934200Y1793500D03*
X932199Y1801850D03*
X937199Y1869950D03*
X937499Y1893850D03*
X938199Y1917150D03*
X947499Y1936050D03*
X930999Y1931050D03*
X945199Y1946350D03*
X930999Y1950050D03*
X946199Y1966650D03*
X931499Y1962050D03*
X930199Y1979550D03*
X936999Y1986550D03*
X960999Y6550D03*
X954799Y17850D03*
X965999Y47050D03*
Y56050D03*
Y64050D03*
X966499Y73050D03*
Y82050D03*
X964042Y96050D03*
X954499Y116550D03*
X968399Y137150D03*
X967399Y180350D03*
X958799Y167350D03*
X956099Y181350D03*
X952799Y199150D03*
Y213650D03*
Y231150D03*
X952299Y250650D03*
Y269650D03*
X953299Y290650D03*
X952799Y324650D03*
Y310150D03*
Y342150D03*
X952299Y361650D03*
Y380650D03*
X953299Y401650D03*
X954799Y434150D03*
Y419650D03*
Y451650D03*
X966199Y473350D03*
Y492350D03*
X951799Y489650D03*
X967199Y513350D03*
X951799Y504150D03*
Y521650D03*
X951299Y560150D03*
Y541150D03*
X966799Y566350D03*
X952299Y581150D03*
X966799Y585350D03*
X967799Y606350D03*
X969499Y639050D03*
Y653550D03*
Y671050D03*
X968999Y709550D03*
Y690550D03*
X969999Y730550D03*
Y744250D03*
Y758750D03*
Y776250D03*
X969499Y795750D03*
Y814750D03*
X970499Y835750D03*
Y847750D03*
Y862250D03*
X969999Y899250D03*
X970499Y879750D03*
X969999Y918250D03*
X970999Y939250D03*
X971999Y996550D03*
Y1011050D03*
Y1028550D03*
X971499Y1067050D03*
Y1048050D03*
X951199Y1211250D03*
Y1199250D03*
Y1225750D03*
Y1243250D03*
X951699Y1302750D03*
X965099Y1324350D03*
X952499Y1361850D03*
X964400Y1409700D03*
X972000Y1442000D03*
Y1437500D03*
X971700Y1448300D03*
X962500Y1436500D03*
Y1441000D03*
X952800Y1437500D03*
Y1442000D03*
X962200Y1447300D03*
X952500Y1448300D03*
X971500Y1467500D03*
X971700Y1457800D03*
Y1462300D03*
Y1452800D03*
X962000Y1466500D03*
X952300Y1467500D03*
X962200Y1451800D03*
X952500Y1452800D03*
X962200Y1456800D03*
Y1461300D03*
X952500Y1457800D03*
Y1462300D03*
X966000Y1475000D03*
X958800Y1472500D03*
X966000Y1479500D03*
Y1484000D03*
X958800Y1477000D03*
Y1481500D03*
X965700Y1489300D03*
X958500Y1486800D03*
X960200Y1495300D03*
X951500D03*
X960049Y1500300D03*
X951349D03*
X960049Y1504800D03*
X951349D03*
X966600Y1529100D03*
X961400Y1528700D03*
X961900Y1522400D03*
X967100Y1522800D03*
X962100Y1516000D03*
X967300Y1516400D03*
X961600Y1534400D03*
X972000Y1547500D03*
X966100D03*
X960900Y1547100D03*
X961400Y1540800D03*
X966600Y1541200D03*
X966800Y1534800D03*
X961600Y1552900D03*
X966800Y1553300D03*
X972000Y1566000D03*
X966100D03*
X960900Y1565600D03*
X961400Y1559300D03*
X966600Y1559700D03*
X961900Y1572400D03*
X967100Y1572800D03*
X966400Y1585500D03*
X961200Y1585100D03*
X961700Y1578800D03*
X966900Y1579200D03*
X966500Y1592000D03*
X961300Y1591600D03*
X966300Y1598400D03*
X961100Y1598000D03*
X960600Y1604300D03*
X971700Y1604700D03*
X965800D03*
X957799Y1646950D03*
X955499Y1690850D03*
X958799Y1715750D03*
X965349Y1742000D03*
X954499Y1783550D03*
X971000Y1803000D03*
X971500Y1871500D03*
X966799Y1892150D03*
X955499Y1893050D03*
Y1902050D03*
X954099Y1915450D03*
X955799Y1951950D03*
X971499Y1956050D03*
Y1937050D03*
X953799Y1977950D03*
X971499Y1965050D03*
X956499Y1986050D03*
X976499Y6550D03*
X974699Y21450D03*
X991399Y22450D03*
X977399Y44050D03*
X974699Y64650D03*
X991999Y56050D03*
X983099Y83650D03*
X977699Y109150D03*
X981099Y123450D03*
X988699Y174350D03*
X982999Y189050D03*
Y203550D03*
Y221050D03*
X982499Y240550D03*
Y259550D03*
X983499Y280550D03*
X983999Y301550D03*
Y316050D03*
Y333550D03*
X983499Y353050D03*
Y372050D03*
X983999Y412550D03*
X984499Y393050D03*
X983999Y427050D03*
Y444550D03*
X983499Y464050D03*
Y483050D03*
X984499Y504050D03*
X985999Y536550D03*
Y522050D03*
Y554050D03*
X985499Y573550D03*
Y592550D03*
X986499Y613550D03*
X992999Y894550D03*
Y913550D03*
X972499Y1088050D03*
X975999Y1101050D03*
Y1115550D03*
X975499Y1152550D03*
X975999Y1133050D03*
X975499Y1171550D03*
X976499Y1192550D03*
Y1204550D03*
Y1219050D03*
Y1236550D03*
X975999Y1256050D03*
Y1275050D03*
X976999Y1296050D03*
X975100Y1342600D03*
X976499Y1362550D03*
Y1377050D03*
X992500Y1397300D03*
X973500Y1483000D03*
Y1478500D03*
X973200Y1488300D03*
X973500Y1474000D03*
X972549Y1502300D03*
Y1506800D03*
X972700Y1497300D03*
X973200Y1516400D03*
X972500Y1529100D03*
X973000Y1522800D03*
X972700Y1534800D03*
X972500Y1541200D03*
X972700Y1553300D03*
X972500Y1559700D03*
X973000Y1572800D03*
X972300Y1585500D03*
X972800Y1579200D03*
X972400Y1592000D03*
X972200Y1598400D03*
X989999Y1718050D03*
X993299Y1734350D03*
X976600Y1757100D03*
X976399Y1772250D03*
Y1791150D03*
X974699Y1914450D03*
X991999Y1915750D03*
X992299Y1929050D03*
X980999Y1933350D03*
X987999Y1949050D03*
Y1971950D03*
X989999Y1962650D03*
X973999Y1986550D03*
X995999Y6050D03*
X1013499Y6550D03*
X1002699Y40050D03*
X1005299Y71350D03*
X994399Y101250D03*
X1010599Y115550D03*
X1005299Y179950D03*
Y194450D03*
Y211950D03*
X1004799Y231450D03*
Y250450D03*
X1005799Y271450D03*
X1005299Y305450D03*
Y290950D03*
Y322950D03*
X1004799Y342450D03*
Y361450D03*
X1005799Y382450D03*
X1007299Y400450D03*
Y432450D03*
Y414950D03*
X1000699Y463350D03*
Y482350D03*
X1001699Y503350D03*
X1003999Y526850D03*
X1003499Y546350D03*
Y565350D03*
X1004499Y586350D03*
X1005999Y618850D03*
Y604350D03*
Y636350D03*
X994999Y747550D03*
Y733050D03*
Y765050D03*
X994499Y784550D03*
Y803550D03*
X995499Y824550D03*
X993499Y857550D03*
Y843050D03*
Y875050D03*
X994499Y941550D03*
X993999Y934550D03*
X994499Y956050D03*
Y973550D03*
X993999Y993050D03*
Y1012050D03*
X994999Y1033050D03*
Y1045050D03*
X998599Y1110950D03*
Y1096450D03*
Y1128450D03*
X998099Y1147950D03*
Y1166950D03*
X999099Y1187950D03*
Y1214450D03*
Y1199950D03*
Y1231950D03*
X998599Y1251450D03*
Y1270450D03*
X999599Y1291450D03*
X996500Y1324800D03*
X1000700Y1358100D03*
X994200Y1421500D03*
X1008999Y1702450D03*
X1008599Y1716050D03*
X994999Y1748950D03*
X999999Y1775250D03*
X1009999Y1797450D03*
X993499Y1805550D03*
X1007599Y1818450D03*
X993499Y1824550D03*
X1003599Y1846650D03*
X993499Y1833550D03*
X1011299Y1860650D03*
X995699Y1858950D03*
X1001599Y1921450D03*
X1000999Y1946350D03*
X1002500Y1953500D03*
X1005000Y1980500D03*
X994999Y1986550D03*
X1022000Y15500D03*
X1020499Y50550D03*
X1020999Y33050D03*
Y70050D03*
Y85550D03*
Y105050D03*
X1020499Y122550D03*
X1020999Y158550D03*
X1021499Y141050D03*
Y178050D03*
Y193550D03*
Y213050D03*
X1020999Y230550D03*
Y252050D03*
X1020499Y269550D03*
X1020999Y304550D03*
Y289050D03*
Y324050D03*
X1020499Y341550D03*
Y391550D03*
X1020999Y374050D03*
Y411050D03*
Y426550D03*
Y446050D03*
X1020499Y463550D03*
X1021999Y486550D03*
X1021499Y504050D03*
X1021999Y539050D03*
Y523550D03*
Y558550D03*
X1021499Y576050D03*
X1020499Y623050D03*
X1020999Y605550D03*
Y642550D03*
Y658050D03*
Y677550D03*
X1020499Y695050D03*
X1020999Y720050D03*
X1020499Y737550D03*
X1020999Y772550D03*
Y757050D03*
Y792050D03*
X1020499Y809550D03*
Y828050D03*
X1019999Y845550D03*
X1020499Y865050D03*
Y880550D03*
X1019999Y917550D03*
X1020499Y900050D03*
X1019999Y934050D03*
X1019499Y951550D03*
X1019999Y971050D03*
Y986550D03*
X1019499Y1023550D03*
X1019999Y1006050D03*
Y1043050D03*
Y1058550D03*
X1020499Y1081550D03*
X1019999Y1099050D03*
X1020499Y1118550D03*
Y1134050D03*
X1019499Y1146050D03*
X1018999Y1163550D03*
X1019499Y1183050D03*
Y1198550D03*
X1016999Y1219050D03*
X1016499Y1236550D03*
X1016999Y1256050D03*
Y1271550D03*
X1016499Y1301050D03*
X1022599Y1322950D03*
X1023300Y1344400D03*
X1024300Y1365200D03*
Y1393600D03*
X1022299Y1715750D03*
X1016899Y1731650D03*
X1020299Y1746650D03*
X1015299Y1765950D03*
X1026899Y1768550D03*
X1022999Y1784550D03*
X1022499Y1802050D03*
X1022999Y1821550D03*
Y1837050D03*
X1020999Y1860050D03*
X1020499Y1877550D03*
X1020999Y1912550D03*
Y1897050D03*
X1017499Y1954550D03*
X1017999Y1937050D03*
X1023000Y1973000D03*
X1017999Y1987050D03*
G54D22*
X20799Y1976200D03*
X946999Y118800D03*
G54D40*
X43999Y1968350D03*
X103499Y1301413D03*
X104999Y1705663D03*
X123999Y1738413D03*
X138999Y520913D03*
X142667Y1310060D03*
X132999Y1310413D03*
X137504Y1739123D03*
X161999Y919413D03*
X182499Y74850D03*
X194500Y502800D03*
X215900Y900500D03*
X292999Y89913D03*
X295500Y332800D03*
X298000Y739300D03*
X297000Y1553400D03*
X296858Y1947628D03*
X369300Y75900D03*
X389500Y75800D03*
X693549Y1816934D03*
X870201Y1713450D03*
X907999Y88350D03*
G54D13*
X29531Y309549D03*
Y1029510D03*
X17720Y1903132D03*
X129921Y17716D03*
X271657Y267699D03*
Y673210D03*
Y1078722D03*
Y1484234D03*
Y1889746D03*
X994098Y149588D03*
Y673210D03*
Y1068880D03*
X994093Y1889751D03*
G54D31*
X39799Y1918050D03*
X21799Y1956050D03*
X103345Y931489D03*
Y927989D03*
X104128Y1336952D03*
Y1333452D03*
X108799Y129550D03*
Y126050D03*
Y145050D03*
Y141550D03*
X104745Y525988D03*
Y522488D03*
X108745Y550988D03*
Y547488D03*
X108345Y956489D03*
Y952989D03*
X107628Y1361952D03*
Y1358452D03*
X105299Y1743050D03*
Y1739550D03*
X107299Y1764050D03*
Y1767550D03*
X132750Y1081100D03*
Y1077600D03*
X183299Y99050D03*
X181999Y524850D03*
X701349Y1813134D03*
X839299Y167550D03*
X839799Y1788050D03*
X907299Y124550D03*
X954799Y96050D03*
G54D32*
X39799Y1921550D03*
X57299Y1901550D03*
X88300Y1097500D03*
Y1111500D03*
X109250Y1348100D03*
Y1344600D03*
X131799Y224550D03*
Y228050D03*
Y249050D03*
Y252550D03*
X127300Y433600D03*
X135238Y630065D03*
Y633565D03*
Y654565D03*
Y658065D03*
X132799Y1035550D03*
Y1039050D03*
Y1060050D03*
Y1063550D03*
X131190Y1441241D03*
Y1444741D03*
Y1465741D03*
Y1469241D03*
X131892Y1846254D03*
Y1849754D03*
Y1870754D03*
Y1874254D03*
X859278Y224924D03*
Y228424D03*
Y249424D03*
Y252924D03*
X859496Y630382D03*
Y633882D03*
Y654882D03*
Y658382D03*
X859133Y1035892D03*
Y1039392D03*
Y1060892D03*
Y1064392D03*
X860627Y1440796D03*
Y1444296D03*
Y1465796D03*
Y1469296D03*
X862614Y1846613D03*
Y1850113D03*
Y1871113D03*
Y1874613D03*
G54D41*
X49999Y1971850D03*
X107999Y1303913D03*
X109499Y1708413D03*
X143499Y523413D03*
X136600Y1180200D03*
X166499Y921913D03*
X218998Y317914D03*
X213598Y350914D03*
X218499Y724850D03*
X214599Y757850D03*
X217600Y1127800D03*
X217999Y1534850D03*
X218814Y1925913D03*
X213600Y1962400D03*
X297499Y92413D03*
X783049Y1819434D03*
X788049D03*
X858999Y311850D03*
X864900Y344900D03*
X855696Y712182D03*
X862896Y746382D03*
X855333Y1117692D03*
X862933Y1149192D03*
X857827Y1522596D03*
X865700Y1552400D03*
X857314Y1928413D03*
X864500Y1962200D03*
G54D50*
X76038Y1929550D03*
X110960D03*
G54D23*
X38999Y372160D03*
X29999Y849660D03*
X20499Y1315050D03*
X34999Y1572550D03*
X35900Y1832700D03*
X26499Y1935550D03*
X26999Y1941550D03*
X57400Y610900D03*
X102999Y29050D03*
X100999Y468550D03*
X96999Y1632050D03*
X109999Y872550D03*
X107699Y1510950D03*
X118999Y1525550D03*
X126999Y1119050D03*
X141499Y1267050D03*
X162500Y557500D03*
X202999Y90550D03*
X197226Y90428D03*
X233100Y1929800D03*
X287999Y315550D03*
X288999Y723550D03*
X655049Y1810634D03*
X807499Y1089550D03*
X803499Y1496050D03*
X814499Y1809050D03*
X806499Y1903550D03*
X824499Y205050D03*
X843700Y312200D03*
X841500Y713000D03*
X920999Y103050D03*
X914999D03*
G54D14*
X12569Y372041D03*
Y375978D03*
Y379915D03*
Y383852D03*
Y387789D03*
Y391726D03*
Y395663D03*
Y399600D03*
Y403537D03*
Y407474D03*
Y411411D03*
Y431098D03*
Y427161D03*
Y423223D03*
Y435035D03*
Y438972D03*
Y442909D03*
Y446846D03*
Y450783D03*
Y454720D03*
Y458657D03*
Y462594D03*
Y466531D03*
Y470468D03*
Y474405D03*
Y478342D03*
Y482279D03*
Y486216D03*
Y490153D03*
Y494090D03*
Y498027D03*
Y501964D03*
Y505901D03*
Y509838D03*
Y513775D03*
Y517712D03*
Y521649D03*
Y525586D03*
Y529523D03*
Y533460D03*
Y537397D03*
Y541334D03*
Y545271D03*
Y549208D03*
Y553145D03*
Y557082D03*
Y561019D03*
Y564956D03*
Y568893D03*
Y572830D03*
Y576767D03*
Y580704D03*
Y584641D03*
Y588578D03*
Y592515D03*
Y596452D03*
Y600389D03*
Y604326D03*
Y608263D03*
Y612200D03*
Y616137D03*
Y620074D03*
Y624011D03*
Y627948D03*
Y631885D03*
Y635822D03*
Y639759D03*
Y643696D03*
Y647633D03*
Y651570D03*
Y655507D03*
Y659444D03*
Y663381D03*
Y671255D03*
Y667318D03*
Y675192D03*
Y679129D03*
Y683066D03*
Y687003D03*
Y690940D03*
Y694877D03*
Y698814D03*
X12560Y793325D03*
Y789388D03*
Y785451D03*
Y781514D03*
Y813010D03*
Y809073D03*
Y805136D03*
Y801199D03*
Y797262D03*
Y832696D03*
Y820884D03*
Y816947D03*
Y856318D03*
Y852381D03*
Y848444D03*
Y844507D03*
Y840570D03*
Y836633D03*
X12569Y1356293D03*
Y1360230D03*
Y1364167D03*
Y1368104D03*
Y1372041D03*
Y1375978D03*
Y1379915D03*
Y1383852D03*
Y1387789D03*
Y1391726D03*
Y1395663D03*
Y1415350D03*
Y1411413D03*
Y1407475D03*
Y1419287D03*
Y1423224D03*
Y1427161D03*
Y1431098D03*
Y1435035D03*
Y1438972D03*
Y1442909D03*
Y1446846D03*
Y1450783D03*
Y1454720D03*
Y1458657D03*
Y1462594D03*
Y1466531D03*
Y1470468D03*
Y1474405D03*
Y1478342D03*
Y1482279D03*
Y1486216D03*
Y1490153D03*
Y1494090D03*
Y1498027D03*
Y1501964D03*
Y1505901D03*
Y1509838D03*
Y1513775D03*
Y1517712D03*
Y1521649D03*
Y1525586D03*
Y1529523D03*
Y1533460D03*
Y1537397D03*
Y1541334D03*
Y1545271D03*
Y1549208D03*
Y1553145D03*
Y1557082D03*
Y1561019D03*
Y1564956D03*
Y1568893D03*
Y1572830D03*
Y1576767D03*
Y1580704D03*
Y1584641D03*
Y1588578D03*
Y1592515D03*
Y1596452D03*
Y1600389D03*
Y1604326D03*
Y1608263D03*
Y1612200D03*
Y1616137D03*
Y1620074D03*
Y1624011D03*
Y1627948D03*
Y1631885D03*
Y1635822D03*
Y1639759D03*
Y1643696D03*
Y1655507D03*
Y1651570D03*
Y1647633D03*
Y1659444D03*
Y1663381D03*
Y1667318D03*
Y1675192D03*
Y1671255D03*
Y1679129D03*
Y1683066D03*
X12560Y1765766D03*
Y1785451D03*
Y1781514D03*
Y1777577D03*
Y1773640D03*
Y1769703D03*
Y1805136D03*
Y1801199D03*
Y1797262D03*
Y1793325D03*
Y1789388D03*
Y1828759D03*
Y1824822D03*
Y1820885D03*
Y1816948D03*
Y1840570D03*
Y1836633D03*
Y1832696D03*
G54D15*
X19399Y1065050D03*
X18299Y1936050D03*
Y1944050D03*
X32100Y597400D03*
Y593300D03*
X39700Y597400D03*
X31299Y616050D03*
X35400Y607326D03*
Y603200D03*
X38299Y1838050D03*
Y1842050D03*
X48399Y217100D03*
X45000Y635500D03*
Y639600D03*
X57049Y656487D03*
Y652487D03*
Y648487D03*
X75799Y642550D03*
X79300Y1013000D03*
X63899Y1851900D03*
X83899Y1000450D03*
Y1004450D03*
X97899Y1081700D03*
Y1077400D03*
X89300Y1553500D03*
Y1557500D03*
X118799Y1125050D03*
X124600Y1319900D03*
X120299Y1343050D03*
X119799Y1356050D03*
Y1352050D03*
X115549Y1476050D03*
X105799Y1716613D03*
Y1720613D03*
X134299Y423113D03*
Y427113D03*
X136200Y1210400D03*
X128300Y1365000D03*
X144299Y1722550D03*
Y1718550D03*
X154799Y165050D03*
Y161050D03*
X154099Y540050D03*
Y544250D03*
X154299Y570050D03*
Y566050D03*
X154799Y975550D03*
Y971550D03*
X154771Y1786909D03*
Y1782909D03*
X179426Y82428D03*
X176799Y156550D03*
Y165050D03*
Y161050D03*
X169000Y424400D03*
X176799Y572050D03*
Y568050D03*
Y564050D03*
X171300Y922700D03*
X180400Y931600D03*
X176549Y976550D03*
Y972550D03*
X176799Y967550D03*
X177364Y1786613D03*
Y1782613D03*
Y1778613D03*
X195400Y823000D03*
X191299Y1381050D03*
Y1377050D03*
Y1373050D03*
X195349Y1635113D03*
Y1630613D03*
X230299Y101050D03*
Y97050D03*
X228700Y283000D03*
X226300Y689500D03*
X224550Y1082500D03*
X224800Y1480100D03*
X229700Y1499300D03*
X302300Y90700D03*
X305299Y343550D03*
X306799Y360050D03*
Y356050D03*
Y750050D03*
X307799Y767050D03*
Y762550D03*
X306799Y1573050D03*
X303299Y1562550D03*
X306799Y1577050D03*
X310158Y1953328D03*
X310077Y1966191D03*
Y1962191D03*
X334299Y63050D03*
Y67050D03*
X375299Y53050D03*
Y57050D03*
X383299Y30550D03*
Y26050D03*
X400799Y51050D03*
Y56050D03*
X648349Y1803634D03*
Y1796134D03*
X647849Y1818634D03*
X693849Y1821634D03*
Y1825634D03*
X736349Y1806634D03*
Y1798634D03*
Y1814134D03*
X775700Y336200D03*
X774400Y736700D03*
X774500Y1138200D03*
X777100Y1543100D03*
X774349Y1817634D03*
X776299Y1949050D03*
X785849Y1804634D03*
Y1800634D03*
X813799Y1825550D03*
Y1821550D03*
X844496Y681882D03*
X844133Y1087392D03*
X845778Y280924D03*
X858399Y1372200D03*
X846127Y1492296D03*
X846614Y1898113D03*
X871528Y163924D03*
Y159924D03*
X883299Y570550D03*
Y565050D03*
X883133Y975892D03*
Y971892D03*
X870127Y1379796D03*
Y1375796D03*
X878401Y1720950D03*
X885901D03*
X882900Y1786300D03*
X882864Y1782213D03*
X902299Y99050D03*
X905246Y570882D03*
Y566882D03*
Y562882D03*
X905133Y974392D03*
Y970392D03*
Y966392D03*
X904864Y1785613D03*
Y1781613D03*
Y1777613D03*
X922528Y168424D03*
Y164424D03*
X922299Y172550D03*
G54D24*
X35500Y597400D03*
Y593300D03*
X34699Y616050D03*
X38800Y607326D03*
Y603200D03*
X22799Y1065050D03*
X21699Y1936050D03*
Y1944050D03*
X51799Y217100D03*
X43100Y597400D03*
X48400Y635500D03*
Y639600D03*
X60449Y656487D03*
Y652487D03*
Y648487D03*
X41699Y1838050D03*
Y1842050D03*
X79199Y642550D03*
X82700Y1013000D03*
X67299Y1851900D03*
X87299Y1000450D03*
Y1004450D03*
X101299Y1081700D03*
Y1077400D03*
X92700Y1553500D03*
Y1557500D03*
X122199Y1125050D03*
X123699Y1343050D03*
X123199Y1356050D03*
Y1352050D03*
X118949Y1476050D03*
X109199Y1716613D03*
Y1720613D03*
X137699Y423113D03*
Y427113D03*
X139600Y1210400D03*
X128000Y1319900D03*
X131700Y1365000D03*
X158199Y165050D03*
Y161050D03*
X157499Y540050D03*
Y544250D03*
X157699Y570050D03*
Y566050D03*
X158199Y975550D03*
Y971550D03*
X147699Y1722550D03*
Y1718550D03*
X158171Y1786909D03*
Y1782909D03*
X182826Y82428D03*
X180199Y156550D03*
Y165050D03*
Y161050D03*
X172400Y424400D03*
X180199Y572050D03*
Y568050D03*
Y564050D03*
X174700Y922700D03*
X183800Y931600D03*
X179949Y976550D03*
Y972550D03*
X180199Y967550D03*
X180764Y1786613D03*
Y1782613D03*
Y1778613D03*
X198800Y823000D03*
X194699Y1381050D03*
Y1377050D03*
Y1373050D03*
X198749Y1635113D03*
Y1630613D03*
X229700Y689500D03*
X227950Y1082500D03*
X228200Y1480100D03*
X233699Y101050D03*
Y97050D03*
X232100Y283000D03*
X233100Y1499300D03*
X305700Y90700D03*
X308699Y343550D03*
X310199Y360050D03*
Y356050D03*
Y750050D03*
X311199Y767050D03*
Y762550D03*
X310199Y1573050D03*
X306699Y1562550D03*
X310199Y1577050D03*
X313558Y1953328D03*
X313477Y1966191D03*
Y1962191D03*
X337699Y63050D03*
Y67050D03*
X378699Y53050D03*
Y57050D03*
X386699Y30550D03*
Y26050D03*
X404199Y51050D03*
Y56050D03*
X651749Y1803634D03*
Y1796134D03*
X651249Y1818634D03*
X697249Y1821634D03*
Y1825634D03*
X739749Y1806634D03*
Y1798634D03*
Y1814134D03*
X779100Y336200D03*
X777800Y736700D03*
X777900Y1138200D03*
X780500Y1543100D03*
X777749Y1817634D03*
X779699Y1949050D03*
X789249Y1804634D03*
Y1800634D03*
X817199Y1825550D03*
Y1821550D03*
X849178Y280924D03*
X847896Y681882D03*
X847533Y1087392D03*
X861799Y1372200D03*
X849527Y1492296D03*
X850014Y1898113D03*
X874928Y163924D03*
Y159924D03*
X886699Y570550D03*
Y565050D03*
X886533Y975892D03*
Y971892D03*
X873527Y1379796D03*
Y1375796D03*
X881801Y1720950D03*
X886300Y1786300D03*
X886264Y1782213D03*
X905699Y99050D03*
X889301Y1720950D03*
X925928Y168424D03*
Y164424D03*
X925699Y172550D03*
X908646Y570882D03*
Y566882D03*
Y562882D03*
X908533Y974392D03*
Y970392D03*
Y966392D03*
X908264Y1785613D03*
Y1781613D03*
Y1777613D03*
G54D33*
X36199Y1921550D03*
X53699Y1901550D03*
X84700Y1097500D03*
Y1111500D03*
X123700Y433600D03*
X105650Y1348100D03*
Y1344600D03*
X128199Y224550D03*
Y228050D03*
Y249050D03*
Y252550D03*
X131638Y630065D03*
Y633565D03*
Y654565D03*
Y658065D03*
X129199Y1035550D03*
Y1039050D03*
Y1060050D03*
Y1063550D03*
X127590Y1441241D03*
Y1444741D03*
Y1465741D03*
Y1469241D03*
X128292Y1846254D03*
Y1849754D03*
Y1870754D03*
Y1874254D03*
X855678Y224924D03*
Y228424D03*
Y249424D03*
Y252924D03*
X855896Y630382D03*
Y633882D03*
Y654882D03*
Y658382D03*
X855533Y1035892D03*
Y1039392D03*
Y1060892D03*
Y1064392D03*
X857027Y1440796D03*
Y1444296D03*
Y1465796D03*
Y1469296D03*
X859014Y1846613D03*
Y1850113D03*
Y1871113D03*
Y1874613D03*
G54D51*
X91099Y1870050D03*
Y1890550D03*
X124500Y1583500D03*
X115899Y1870050D03*
Y1890550D03*
X149300Y1583500D03*
G54D60*
X122799Y1485350D03*
X159500Y821800D03*
X178999Y74850D03*
X213499Y101350D03*
X216998Y287414D03*
X216999Y693850D03*
X222900Y1090100D03*
X216999Y1503850D03*
X235499Y84850D03*
X232314Y1897413D03*
X312800Y321100D03*
X308999Y728350D03*
X309299Y1536750D03*
X313499Y1931850D03*
X655549Y1796434D03*
Y1803934D03*
X693549Y1801934D03*
Y1809434D03*
X755500Y709800D03*
X759500Y1922800D03*
X764500Y308300D03*
X779978Y308224D03*
X777500Y709800D03*
X760500Y1110800D03*
X778500D03*
X762000Y1516800D03*
X783200Y1516500D03*
X784500Y1922800D03*
X858478Y281224D03*
X857196Y682182D03*
X856833Y1087692D03*
X858827Y1492596D03*
X859314Y1898413D03*
X904499Y88350D03*
X928499Y111850D03*
G54D42*
X49999Y1966250D03*
X107999Y1298313D03*
X109499Y1702813D03*
X143499Y517813D03*
X136600Y1174600D03*
X166499Y916313D03*
X218998Y312314D03*
X213598Y345314D03*
X218499Y719250D03*
X214599Y752250D03*
X217600Y1122200D03*
X217999Y1529250D03*
X218814Y1920313D03*
X213600Y1956800D03*
X297499Y86813D03*
X783049Y1813834D03*
X788049D03*
X858999Y306250D03*
X864900Y339300D03*
X855696Y706582D03*
X862896Y740782D03*
X855333Y1112092D03*
X862933Y1143592D03*
X857827Y1516996D03*
X865700Y1546800D03*
X857314Y1922813D03*
X864500Y1956600D03*
G54D34*
X44368Y1946712D03*
G54D70*
X139875Y1694600D03*
X166275Y485500D03*
X196875Y910700D03*
X328175Y79500D03*
X823825Y285000D03*
X822025Y688200D03*
X822225Y1093700D03*
X824025Y1496200D03*
X824225Y1902900D03*
X835075Y1734500D03*
G54D52*
X105749Y1964050D03*
X121249D03*
X206249Y39550D03*
X221749D03*
X915749Y44550D03*
X931249D03*
G54D25*
X34699Y611550D03*
X21699Y1948050D03*
Y1952050D03*
Y1940050D03*
X59199Y203550D03*
Y207550D03*
Y211550D03*
X59699Y1017050D03*
X59636Y1021050D03*
Y1025050D03*
X55699Y1897050D03*
X81199Y204550D03*
Y208550D03*
X81201Y611450D03*
Y615450D03*
X77199Y1837550D03*
X77449Y1843113D03*
X77199Y1849050D03*
X84700Y1008500D03*
X100700Y1115400D03*
X103949Y1476050D03*
X85949Y1828613D03*
Y1832613D03*
X108950Y972000D03*
X108899Y967850D03*
X116199Y1298113D03*
X111449Y1476050D03*
X117449Y1702613D03*
X128180Y1098482D03*
Y1094482D03*
X142100Y1335800D03*
X131199Y1342050D03*
X131700Y1361000D03*
X151699Y517613D03*
X159399Y524850D03*
X166899D03*
X147200Y545000D03*
X182872Y90572D03*
Y86572D03*
X186599Y152000D03*
X174399Y524850D03*
X186599Y559300D03*
X174699Y916113D03*
X187099Y963100D03*
X174200Y1691200D03*
X186099Y1773200D03*
X202599Y1367400D03*
X229698Y287114D03*
X229699Y693550D03*
X233572Y92572D03*
X233699Y105050D03*
X241699Y95550D03*
X244000Y269700D03*
X243400Y677100D03*
X305699Y86613D03*
X308699Y334050D03*
Y339050D03*
X310199Y742050D03*
Y746050D03*
X306699Y1554550D03*
Y1558550D03*
X313921Y1944909D03*
Y1948909D03*
X319600Y105200D03*
X333198Y337114D03*
Y333114D03*
X318400Y365200D03*
X334699Y745050D03*
Y741050D03*
X319400Y772200D03*
X331199Y1553550D03*
Y1557550D03*
X318400Y1582600D03*
X321600Y1971900D03*
X339421Y1947409D03*
Y1943409D03*
X378800Y42300D03*
X700749Y1801634D03*
Y1808634D03*
X754678Y323924D03*
Y328924D03*
X753396Y724882D03*
Y729882D03*
X754033Y1126392D03*
Y1131392D03*
X757027Y1531296D03*
Y1536296D03*
X753514Y1937713D03*
Y1942213D03*
X779699Y326550D03*
Y322550D03*
X771678Y347924D03*
Y352424D03*
X777699Y724050D03*
Y728550D03*
X769896Y748382D03*
Y752882D03*
X778699Y1127550D03*
Y1123550D03*
X770033Y1152392D03*
Y1156892D03*
X780881Y1527893D03*
Y1531893D03*
X772527Y1554796D03*
Y1559296D03*
X778199Y1935050D03*
Y1939050D03*
X770014Y1960713D03*
Y1965213D03*
X800699Y336050D03*
Y332050D03*
X799199Y736050D03*
Y732050D03*
Y1133050D03*
Y1137050D03*
X801881Y1538893D03*
Y1542893D03*
X800381Y1944393D03*
Y1948393D03*
X816699Y167050D03*
X817199Y1788050D03*
X824199Y167050D03*
X831699D03*
X824699Y1788050D03*
X832199D03*
X849200Y276800D03*
X847900Y677700D03*
X847500Y1083200D03*
X849500Y1488100D03*
X849999Y1893850D03*
X873199Y1359550D03*
Y1363550D03*
Y1367550D03*
X905699Y107050D03*
Y103050D03*
X916099Y557800D03*
X916599Y962100D03*
X916099Y1771700D03*
X931099Y158500D03*
G54D16*
X18499Y1923750D03*
X103999Y1235250D03*
X104499Y1267813D03*
X102100Y1638700D03*
X105499Y1673313D03*
X134300Y455000D03*
X139499Y488813D03*
X162999Y852813D03*
X162499Y886313D03*
X221498Y281314D03*
X221499Y687750D03*
X217500Y1084200D03*
X220999Y1497750D03*
X227814Y1891313D03*
X253200Y1534900D03*
X289099Y23313D03*
X293999Y56313D03*
X853978Y275124D03*
X852696Y676082D03*
X852333Y1081592D03*
X854327Y1486496D03*
X854814Y1892313D03*
X894800Y1704200D03*
G54D61*
X122799Y1481750D03*
X159500Y818200D03*
X178999Y71250D03*
X213499Y97750D03*
X216998Y283814D03*
X216999Y690250D03*
X222900Y1086500D03*
X216999Y1500250D03*
X235499Y81250D03*
X232314Y1893813D03*
X312800Y317500D03*
X308999Y724750D03*
X309299Y1533150D03*
X313499Y1928250D03*
X655549Y1792834D03*
Y1800334D03*
X693549Y1798334D03*
Y1805834D03*
X755500Y706200D03*
X759500Y1919200D03*
X764500Y304700D03*
X779978Y304624D03*
X777500Y706200D03*
X760500Y1107200D03*
X778500D03*
X762000Y1513200D03*
X783200Y1512900D03*
X784500Y1919200D03*
X858478Y277624D03*
X857196Y678582D03*
X856833Y1084092D03*
X858827Y1488996D03*
X859314Y1894813D03*
X904499Y84750D03*
X928499Y108250D03*
G54D43*
X68898Y17047D03*
Y190275D03*
Y422559D03*
Y595787D03*
Y828071D03*
Y1001299D03*
Y1233583D03*
Y1406811D03*
Y1639095D03*
Y1812323D03*
X167323Y179803D03*
Y353031D03*
Y585315D03*
Y758543D03*
Y990827D03*
Y1164055D03*
Y1396339D03*
Y1569567D03*
Y1801851D03*
Y1975079D03*
X895669Y179803D03*
Y353031D03*
Y585315D03*
Y758543D03*
Y990827D03*
Y1164055D03*
Y1396339D03*
Y1569567D03*
Y1801851D03*
Y1975079D03*
G54D80*
X238249Y102050D03*
G54D44*
X85630Y41141D03*
Y46141D03*
Y51141D03*
Y56141D03*
Y61141D03*
Y66141D03*
Y71141D03*
Y76141D03*
Y81141D03*
Y86141D03*
Y91141D03*
Y96141D03*
Y101141D03*
Y106141D03*
Y111141D03*
Y136141D03*
Y141141D03*
Y146141D03*
Y151141D03*
Y156141D03*
Y161141D03*
Y166141D03*
Y446653D03*
Y451653D03*
Y456653D03*
Y461653D03*
Y466653D03*
Y471653D03*
Y476653D03*
Y481653D03*
Y486653D03*
Y491653D03*
Y496653D03*
Y501653D03*
Y506653D03*
Y511653D03*
Y516653D03*
Y541653D03*
Y546653D03*
Y551653D03*
Y556653D03*
Y561653D03*
Y566653D03*
Y571653D03*
Y852165D03*
Y857165D03*
Y862165D03*
Y867165D03*
Y872165D03*
Y877165D03*
Y882165D03*
Y887165D03*
Y892165D03*
Y897165D03*
Y902165D03*
Y907165D03*
Y912165D03*
Y917165D03*
Y922165D03*
Y947165D03*
Y952165D03*
Y957165D03*
Y962165D03*
Y967165D03*
Y972165D03*
Y977165D03*
Y1257677D03*
Y1262677D03*
Y1267677D03*
Y1272677D03*
Y1277677D03*
Y1282677D03*
Y1287677D03*
Y1292677D03*
Y1297677D03*
Y1302677D03*
Y1307677D03*
Y1312677D03*
Y1317677D03*
Y1322677D03*
Y1327677D03*
Y1352677D03*
Y1357677D03*
Y1362677D03*
Y1367677D03*
Y1372677D03*
Y1377677D03*
Y1382677D03*
Y1663189D03*
Y1668189D03*
Y1673189D03*
Y1678189D03*
Y1683189D03*
Y1688189D03*
Y1693189D03*
Y1698189D03*
Y1703189D03*
Y1708189D03*
Y1713189D03*
Y1718189D03*
Y1723189D03*
Y1728189D03*
Y1733189D03*
Y1758189D03*
Y1763189D03*
Y1768189D03*
Y1773189D03*
Y1778189D03*
Y1783189D03*
Y1788189D03*
X150591Y218937D03*
Y213937D03*
Y208937D03*
Y203937D03*
Y233937D03*
Y228937D03*
Y223937D03*
Y263937D03*
Y258937D03*
Y283937D03*
Y278937D03*
Y273937D03*
Y268937D03*
Y303937D03*
Y298937D03*
Y293937D03*
Y288937D03*
Y323937D03*
Y318937D03*
Y313937D03*
Y308937D03*
Y328937D03*
Y624449D03*
Y619449D03*
Y614449D03*
Y609449D03*
Y639449D03*
Y634449D03*
Y629449D03*
Y664449D03*
Y684449D03*
Y679449D03*
Y674449D03*
Y669449D03*
Y704449D03*
Y699449D03*
Y694449D03*
Y689449D03*
Y729449D03*
Y724449D03*
Y719449D03*
Y714449D03*
Y709449D03*
Y734449D03*
Y1024961D03*
Y1019961D03*
Y1014961D03*
Y1044961D03*
Y1039961D03*
Y1034961D03*
Y1029961D03*
Y1084961D03*
Y1079961D03*
Y1074961D03*
Y1069961D03*
Y1109961D03*
Y1104961D03*
Y1099961D03*
Y1094961D03*
Y1089961D03*
Y1129961D03*
Y1124961D03*
Y1119961D03*
Y1114961D03*
Y1139961D03*
Y1134961D03*
Y1425473D03*
Y1420473D03*
Y1445473D03*
Y1440473D03*
Y1435473D03*
Y1430473D03*
Y1450473D03*
Y1490473D03*
Y1485473D03*
Y1480473D03*
Y1475473D03*
Y1510473D03*
Y1505473D03*
Y1500473D03*
Y1495473D03*
Y1530473D03*
Y1525473D03*
Y1520473D03*
Y1515473D03*
Y1545473D03*
Y1540473D03*
Y1535473D03*
Y1825985D03*
Y1850985D03*
Y1845985D03*
Y1840985D03*
Y1835985D03*
Y1830985D03*
Y1855985D03*
Y1890985D03*
Y1885985D03*
Y1880985D03*
Y1910985D03*
Y1905985D03*
Y1900985D03*
Y1895985D03*
Y1930985D03*
Y1925985D03*
Y1920985D03*
Y1915985D03*
Y1950985D03*
Y1945985D03*
Y1940985D03*
Y1935985D03*
X878937Y218937D03*
Y213937D03*
Y208937D03*
Y203937D03*
Y233937D03*
Y228937D03*
Y223937D03*
Y263937D03*
Y258937D03*
Y283937D03*
Y278937D03*
Y273937D03*
Y268937D03*
Y303937D03*
Y298937D03*
Y293937D03*
Y288937D03*
Y323937D03*
Y318937D03*
Y313937D03*
Y308937D03*
Y328937D03*
Y624449D03*
Y619449D03*
Y614449D03*
Y609449D03*
Y639449D03*
Y634449D03*
Y629449D03*
Y664449D03*
Y684449D03*
Y679449D03*
Y674449D03*
Y669449D03*
Y704449D03*
Y699449D03*
Y694449D03*
Y689449D03*
Y729449D03*
Y724449D03*
Y719449D03*
Y714449D03*
Y709449D03*
Y734449D03*
Y1024961D03*
Y1019961D03*
Y1014961D03*
Y1044961D03*
Y1039961D03*
Y1034961D03*
Y1029961D03*
Y1084961D03*
Y1079961D03*
Y1074961D03*
Y1069961D03*
Y1109961D03*
Y1104961D03*
Y1099961D03*
Y1094961D03*
Y1089961D03*
Y1129961D03*
Y1124961D03*
Y1119961D03*
Y1114961D03*
Y1139961D03*
Y1134961D03*
Y1425473D03*
Y1420473D03*
Y1445473D03*
Y1440473D03*
Y1435473D03*
Y1430473D03*
Y1450473D03*
Y1490473D03*
Y1485473D03*
Y1480473D03*
Y1475473D03*
Y1510473D03*
Y1505473D03*
Y1500473D03*
Y1495473D03*
Y1530473D03*
Y1525473D03*
Y1520473D03*
Y1515473D03*
Y1545473D03*
Y1540473D03*
Y1535473D03*
Y1825985D03*
Y1850985D03*
Y1845985D03*
Y1840985D03*
Y1835985D03*
Y1830985D03*
Y1855985D03*
Y1890985D03*
Y1885985D03*
Y1880985D03*
Y1910985D03*
Y1905985D03*
Y1900985D03*
Y1895985D03*
Y1930985D03*
Y1925985D03*
Y1920985D03*
Y1915985D03*
Y1950985D03*
Y1945985D03*
Y1940985D03*
Y1935985D03*
G54D53*
X109439Y1079300D03*
X111999D03*
X114559D03*
Y1085800D03*
X109439D03*
X106939Y1210363D03*
X109499D03*
X112059D03*
Y1216863D03*
X106939D03*
X120059Y1311800D03*
X117499D03*
X114939D03*
Y1305300D03*
X120059D03*
X145439Y426863D03*
Y433363D03*
X132939Y1714800D03*
X135499D03*
X138059D03*
Y1721300D03*
X132939D03*
X147999Y426863D03*
X150559D03*
Y433363D03*
X167439Y820363D03*
Y826863D03*
X169999Y820363D03*
X172559D03*
Y826863D03*
X208559Y891800D03*
X205999D03*
X203439D03*
Y885300D03*
X208559D03*
X278939Y327300D03*
X284059D03*
Y333800D03*
X281499D03*
X278939D03*
X285059Y740300D03*
X282499D03*
X279939D03*
Y733800D03*
X285059D03*
X284059Y1551300D03*
X281499D03*
X278939D03*
Y1544800D03*
X284059D03*
X283589Y1936200D03*
X288709D03*
Y1942700D03*
X286149D03*
X283589D03*
X790559Y327800D03*
X787999D03*
X785439D03*
Y321300D03*
X790559D03*
X790059Y728800D03*
X787499D03*
X784939D03*
Y722300D03*
X790059D03*
X789559Y1131800D03*
X786999D03*
X784439D03*
Y1125300D03*
X789559D03*
X787693Y1529128D03*
X792813D03*
Y1535628D03*
X790253D03*
X787693D03*
X785939Y1935800D03*
X791059D03*
Y1942300D03*
X788499D03*
X785939D03*
G54D71*
X166499Y1277113D03*
X161499D03*
X156499D03*
Y1297113D03*
X161499D03*
X166499D03*
X167499Y1700113D03*
X162499D03*
X157499D03*
Y1720113D03*
X162499D03*
X167499D03*
X171499Y1277113D03*
Y1297113D03*
X172499Y1700113D03*
Y1720113D03*
X206499Y514113D03*
X201499D03*
X196499D03*
X191499D03*
Y534113D03*
X196499D03*
X201499D03*
X206499D03*
X229999Y912613D03*
X224999D03*
X219999D03*
X214999D03*
Y932613D03*
X219999D03*
X224999D03*
X229999D03*
X247299Y1136650D03*
X242299D03*
X237299D03*
X232299D03*
Y1156650D03*
X237299D03*
X242299D03*
X247299D03*
X355999Y86550D03*
X350999D03*
X345999D03*
Y106550D03*
X350999D03*
X355999D03*
X360999Y86550D03*
Y106550D03*
G54D26*
X20849Y1059925D03*
Y1052175D03*
X28349Y1056050D03*
X42449Y211775D03*
Y204025D03*
X49949Y207900D03*
X60449Y1846475D03*
Y1838725D03*
X74049Y648025D03*
Y655775D03*
X66549Y651900D03*
X67949Y1842600D03*
X137249Y1347675D03*
Y1355425D03*
X129749Y1351550D03*
X186049Y161200D03*
Y568400D03*
Y972100D03*
X186549Y1782500D03*
X193549Y157325D03*
Y165075D03*
Y564525D03*
Y572275D03*
Y968225D03*
Y975975D03*
X208049Y1372925D03*
Y1380675D03*
X200549Y1376800D03*
X194049Y1778625D03*
Y1786375D03*
X856449Y1358925D03*
X863949Y1362800D03*
X856449Y1366675D03*
X922049Y563025D03*
Y570775D03*
X914549Y566900D03*
X922049Y967225D03*
Y974975D03*
X914549Y971100D03*
X921549Y1777125D03*
Y1784875D03*
X914049Y1781000D03*
X939549Y163825D03*
Y171575D03*
X932049Y167700D03*
G54D35*
X34525Y1956355D03*
X36494D03*
X38462D03*
Y1937069D03*
X36494D03*
X34525D03*
X40431Y1956355D03*
X42399D03*
X44368D03*
X46337D03*
X48305D03*
X50274D03*
X52242D03*
X54211D03*
Y1937069D03*
X52242D03*
X50274D03*
X48305D03*
X46337D03*
X44368D03*
X42399D03*
X40431D03*
G54D62*
X116045Y1484981D03*
X113485D03*
X110925D03*
X108365D03*
Y1501161D03*
X110925D03*
X113485D03*
X116045D03*
X166437Y533288D03*
X163877D03*
Y549468D03*
X166437D03*
X171557Y533288D03*
X168997D03*
Y549468D03*
X171557D03*
X833013Y176949D03*
X830453D03*
X827893D03*
X825333D03*
Y193129D03*
X827893D03*
X830453D03*
X833013D03*
Y1798997D03*
X830453D03*
X827893D03*
X825333D03*
Y1815177D03*
X827893D03*
X830453D03*
X833013D03*
G54D17*
X18499Y1929350D03*
X103999Y1240850D03*
X104499Y1273413D03*
X102100Y1644300D03*
X105499Y1678913D03*
X134300Y460600D03*
X139499Y494413D03*
X162999Y858413D03*
X162499Y891913D03*
X221498Y286914D03*
X221499Y693350D03*
X217500Y1089800D03*
X220999Y1503350D03*
X227814Y1896913D03*
X253200Y1540500D03*
X289099Y28913D03*
X293999Y61913D03*
X853978Y280724D03*
X852696Y681682D03*
X852333Y1087192D03*
X854327Y1492096D03*
X854814Y1897913D03*
X894800Y1709800D03*
G54D27*
X34599Y1588650D03*
X27030Y1925238D03*
X23030D03*
X19999Y1964850D03*
X31999Y1972350D03*
Y1964850D03*
X42700Y408900D03*
X49499Y1901850D03*
X83000Y1548300D03*
X79000D03*
X75000Y1565200D03*
X79000D03*
X97499Y1086850D03*
X101999D03*
X100700Y1107900D03*
X116499Y1223913D03*
Y1321413D03*
X120507Y1321496D03*
X116749Y1510150D03*
X112599D03*
X131999Y1224413D03*
X127499D03*
X162999Y443913D03*
X166999D03*
X150999Y440413D03*
X185999Y496450D03*
X181899D03*
X176499Y833413D03*
X185999Y842413D03*
X174499Y1649663D03*
X197499Y97850D03*
X205499D03*
X190499Y842413D03*
X205999Y898313D03*
X209999D03*
X226800Y1086600D03*
X225499Y1499350D03*
X231000Y1880500D03*
X247500Y1078550D03*
X236100Y1893900D03*
X280499Y341850D03*
X284999D03*
X281499Y748350D03*
X285499D03*
X278499Y1559350D03*
X282499D03*
X284358Y1951628D03*
X288358D03*
X399999Y39350D03*
X640049Y1803934D03*
Y1792934D03*
X649049Y1810934D03*
X655549Y1815434D03*
X712549Y1808634D03*
X706549Y1797934D03*
X744049Y1802934D03*
Y1795434D03*
Y1810434D03*
X833999Y204850D03*
X829499D03*
X827500Y267500D03*
X825700Y1075800D03*
X827700Y1480700D03*
X889700Y1704700D03*
X920499Y108350D03*
X912499D03*
X936499D03*
X948499D03*
G54D36*
X37999Y1968750D03*
Y1976350D03*
X53999Y778750D03*
Y786350D03*
X57068Y1966462D03*
Y1974062D03*
X83568Y1966462D03*
Y1974062D03*
X74568Y1966462D03*
Y1974062D03*
X65768Y1966462D03*
Y1974062D03*
X92568Y1966462D03*
Y1974062D03*
X240999Y89850D03*
Y82250D03*
G54D72*
X159550Y1263700D03*
X151650D03*
X184050Y478000D03*
X191950D03*
X207350Y876200D03*
X215250D03*
G54D45*
X77166Y114212D03*
Y117362D03*
Y120511D03*
Y123661D03*
Y126811D03*
Y129960D03*
Y133110D03*
Y519724D03*
Y522874D03*
Y526023D03*
Y529173D03*
Y532323D03*
Y535472D03*
Y538622D03*
Y925236D03*
Y928386D03*
Y931535D03*
Y934685D03*
Y937835D03*
Y940984D03*
Y944134D03*
Y1330748D03*
Y1333898D03*
Y1337047D03*
Y1340197D03*
Y1343347D03*
Y1346496D03*
Y1349646D03*
Y1736260D03*
Y1739410D03*
Y1742559D03*
Y1745709D03*
Y1748859D03*
Y1752008D03*
Y1755158D03*
X159055Y243267D03*
Y240118D03*
Y236968D03*
Y255866D03*
Y252716D03*
Y249567D03*
Y246417D03*
Y642480D03*
Y661378D03*
Y658228D03*
Y655079D03*
Y651929D03*
Y648779D03*
Y645630D03*
Y1066890D03*
Y1063740D03*
Y1060591D03*
Y1057441D03*
Y1054291D03*
Y1051142D03*
Y1047992D03*
Y1469252D03*
Y1466103D03*
Y1462953D03*
Y1459803D03*
Y1456654D03*
Y1453504D03*
Y1472402D03*
Y1871615D03*
Y1868465D03*
Y1865315D03*
Y1862166D03*
Y1859016D03*
Y1877914D03*
Y1874764D03*
X887401Y243267D03*
Y240118D03*
Y236968D03*
Y255866D03*
Y252716D03*
Y249567D03*
Y246417D03*
Y642480D03*
Y661378D03*
Y658228D03*
Y655079D03*
Y651929D03*
Y648779D03*
Y645630D03*
Y1066890D03*
Y1063740D03*
Y1060591D03*
Y1057441D03*
Y1054291D03*
Y1051142D03*
Y1047992D03*
Y1469252D03*
Y1466103D03*
Y1462953D03*
Y1459803D03*
Y1456654D03*
Y1453504D03*
Y1472402D03*
Y1871615D03*
Y1868465D03*
Y1865315D03*
Y1862166D03*
Y1859016D03*
Y1877914D03*
Y1874764D03*
G54D63*
X143999Y54089D03*
Y89011D03*
X862999Y60089D03*
Y95011D03*
G54D54*
X113499Y1106640D03*
Y1109200D03*
X106099D03*
Y1106640D03*
X113499Y1111760D03*
X106099D03*
X123299Y1216113D03*
Y1213553D03*
Y1218673D03*
X130699Y1213553D03*
Y1216113D03*
Y1218673D03*
X147400Y1324540D03*
Y1327100D03*
Y1329660D03*
X140000D03*
Y1327100D03*
Y1324540D03*
X158299Y433053D03*
X165699D03*
X158299Y438173D03*
Y435613D03*
X165699D03*
Y438173D03*
X181799Y834113D03*
Y831553D03*
X189199D03*
Y834113D03*
X181799Y836673D03*
X189199D03*
X179999Y1652987D03*
Y1650427D03*
Y1647867D03*
X187399D03*
Y1650427D03*
Y1652987D03*
X218100Y1882960D03*
Y1880400D03*
Y1877840D03*
X225500D03*
Y1880400D03*
Y1882960D03*
X242000Y1069000D03*
Y1071560D03*
Y1074120D03*
X234600D03*
Y1071560D03*
Y1069000D03*
X233600Y1478360D03*
Y1475800D03*
Y1473240D03*
X241000D03*
Y1475800D03*
Y1478360D03*
X324800Y92340D03*
Y94900D03*
X317400D03*
Y92340D03*
X324800Y97460D03*
X317400D03*
X394199Y36490D03*
Y39050D03*
Y41610D03*
X386799D03*
Y39050D03*
Y36490D03*
X760778Y341984D03*
Y339424D03*
Y336864D03*
X758996Y742442D03*
Y739882D03*
Y737322D03*
X760799Y1146610D03*
Y1144050D03*
Y1141490D03*
X759114Y1954773D03*
Y1952213D03*
Y1949653D03*
X768178Y336864D03*
Y339424D03*
Y341984D03*
X766396Y737322D03*
Y739882D03*
Y742442D03*
X768199Y1141490D03*
Y1144050D03*
Y1146610D03*
X761627Y1548856D03*
Y1546296D03*
Y1543736D03*
X769027D03*
Y1546296D03*
Y1548856D03*
X766514Y1949653D03*
Y1952213D03*
Y1954773D03*
X814700Y270060D03*
Y267500D03*
Y264940D03*
X822100D03*
Y267500D03*
Y270060D03*
X813200Y672660D03*
Y670100D03*
Y667540D03*
X820600D03*
Y670100D03*
Y672660D03*
X812900Y1075460D03*
Y1072900D03*
Y1070340D03*
X820300D03*
Y1072900D03*
Y1075460D03*
X814700Y1483160D03*
Y1480600D03*
Y1478040D03*
X822100D03*
Y1480600D03*
Y1483160D03*
X815300Y1887560D03*
Y1885000D03*
Y1882440D03*
X822700D03*
Y1885000D03*
Y1887560D03*
G54D81*
X240749Y102050D03*
G54D18*
G01X176749Y572050D02*
Y575550D01*
X198499Y597300D01*
X350499D01*
G01X176499Y976550D02*
Y995999D01*
X176691D01*
X254307Y1073615D01*
Y1090808D01*
X268499Y1105000D01*
Y1120999D01*
X282500Y1135000D01*
X14999Y1936050D03*
Y1940050D03*
X8499Y1937550D03*
X15099Y1944050D03*
X5303Y1947050D03*
X11703Y1951946D03*
X17499Y1961050D03*
X29699Y388484D03*
X29599Y382884D03*
X23399Y373931D03*
Y389679D03*
X23499Y381831D03*
X26299Y383854D03*
Y387629D03*
X28100Y374000D03*
X26299Y399601D03*
Y403376D03*
X29999Y398684D03*
X29899Y404384D03*
X23799Y405684D03*
X23499Y397579D03*
X35900Y412600D03*
X26524Y426720D03*
X26399Y423322D03*
X28672Y429356D03*
X29365Y421169D03*
X23399Y429051D03*
X28900Y417800D03*
X26492Y439350D03*
X26599Y442749D03*
X26899Y454850D03*
X28700Y451900D03*
X28800Y436700D03*
X28700Y445700D03*
X23399Y444799D03*
X23499Y452699D03*
Y436951D03*
X26799Y458497D03*
X26486Y462648D03*
X26499Y466250D03*
X29500Y460800D03*
X23499Y468447D03*
X23399Y476295D03*
Y460547D03*
X26299Y478404D03*
X26515Y481798D03*
X23399Y492043D03*
X23499Y484195D03*
X36499Y517775D03*
X26399Y501966D03*
Y505741D03*
X28600Y508500D03*
X38400Y514955D03*
X28664Y499429D03*
X23499Y515691D03*
Y499943D03*
X23399Y507791D03*
X36499Y521550D03*
X35338Y524746D03*
X26691Y532701D03*
X22800Y539600D03*
X23399Y523539D03*
X23499Y531439D03*
X26599Y525648D03*
Y529302D03*
X27199Y539600D03*
X39217Y554750D03*
X33307Y557938D03*
X26199Y547176D03*
X29999Y557150D03*
X33699Y561850D03*
X36499Y566350D03*
X22699Y577950D03*
X22999Y565550D03*
X28000Y578500D03*
X25581Y567763D03*
X27699Y573750D03*
X22978Y588571D03*
X28808Y593150D03*
X28700Y596549D03*
X27499Y620203D03*
Y623857D03*
X37999Y611550D03*
X26869Y616861D03*
X23499Y618053D03*
X23999Y609250D03*
X34976Y619250D03*
X26800Y611500D03*
X32200Y603710D03*
X31598Y607102D03*
X39600Y626984D03*
X38300Y633800D03*
X30712Y624971D03*
X29999Y640550D03*
X29819Y634951D03*
X23399Y641649D03*
X23799Y625950D03*
X23499Y633801D03*
X26568Y635950D03*
Y639604D03*
X30999Y656250D03*
Y650550D03*
X23499Y665297D03*
Y649549D03*
X23725Y657471D03*
X26737Y651957D03*
X26999Y656550D03*
X23699Y673150D03*
X23499Y681045D03*
X27687Y667447D03*
Y671101D03*
X27700Y682700D03*
X29999Y694550D03*
X25999Y694870D03*
X23999Y689050D03*
X27299Y783550D03*
X35300Y789375D03*
X32800Y803050D03*
X37416Y799033D03*
X37099Y811350D03*
X26299Y815050D03*
X35559Y795112D03*
X31699Y814350D03*
X37216Y807951D03*
X39649Y822000D03*
X29299Y836901D03*
X40400Y840792D03*
X22500Y853700D03*
X29600Y854000D03*
X23299Y863050D03*
X26662Y861550D03*
X25000Y858100D03*
X20400Y1048300D03*
X20999Y1320550D03*
X23700Y1354600D03*
X20999Y1352050D03*
X25000Y1357742D03*
X22851Y1374169D03*
X22999Y1366050D03*
X23499Y1381550D03*
X25507Y1372045D03*
X25558Y1368447D03*
X32550Y1392777D03*
X27499Y1387550D03*
X24499Y1389663D03*
X28499Y1391050D03*
X32333Y1389383D03*
X30500Y1395500D03*
X33321Y1414755D03*
X29786Y1414858D03*
X23499Y1421550D03*
X23999Y1413550D03*
X32451Y1411468D03*
X28999Y1411550D03*
X32094Y1448448D03*
X28697Y1448296D03*
X36198Y1446749D03*
X27099Y1444350D03*
X30999Y1438050D03*
X27999Y1430050D03*
X23499Y1445050D03*
X22999Y1437050D03*
X23999Y1429050D03*
X33206Y1432352D03*
X30499Y1434550D03*
X30378Y1462518D03*
X33915Y1462681D03*
X29069Y1459379D03*
X36791Y1460866D03*
X23028Y1468579D03*
X23499Y1460550D03*
X22999Y1453050D03*
X34465Y1481683D03*
X30999Y1482050D03*
X32520Y1485092D03*
X28999Y1478050D03*
X23599Y1476350D03*
X23277Y1484050D03*
X34099Y1497550D03*
X30499D03*
X27499Y1495050D03*
X36999Y1494550D03*
X22999Y1500050D03*
X23799Y1508050D03*
X24499Y1492050D03*
X30115Y1511900D03*
X33512Y1512051D03*
X29631Y1533063D03*
X31999Y1517846D03*
Y1521500D03*
X35245Y1522512D03*
X35999Y1514550D03*
X29765Y1515282D03*
X24423Y1527123D03*
X22999Y1515550D03*
X37999Y1530900D03*
X24199Y1523700D03*
X25247Y1546912D03*
X38500Y1534600D03*
X32099Y1535550D03*
X26705Y1534795D03*
X30199Y1545450D03*
X36340Y1558809D03*
X34896Y1555730D03*
X38208Y1569841D03*
X25521Y1563350D03*
X30520Y1572049D03*
X24999Y1569550D03*
X31149Y1568300D03*
X23608Y1572653D03*
X24323Y1559950D03*
X27123Y1572205D03*
X39000Y1573500D03*
X34999Y1595350D03*
X22699Y1594224D03*
X31099Y1595350D03*
X28899Y1613524D03*
X32299D03*
X26999Y1610550D03*
X34884Y1615734D03*
X23499Y1618050D03*
Y1610050D03*
Y1602050D03*
X33599Y1600200D03*
X29499Y1630050D03*
X32199Y1633124D03*
X34816Y1630953D03*
X22999Y1626050D03*
X23499Y1634050D03*
X32663Y1628181D03*
X31999Y1661127D03*
X28600Y1661039D03*
X29626Y1645002D03*
X33026Y1645051D03*
X27499Y1657050D03*
X32989Y1648451D03*
X26785Y1642089D03*
X23499Y1657050D03*
X23999Y1649550D03*
X23415Y1641634D03*
X34699Y1663300D03*
X22999Y1665550D03*
X24244Y1681868D03*
X22864Y1673550D03*
X32700Y1673300D03*
X32494Y1669706D03*
X29100Y1669500D03*
X30500Y1697500D03*
X39900Y1751200D03*
X41200Y1747050D03*
X30274Y1787238D03*
X35675Y1783450D03*
X39324Y1780623D03*
X38094Y1785840D03*
X38878Y1799571D03*
X34599Y1805123D03*
X37699Y1789850D03*
X37574Y1794050D03*
X31811Y1790271D03*
X40478Y1795820D03*
X32099Y1797150D03*
X28550Y1828153D03*
X29899Y1821050D03*
X34099Y1822850D03*
X35876Y1812350D03*
X34129Y1815267D03*
X36532Y1825352D03*
X36399Y1828750D03*
X26099Y1824950D03*
X29599Y1844350D03*
X22099Y1836609D03*
X28123Y1831527D03*
X25999Y1842550D03*
X39699Y1833850D03*
X28799Y1919060D03*
X23030Y1922038D03*
X26765Y1921945D03*
X34799Y1946750D03*
X38703Y1946754D03*
X25499Y1956050D03*
X32999Y1960555D03*
X31799Y1979050D03*
X41999Y200050D03*
X45800Y405200D03*
X61400Y452600D03*
X62497Y474346D03*
X60003Y534150D03*
X59999Y537550D03*
X42867Y548450D03*
X43099Y555850D03*
X46299Y552950D03*
X49799Y559150D03*
X42599Y567850D03*
X47543Y578340D03*
X44959Y575756D03*
X60076Y595777D03*
X55499Y595650D03*
X42202Y608195D03*
X41400Y611500D03*
X47626Y611300D03*
X45701Y607700D03*
X42709Y625607D03*
X41500Y642800D03*
X57800Y634300D03*
X44900Y642800D03*
X47101Y632355D03*
X41500Y635000D03*
X52500D03*
X48999Y642900D03*
X50410Y695801D03*
X50300Y699200D03*
X45100Y793100D03*
X44046Y799554D03*
X46887Y803413D03*
X51100Y806300D03*
X49900Y813200D03*
X56281Y801350D03*
X50399Y836250D03*
X46700Y820100D03*
X54074Y815750D03*
X62405Y820300D03*
X46576Y832951D03*
X48346Y844529D03*
X58699Y837250D03*
X44697Y1546793D03*
X44299Y1550950D03*
X42199Y1601050D03*
X47400Y1721700D03*
X42000Y1740100D03*
X47717Y1731337D03*
X47800Y1740500D03*
X45877Y1728477D03*
Y1724823D03*
X47000Y1737100D03*
X43600D03*
X42275Y1754000D03*
X45799Y1757650D03*
X47440Y1761391D03*
X47400Y1765250D03*
X43751Y1780559D03*
X46999Y1779550D03*
X46199Y1783050D03*
X43925Y1767890D03*
X47604Y1769005D03*
X45782Y1771877D03*
X47499Y1775350D03*
X47899Y1798650D03*
X48049Y1791450D03*
X42199Y1792250D03*
X46799Y1794900D03*
X61009Y1822340D03*
X60449Y1842550D03*
X46499Y1836550D03*
X47166Y1839884D03*
X43099Y1833850D03*
X57999Y1891050D03*
X42499Y1902550D03*
X48499Y1897050D03*
X44368Y1951450D03*
X44399Y1942250D03*
X42532Y1946783D03*
X53999Y1946650D03*
X50299D03*
X46565Y1946703D03*
X45999Y1971450D03*
X50499Y1961550D03*
X43462Y1961160D03*
X78700Y74200D03*
Y70700D03*
X74999Y70550D03*
Y74050D03*
X74499Y80650D03*
Y84050D03*
X65999Y216050D03*
X65000Y455500D03*
X62503Y470946D03*
X66199Y475184D03*
Y469884D03*
X77499Y469550D03*
X62978Y486217D03*
X63067Y489616D03*
X66299Y490784D03*
Y485484D03*
X77999Y493050D03*
X77499Y502550D03*
X65599Y514250D03*
X63499Y538550D03*
Y533050D03*
X68000Y546500D03*
X72500Y545000D03*
X81251Y607249D03*
Y619251D03*
X82499Y627050D03*
X80499Y664550D03*
X74499Y662050D03*
X78499Y654050D03*
X76999Y664550D03*
X81999Y668050D03*
X65500Y817700D03*
X80500Y817000D03*
X76540Y850938D03*
X75500Y847700D03*
X68860Y838706D03*
X69499Y842950D03*
X63499Y843050D03*
X74220Y854150D03*
X72362Y849550D03*
X80699Y1004450D03*
Y1000450D03*
X72000Y1013400D03*
X63273Y1023974D03*
X66499Y1025050D03*
X75500Y1012261D03*
X65486Y1031515D03*
X80000Y1090500D03*
X74500Y1097550D03*
X79899Y1104550D03*
X74399Y1111550D03*
X76999Y1196550D03*
X78499Y1273550D03*
X78613Y1282664D03*
X78779Y1302664D03*
Y1312664D03*
X77758Y1357742D03*
X76000Y1431100D03*
X80043Y1544691D03*
X78600Y1561900D03*
X75000Y1561800D03*
X74400Y1574800D03*
X80400Y1571766D03*
X82329Y1568117D03*
X79000Y1555500D03*
X82429D03*
X74800Y1584700D03*
X78100Y1688189D03*
X74500Y1692000D03*
X74400Y1778100D03*
X80099Y1817250D03*
X80999Y1836550D03*
X93999Y58550D03*
X92900Y66128D03*
X92999Y86128D03*
X97499Y90050D03*
X92999Y96128D03*
X89603Y132629D03*
X86899Y130567D03*
X86599Y126750D03*
X95350Y204550D03*
X89800Y208550D03*
X96900Y510000D03*
X93200Y510500D03*
X95500Y513400D03*
X98900D03*
X83700Y529500D03*
X88999Y538050D03*
X104502Y530552D03*
X86199Y536025D03*
Y532250D03*
X89000Y816500D03*
X90000Y826000D03*
X90500Y831500D03*
X98700Y822550D03*
X98000Y833500D03*
X98700Y842600D03*
X92999Y868550D03*
X92499Y876550D03*
X94999Y901550D03*
X89469Y935588D03*
X85999Y940429D03*
X86399Y937050D03*
X89499Y942850D03*
X102100Y968500D03*
X99000Y965000D03*
X104600Y980500D03*
X90000Y993100D03*
X92600Y996100D03*
X88000Y1008500D03*
X101499Y1072550D03*
X103999Y1216863D03*
X102900Y1196050D03*
X103686Y1223863D03*
X101541Y1262607D03*
X101399Y1292550D03*
X102700Y1321363D03*
X102000Y1341000D03*
X91279Y1340642D03*
X86165Y1339050D03*
X86890Y1342860D03*
X101500Y1352000D03*
X89999Y1348050D03*
X86890Y1346635D03*
X102350Y1344500D03*
Y1348154D03*
X97229Y1373337D03*
X97000Y1377600D03*
X98599Y1491350D03*
X100699Y1471050D03*
X100499Y1479650D03*
X83932Y1544705D03*
X100800Y1536450D03*
X96200Y1550100D03*
X99899Y1539850D03*
X100000Y1546650D03*
X90324Y1538800D03*
X97499Y1554550D03*
X98144Y1534309D03*
X96999Y1558050D03*
X89373Y1561073D03*
X85600Y1561500D03*
X95499Y1665418D03*
X92900Y1678176D03*
X93999Y1703050D03*
X92873Y1708176D03*
X92479Y1718176D03*
X89306Y1746856D03*
X89499Y1753575D03*
X85341Y1752245D03*
X85194Y1748848D03*
X99199Y1761899D03*
X99999Y1753575D03*
X101399Y1784700D03*
X85599Y1797350D03*
X96600Y1826000D03*
X86649Y1817100D03*
X90000Y1827900D03*
X93500D03*
X97999Y1843050D03*
X112999Y124050D03*
X111790Y132259D03*
X115876Y125973D03*
Y130050D03*
X114900Y177900D03*
X122397Y252688D03*
X122799Y249150D03*
X124999Y246050D03*
X123378Y255944D03*
X107499Y497050D03*
X107526Y528996D03*
X109400Y543200D03*
X106000D03*
X105100Y600000D03*
X107000Y604800D03*
X125499Y635550D03*
Y638950D03*
X124999Y643050D03*
X110500Y790200D03*
X111100Y813400D03*
X111200Y799450D03*
X111207Y810001D03*
X110700Y795700D03*
X111089Y806603D03*
X110800Y803100D03*
X110499Y834550D03*
X106749Y934367D03*
X108441Y924705D03*
X108845Y931657D03*
X109099Y928250D03*
X108200Y963600D03*
X107300Y986000D03*
X107400Y992900D03*
X124100Y1047100D03*
X123999Y1054050D03*
Y1050650D03*
X120100Y1053200D03*
X116700Y1063500D03*
X112699Y1058974D03*
X105499Y1080550D03*
X106718Y1076050D03*
X105999Y1085800D03*
X121500Y1083600D03*
X121100Y1075300D03*
X117499Y1079300D03*
X105600Y1069500D03*
X124423Y1077523D03*
Y1081177D03*
X120749Y1093990D03*
X125900Y1091282D03*
X116249Y1102550D03*
X112999Y1103740D03*
X123999Y1102550D03*
X108999Y1102050D03*
X106999Y1194550D03*
X106162Y1205702D03*
X114999Y1210363D03*
X118999Y1219050D03*
X123970Y1221573D03*
X119399Y1298113D03*
X116999Y1288050D03*
X120507Y1317050D03*
X111499Y1311800D03*
X107999Y1307713D03*
X116499Y1328013D03*
X120507Y1328096D03*
X113000Y1341000D03*
X107228Y1330552D03*
X107500Y1340500D03*
X109228Y1337090D03*
Y1333315D03*
X119499Y1339050D03*
X113500Y1352000D03*
X110499Y1365050D03*
X109999Y1355050D03*
X112440Y1358196D03*
X112999Y1361550D03*
X121000Y1364000D03*
X113500Y1344500D03*
Y1348154D03*
X125100Y1366000D03*
X117390Y1426201D03*
X119507Y1423540D03*
X117390Y1429976D03*
X104935Y1440634D03*
X104999Y1444941D03*
X107328Y1438218D03*
X114499Y1432050D03*
X107999Y1448050D03*
X124290Y1469241D03*
X123808Y1465050D03*
X106999Y1454450D03*
X105099Y1459150D03*
X123999Y1473050D03*
X122199Y1476050D03*
X118499Y1694050D03*
X117499Y1706050D03*
X109499Y1712213D03*
X104999Y1708963D03*
X117249Y1712090D03*
X112753Y1716613D03*
X122642Y1704243D03*
X112562Y1720613D03*
X123749Y1711550D03*
X109499Y1743550D03*
X107499Y1736550D03*
X109399Y1739550D03*
X106999Y1746290D03*
X110099Y1759875D03*
X123393Y1870859D03*
X123592Y1874254D03*
X127999Y157050D03*
X147099Y245350D03*
X141499Y427550D03*
Y423050D03*
X135499Y517550D03*
X138999Y524213D03*
X137899Y545451D03*
X138416Y553500D03*
X140940Y561800D03*
X141300Y565900D03*
X127999Y645550D03*
X131400Y644600D03*
X144238Y645356D03*
X128725Y636626D03*
X128479Y640589D03*
X141773Y643013D03*
X144238Y649131D03*
X140499Y649350D03*
X134300Y646400D03*
X141500Y711000D03*
X137100Y1084800D03*
X140800Y1076300D03*
X137481Y1077557D03*
X137477Y1081177D03*
X132499Y1094550D03*
X138600Y1124600D03*
X130699Y1210653D03*
X135850Y1322250D03*
X125999Y1315550D03*
X132999Y1319550D03*
X142667Y1319218D03*
X143700Y1332500D03*
X133475Y1331200D03*
X140000Y1332600D03*
X138000Y1359025D03*
X129000Y1356500D03*
X142999Y1456373D03*
X139815Y1454438D03*
X139235Y1460973D03*
X127898Y1462441D03*
X142900Y1460000D03*
X133090Y1699959D03*
X128749Y1703300D03*
X131999Y1710050D03*
X141500Y1715500D03*
X135499Y1710150D03*
X141999Y1764550D03*
X137999Y1861497D03*
Y1865151D03*
X141101Y1866545D03*
X140999Y1859550D03*
X135999Y1881550D03*
X152499Y149550D03*
X154200Y168500D03*
X149400Y166400D03*
X149999Y243504D03*
Y239729D03*
X157440Y283924D03*
Y303924D03*
Y313924D03*
X165699Y428050D03*
X153459Y427494D03*
X154101Y445550D03*
X159600Y446399D03*
X163549Y517100D03*
X152000Y520813D03*
X163449Y521650D03*
X149000Y537500D03*
X150500Y545000D03*
X160932Y549468D03*
X150750Y540416D03*
X156500Y554000D03*
X157000Y573851D03*
X160824Y577000D03*
X161000Y639100D03*
X158885Y679436D03*
Y689436D03*
X158385Y719436D03*
X159500Y814700D03*
X165499Y815550D03*
X153500Y834600D03*
X154799Y838050D03*
X153499Y918550D03*
X163500Y937100D03*
X160399Y922850D03*
X152500Y960000D03*
X154749Y979149D03*
Y968249D03*
X164700Y1085400D03*
X159000Y1083000D03*
X157700Y1114948D03*
X157600Y1124948D03*
X149562Y1315987D03*
X147400Y1321600D03*
X148024Y1333525D03*
X150338Y1453958D03*
X152499Y1462940D03*
X157440Y1490460D03*
Y1500460D03*
Y1520460D03*
Y1530460D03*
X157400Y1596550D03*
X160200Y1598500D03*
X165575Y1676975D03*
X152633Y1677967D03*
X150999Y1713550D03*
X165900Y1790500D03*
X161900Y1793400D03*
X159421Y1925972D03*
X175999Y82428D03*
X174999Y79050D03*
X175499Y86572D03*
X176399Y94872D03*
X178999Y79050D03*
X186999Y99050D03*
X169999Y129050D03*
X188999Y120800D03*
X173499Y149050D03*
X173500Y166315D03*
X187699Y492850D03*
X173100Y483100D03*
X172499Y491053D03*
X176799Y493850D03*
X188000Y484500D03*
X171722Y513827D03*
X182499Y532550D03*
X168453Y527949D03*
X183499Y556100D03*
X172660Y815731D03*
X169106Y815865D03*
X174199Y841050D03*
X172500Y919294D03*
X172000Y931600D03*
X171100Y935000D03*
X171000Y939500D03*
X172000Y961000D03*
X170250Y948500D03*
X179499Y1275550D03*
X181000Y1365500D03*
X180500Y1369900D03*
X179999Y1655887D03*
X171999Y1662250D03*
X169600Y1682300D03*
X169100Y1685800D03*
X174250Y1694500D03*
X181100Y1682700D03*
X177900Y1690400D03*
X205938Y72528D03*
X201499Y104550D03*
X205499Y105550D03*
X207999Y109550D03*
X197899Y165075D03*
X199900Y554050D03*
X193549Y575875D03*
X200000Y818000D03*
X200539Y890300D03*
X200799Y896600D03*
X198924Y975975D03*
X199149Y1362900D03*
X194700Y1385700D03*
X193500Y1647000D03*
X201499Y1781050D03*
X194049Y1792600D03*
X210605Y70692D03*
X210685Y74725D03*
X215138Y72559D03*
X210634Y66863D03*
X210638Y62959D03*
X225499Y68550D03*
X210738Y82159D03*
Y78459D03*
X230749Y76300D03*
X213499Y104650D03*
X223499Y108150D03*
X218499Y190550D03*
X225298Y281114D03*
X213499Y283864D03*
X214063Y318114D03*
X213400Y355300D03*
X224998Y357049D03*
X220000Y516400D03*
X216999Y686550D03*
X213999Y725050D03*
X230849Y726050D03*
X228999Y765550D03*
X218224Y765325D03*
X211750Y894600D03*
X229562Y904113D03*
X215499Y905550D03*
X221800Y1069300D03*
X221300Y1083238D03*
X229800Y1073600D03*
X226800Y1093400D03*
X224750Y1483950D03*
X229025Y1471576D03*
X227814Y1887513D03*
X223436Y1890465D03*
X229800Y1875700D03*
X218100Y1886400D03*
X214999Y1909550D03*
X213562Y1926113D03*
X220062Y1931113D03*
X213138Y1952703D03*
X210999Y1942050D03*
X246999Y51550D03*
X246499Y42550D03*
X246999Y69550D03*
Y60550D03*
X246499Y86050D03*
Y80550D03*
X245499Y100550D03*
X233749Y110800D03*
X237899Y107050D03*
X247800Y269700D03*
X250300Y275100D03*
X250400Y283100D03*
X239600Y278600D03*
X231800Y318414D03*
X233998Y357549D03*
X239400Y357400D03*
X246800Y677100D03*
X249700Y682500D03*
X238500Y680800D03*
X249800Y689900D03*
X252499Y726050D03*
X241600Y765700D03*
X236800Y765800D03*
X233500Y1066100D03*
X242000Y1066000D03*
X247500Y1085500D03*
X251500Y1136700D03*
X241000Y1469600D03*
X233700Y1481600D03*
X232650Y1493450D03*
X231800Y1887100D03*
X232314Y1890513D03*
X236225Y1883125D03*
X231999Y1914050D03*
X249600Y1896800D03*
X249499Y1928050D03*
X240964Y1934113D03*
X253999Y44050D03*
X253871Y291410D03*
X252935Y319114D03*
X254499Y697700D03*
X255000Y1125700D03*
X256000Y1133000D03*
X269500Y1135500D03*
X261999Y1516050D03*
X257499Y1911050D03*
X264499Y1964050D03*
X291999Y94050D03*
X282800Y87500D03*
X293999Y293550D03*
X284999Y338650D03*
X281499Y338550D03*
X294500Y339000D03*
X279939Y728610D03*
X285499Y745050D03*
X282099D03*
X292999Y743650D03*
X277039Y740300D03*
X282500Y1135000D03*
X295000Y1513000D03*
X289999Y1554650D03*
X293700Y1553351D03*
X276039Y1551300D03*
X283499Y1556050D03*
X279999D03*
X291400Y1561500D03*
X285499Y1930050D03*
X288709Y1948042D03*
X284999Y1947691D03*
X280689Y1942710D03*
X296099Y17100D03*
X305099Y17000D03*
X311400Y17100D03*
X308999Y87050D03*
X297499Y97550D03*
X315800Y100500D03*
X298800Y333000D03*
X301249Y346050D03*
X313039Y352350D03*
X308999Y716450D03*
X315999Y718950D03*
X298000Y743500D03*
X310999Y757050D03*
X314999Y1527550D03*
X297800Y1561600D03*
X312999Y1566050D03*
X310249Y1569800D03*
X313499Y1919050D03*
X310499Y1957050D03*
X315999Y1958550D03*
X317000Y17300D03*
X324800Y89400D03*
X323400Y105200D03*
X326499Y334054D03*
Y337454D03*
X321900Y364600D03*
X327999Y740550D03*
X323249Y749010D03*
X327749Y744050D03*
X324959Y766750D03*
X329499Y801550D03*
X330540Y795509D03*
X320499Y798050D03*
X326500Y1550200D03*
X324000Y1562500D03*
X330300Y1561200D03*
X323999Y1577250D03*
X325221Y1927272D03*
X331622Y1944767D03*
X329999Y1952273D03*
X332103Y1948133D03*
X327100Y1966472D03*
X343499Y31650D03*
X354999Y72050D03*
X343499Y60150D03*
X341499Y63050D03*
Y67110D03*
X357503Y77043D03*
X344520Y406329D03*
X350499Y597300D03*
Y715050D03*
X340699Y1046086D03*
X345499Y1096550D03*
X345424Y1310050D03*
X347324Y1524000D03*
X354500Y1559500D03*
X349774Y1582900D03*
X354000Y1584900D03*
X353499Y1710450D03*
X348499Y1762050D03*
X342999Y1947409D03*
X342621Y1943409D03*
X358999Y61550D03*
X374499Y77550D03*
X365499Y86550D03*
X371999Y549300D03*
X375999Y698550D03*
X371500Y880600D03*
X364499Y1099050D03*
X372999Y1123550D03*
X370149Y1320050D03*
X366149Y1554050D03*
X377900Y1703800D03*
X398799Y36152D03*
X381999Y50150D03*
X382339Y41610D03*
X381999Y53550D03*
X394199Y45050D03*
X381999Y57050D03*
X385999Y78050D03*
X400499Y406329D03*
X394649Y630600D03*
X390999Y1514398D03*
Y1517798D03*
X385499Y1735050D03*
X401499Y80550D03*
X402499Y1476850D03*
X400999Y1575550D03*
X645549Y1815134D03*
X644360Y1819137D03*
X659549Y1810634D03*
X690249Y1805634D03*
X707600Y1815600D03*
X711652Y1822109D03*
X711848Y1825504D03*
X732549Y1806634D03*
X733149Y1798634D03*
X733049Y1814134D03*
X752999Y746842D03*
X757499Y745342D03*
Y1079550D03*
X755600Y1149800D03*
X758499Y1371050D03*
X757999Y1484050D03*
X758199Y1553650D03*
X755000Y1825000D03*
X758499Y1893550D03*
X759114Y1957673D03*
X770999Y302050D03*
Y290050D03*
Y295550D03*
X763571Y295622D03*
X777999Y296050D03*
X772499Y323050D03*
X772873Y326924D03*
X760778Y345050D03*
X768178Y333964D03*
X780499Y330050D03*
X771105Y722789D03*
X766499Y732842D03*
X762999Y734550D03*
X769999Y733050D03*
X771999Y1124550D03*
X772499Y1130050D03*
X779499Y1131050D03*
X767083Y1134550D03*
X768199Y1138590D03*
X774542Y1530050D03*
X774577Y1533796D03*
X771225Y1539474D03*
X767936Y1540336D03*
X774500Y1788000D03*
X770999Y1820550D03*
X771499Y1936550D03*
X767999Y1945173D03*
X764908Y1946592D03*
X771499Y1940050D03*
X785499Y291050D03*
X786978Y298529D03*
X791499Y333050D03*
X789999Y336550D03*
X784499Y334050D03*
X781999Y725550D03*
X788999Y736050D03*
X791999Y733050D03*
X784939Y733550D03*
X792154Y1135926D03*
X784439Y1136550D03*
X789499Y1138050D03*
X784499Y1529050D03*
X784577Y1535628D03*
X791499Y1543550D03*
X793999Y1541050D03*
X788000Y1788000D03*
X793000Y1803500D03*
X795849Y1805500D03*
X791999Y1819050D03*
X783499Y1827050D03*
X802499Y1951550D03*
X800431Y1941193D03*
X785939Y1946800D03*
X792499Y1949050D03*
X794499Y1941050D03*
X782999Y1937050D03*
X802099Y1961950D03*
X820749Y163850D03*
X813249Y163800D03*
X821999Y193116D03*
X809940Y264940D03*
X822100Y261700D03*
Y279500D03*
X816700Y274300D03*
X820600Y664300D03*
X808660Y667540D03*
X813200Y675900D03*
X807000Y1072900D03*
X815400Y1078800D03*
X803199Y1151850D03*
X822100Y1466800D03*
X809960Y1478040D03*
X814700Y1486300D03*
X804899Y1556950D03*
X812000Y1799500D03*
X821249Y1791250D03*
X811000Y1793000D03*
X822499Y1815164D03*
X807000Y1822300D03*
X803500Y1822708D03*
X822700Y1871100D03*
X810900Y1882440D03*
X805900Y1887560D03*
X841499Y135550D03*
X827499Y163550D03*
X839249Y164050D03*
X829917Y216200D03*
X833576Y215432D03*
X837999Y219550D03*
X842499Y280924D03*
X827500Y274500D03*
X836500Y274950D03*
X827499Y313424D03*
X829800Y666650D03*
X835150Y677650D03*
X825700Y1083100D03*
X825800Y1072300D03*
X827700Y1487600D03*
X836625Y1487400D03*
X828500Y1877800D03*
X834799Y1946950D03*
X861999Y146550D03*
X854400Y264600D03*
X847878Y250040D03*
X851278Y249974D03*
X847450Y246666D03*
X850999Y246550D03*
X858478Y274050D03*
X865499Y288050D03*
X851172Y655432D03*
X847772Y655370D03*
X851197Y652032D03*
X847493Y651981D03*
X852696Y671197D03*
X850833Y1061441D03*
X847233Y1061492D03*
X847355Y1058094D03*
X851042Y1058047D03*
X852333Y1077716D03*
X860133Y1084142D03*
X864499Y1128750D03*
X860799Y1358925D03*
X861849Y1376050D03*
X848888Y1466402D03*
X852288Y1466346D03*
X848861Y1462463D03*
X852429Y1462948D03*
X854327Y1477550D03*
X858827Y1485696D03*
X863699Y1501250D03*
X862800Y1712700D03*
X851500Y1821400D03*
X849375Y1824982D03*
X854905Y1825583D03*
X853499Y1871036D03*
X850099Y1871056D03*
X854480Y1867578D03*
X849999Y1867550D03*
X863788Y1866953D03*
X865501Y1858747D03*
X859314Y1891365D03*
X854814Y1883550D03*
X863699Y1906450D03*
X857099Y1917650D03*
X882499Y147050D03*
X867500Y163924D03*
X867576Y159924D03*
X878078Y240103D03*
Y243878D03*
X874928Y238822D03*
X874790Y244748D03*
X871999Y283924D03*
X872136Y273924D03*
X886600Y303924D03*
X868799Y294750D03*
X867899Y321550D03*
X886200Y313924D03*
X868299Y336150D03*
X879750Y570550D03*
X879950Y565050D03*
X878596Y645573D03*
X874999Y644550D03*
X878596Y649348D03*
X875270Y650059D03*
X883083Y979183D03*
X879708Y971892D03*
X878233Y1051095D03*
X877964Y1054485D03*
X874733Y1055792D03*
X874999Y1049550D03*
X872086Y1084948D03*
X871999Y1094948D03*
X871499Y1124948D03*
X872086Y1114948D03*
X866700Y1379796D03*
X866596Y1375796D03*
X878054Y1456450D03*
X877853Y1459991D03*
X874499Y1460550D03*
X874986Y1454983D03*
X872086Y1490460D03*
X871999Y1500460D03*
Y1520460D03*
X872086Y1530460D03*
X867523Y1542821D03*
X867199Y1535150D03*
X886439Y1717600D03*
X873800Y1733600D03*
X879700Y1786300D03*
X879664Y1782213D03*
X866914Y1861840D03*
Y1865615D03*
X871921Y1905972D03*
X871421Y1895972D03*
X872086Y1925972D03*
Y1935972D03*
X901499Y92050D03*
X897555Y90494D03*
X898999Y99050D03*
X902499Y110550D03*
X898999D03*
X907499Y131800D03*
X896999Y141550D03*
X902999Y556050D03*
X900499Y962100D03*
X900999Y979050D03*
X889800Y1711500D03*
X923761Y85550D03*
X928561Y95181D03*
X928428Y83714D03*
X928508Y87747D03*
X928561Y91481D03*
X928457Y79885D03*
X928461Y75981D03*
X916499Y115050D03*
X926999D03*
Y122050D03*
X910999Y124550D03*
X916499Y172550D03*
X922049Y574375D03*
Y978575D03*
X921549Y1788475D03*
X917499Y1796550D03*
X932961Y85581D03*
X943499Y82550D03*
X930999Y115550D03*
X938499D03*
X946899Y122550D03*
X937999Y122050D03*
X934499Y118750D03*
X939549Y175175D03*
X961499Y93350D03*
X958999Y96050D03*
X961499Y100050D03*
X966499Y552050D03*
X965999Y954550D03*
X965150Y1639500D03*
X961702Y1636102D03*
X969600Y1638300D03*
X967600Y1651100D03*
X971558Y1646500D03*
X981200Y1618002D03*
X986400Y1639302D03*
X987100Y1624900D03*
X981200Y1625800D03*
X990425Y1633898D03*
X987029Y1634075D03*
X977500Y1660500D03*
X989502Y1646000D03*
X988800Y1658300D03*
X981500Y1653000D03*
X980800Y1659600D03*
X982050Y1649302D03*
X978000Y1668000D03*
X989000Y1663802D03*
X987200Y1675600D03*
X989900Y1678800D03*
X974000Y1670700D03*
X984211Y1667500D03*
G54D90*
X882600Y1734200D03*
G54D28*
X34599Y1592050D03*
X27030Y1928638D03*
X23030D03*
X19999Y1968250D03*
X31999Y1975750D03*
Y1968250D03*
X42700Y412300D03*
X49499Y1905250D03*
X83000Y1551700D03*
X79000D03*
X75000Y1568600D03*
X79000D03*
X97499Y1090250D03*
X101999D03*
X100700Y1111300D03*
X116499Y1227313D03*
Y1324813D03*
X120507Y1324896D03*
X116749Y1513550D03*
X112599D03*
X131999Y1227813D03*
X127499D03*
X162999Y447313D03*
X166999D03*
X150999Y443813D03*
X185999Y499850D03*
X181899D03*
X185999Y845813D03*
X176499Y836813D03*
X174499Y1653063D03*
X197499Y101250D03*
X205499D03*
X190499Y845813D03*
X205999Y901713D03*
X209999D03*
X226800Y1090000D03*
X225499Y1502750D03*
X231000Y1883900D03*
X247500Y1081950D03*
X236100Y1897300D03*
X280499Y345250D03*
X284999D03*
X281499Y751750D03*
X285499D03*
X278499Y1562750D03*
X282499D03*
X284358Y1955028D03*
X288358D03*
X399999Y42750D03*
X640049Y1807334D03*
Y1796334D03*
X649049Y1814334D03*
X655549Y1818834D03*
X706549Y1801334D03*
X712549Y1812034D03*
X744049Y1806334D03*
Y1798834D03*
Y1813834D03*
X833999Y208250D03*
X829499D03*
X827500Y270900D03*
X825700Y1079200D03*
X827700Y1484100D03*
X889700Y1708100D03*
X920499Y111750D03*
X912499D03*
X936499D03*
X948499D03*
G54D73*
X180199Y95050D03*
X878601Y1693850D03*
X900699Y115050D03*
X890600Y1716200D03*
X965400Y1660500D03*
Y1665500D03*
G54D82*
X241500Y1085625D03*
X234000Y1089500D03*
Y1081750D03*
G54D55*
X116249Y1093990D03*
Y1096550D03*
Y1099110D03*
X109749D03*
Y1093990D03*
X117249Y1720110D03*
Y1717550D03*
Y1714990D03*
X123749D03*
Y1720110D03*
X176999Y490913D03*
Y488353D03*
Y485793D03*
X183499D03*
Y490913D03*
X315248Y339174D03*
Y334054D03*
X316749Y746110D03*
Y740990D03*
X313249Y1554490D03*
Y1559610D03*
X321748Y334054D03*
Y336614D03*
Y339174D03*
X323249Y740990D03*
Y743550D03*
Y746110D03*
X319749Y1554490D03*
Y1557050D03*
Y1559610D03*
X326971Y1944349D03*
Y1946909D03*
Y1949469D03*
X320471D03*
Y1944349D03*
X347749Y67110D03*
Y64550D03*
Y61990D03*
X354249D03*
Y67110D03*
X387749Y50990D03*
X394249D03*
X387749Y56110D03*
Y53550D03*
X394249Y56110D03*
X761228Y323864D03*
Y328984D03*
X760446Y724822D03*
Y729942D03*
X760583Y1131452D03*
Y1126332D03*
X760064Y1942273D03*
Y1937153D03*
X767728Y323864D03*
Y326424D03*
Y328984D03*
X766946Y724822D03*
Y727382D03*
Y729942D03*
X767083Y1126332D03*
Y1128892D03*
Y1131452D03*
X770077Y1531236D03*
X763577D03*
X770077Y1533796D03*
Y1536356D03*
X763577D03*
X766564Y1937153D03*
Y1939713D03*
Y1942273D03*
G54D46*
X71773Y209631D03*
Y206431D03*
X66023Y209631D03*
Y206431D03*
X71773Y615143D03*
Y611943D03*
X66023Y615143D03*
Y611943D03*
X71773Y1020655D03*
Y1017455D03*
X66023Y1020655D03*
Y1017455D03*
X71773Y1426167D03*
Y1422967D03*
X66023Y1426167D03*
Y1422967D03*
X71773Y1828479D03*
X66023D03*
X71773Y1831679D03*
X66023D03*
X164448Y160447D03*
Y163647D03*
Y565959D03*
Y569159D03*
Y971471D03*
Y974671D03*
Y1376983D03*
Y1380183D03*
Y1782494D03*
Y1785694D03*
X170198Y160447D03*
Y163647D03*
Y565959D03*
Y569159D03*
Y971471D03*
Y974671D03*
Y1376983D03*
Y1380183D03*
Y1782494D03*
Y1785694D03*
X892794Y160447D03*
Y163647D03*
X898544Y160447D03*
Y163647D03*
X892794Y565959D03*
Y569159D03*
X898544Y565959D03*
Y569159D03*
X892794Y971471D03*
Y974671D03*
X898544Y971471D03*
Y974671D03*
X892794Y1376983D03*
Y1380183D03*
X898544Y1376983D03*
Y1380183D03*
X892794Y1782494D03*
Y1785694D03*
X898544Y1782494D03*
Y1785694D03*
G54D64*
X140940Y550300D03*
X143500D03*
X146060D03*
Y557700D03*
X143500D03*
X140940D03*
X181340Y937100D03*
X183900D03*
X186460D03*
Y944500D03*
X183900D03*
X181340D03*
X172240Y1678400D03*
X174800D03*
X177360D03*
Y1685800D03*
X174800D03*
X172240D03*
X242040Y275100D03*
X244600D03*
X247160D03*
Y282500D03*
X244600D03*
X242040D03*
X241440Y682500D03*
X244000D03*
X246560D03*
Y689900D03*
X244000D03*
X241440D03*
X315939Y352350D03*
X318499D03*
X321059D03*
Y359750D03*
X318499D03*
X315939D03*
X316939Y759350D03*
X319499D03*
X322059D03*
Y766750D03*
X319499D03*
X316939D03*
X315939Y1569850D03*
X318499D03*
X321059D03*
Y1577250D03*
X318499D03*
X315939D03*
X319080Y1959072D03*
X321640D03*
X324200D03*
Y1966472D03*
X321640D03*
X319080D03*
G54D91*
X984808Y1447976D03*
Y1456976D03*
Y1460976D03*
Y1487976D03*
Y1496976D03*
Y1500976D03*
Y1526976D03*
Y1536976D03*
Y1540976D03*
Y1566976D03*
Y1577976D03*
Y1582976D03*
X997607Y1605976D03*
G54D19*
X18199Y1956050D03*
X36199Y1918050D03*
X101145Y525988D03*
Y522488D03*
X99745Y931489D03*
Y927989D03*
X100528Y1336952D03*
Y1333452D03*
X104028Y1361952D03*
Y1358452D03*
X101699Y1743050D03*
Y1739550D03*
X103699Y1764050D03*
Y1767550D03*
X105199Y129550D03*
Y126050D03*
Y145050D03*
Y141550D03*
X105145Y550988D03*
Y547488D03*
X104745Y956489D03*
Y952989D03*
X129150Y1081100D03*
Y1077600D03*
X179699Y99050D03*
X178399Y524850D03*
X697749Y1813134D03*
X835699Y167550D03*
X836199Y1788050D03*
X903699Y124550D03*
X951199Y96050D03*
G54D37*
X62499Y733150D03*
Y759950D03*
X86499Y1147150D03*
Y1173950D03*
X104000Y1571600D03*
Y1598400D03*
X151499Y1634087D03*
Y1660887D03*
X262998Y333214D03*
Y360014D03*
X263999Y738650D03*
Y765450D03*
X262999Y1549650D03*
Y1576450D03*
Y1946150D03*
Y1972950D03*
X339499Y24650D03*
Y51450D03*
X815499Y326150D03*
Y352950D03*
X813499Y729150D03*
Y755950D03*
Y1131650D03*
Y1158450D03*
X816171Y1536904D03*
Y1563704D03*
X814999Y1940650D03*
Y1967450D03*
G54D83*
X242299Y1117109D03*
Y1128271D03*
G54D47*
X79200Y752050D03*
Y744150D03*
X103100Y1150250D03*
Y1158150D03*
X87300Y1574250D03*
Y1582150D03*
X134900Y1639550D03*
Y1647450D03*
X246400Y350050D03*
Y342150D03*
X247400Y751150D03*
Y759050D03*
X246400Y1566550D03*
Y1558650D03*
Y1955150D03*
Y1963050D03*
X322900Y23650D03*
Y31550D03*
X832100Y345250D03*
Y337350D03*
X830100Y746050D03*
Y738150D03*
Y1150850D03*
Y1142950D03*
X832800Y1554750D03*
Y1546850D03*
X831600Y1955550D03*
Y1963450D03*
G54D38*
X63999Y1871050D03*
Y1882050D03*
X72999Y1871550D03*
Y1882550D03*
X102999Y1171550D03*
Y1182550D03*
X111999Y1171550D03*
X120999D03*
X111999Y1182550D03*
X120999D03*
X120499Y1233613D03*
X111499D03*
X120499Y1244613D03*
X111499D03*
Y1266613D03*
Y1277613D03*
X126199Y1638013D03*
X117500Y1638000D03*
X108799Y1638013D03*
X126199Y1649013D03*
X117500Y1649000D03*
X108799Y1649013D03*
X112499Y1671613D03*
Y1682613D03*
X140999Y453113D03*
Y464113D03*
X146499Y486613D03*
Y497613D03*
X129900Y1171500D03*
Y1182500D03*
X129499Y1233613D03*
X132700Y1254400D03*
X129499Y1244613D03*
X132700Y1265400D03*
X133999Y1659613D03*
Y1670613D03*
X158999Y453113D03*
X149999D03*
X167900Y453100D03*
X158999Y464113D03*
X149999D03*
X167900Y464100D03*
X169499Y885113D03*
Y896113D03*
X169999Y112550D03*
X178999D03*
X169999Y123550D03*
X178999D03*
X187999Y851613D03*
X178999D03*
X169999D03*
X187999Y862613D03*
X178999D03*
X169999D03*
X191499Y873113D03*
Y884113D03*
X225900Y307400D03*
Y318400D03*
X228998Y340614D03*
X220298D03*
X228998Y351614D03*
X220298D03*
X225499Y726050D03*
Y715050D03*
X229999Y749550D03*
X221299D03*
X229999Y760550D03*
X221299D03*
X224300Y1130200D03*
Y1119200D03*
X224999Y1524550D03*
Y1535550D03*
X229000Y1568100D03*
Y1557100D03*
X220300Y1568100D03*
Y1557100D03*
X225814Y1931113D03*
Y1920113D03*
X220300Y1953600D03*
X229000D03*
X220300Y1964600D03*
X229000D03*
X246498Y319114D03*
Y330114D03*
X237698Y340614D03*
Y351614D03*
X246499Y726050D03*
Y737050D03*
X238699Y749550D03*
Y760550D03*
X246499Y1535550D03*
Y1546550D03*
X237700Y1568100D03*
Y1557100D03*
X246314Y1934113D03*
Y1945113D03*
X237700Y1953600D03*
Y1964600D03*
X296099Y22113D03*
Y33113D03*
X314099Y22113D03*
Y33113D03*
X305099Y22113D03*
Y33113D03*
X300999Y55613D03*
Y66613D03*
X322499Y43613D03*
Y54613D03*
X832978Y313424D03*
Y324424D03*
X840800Y346800D03*
Y335800D03*
X830499Y715550D03*
Y726550D03*
X838796Y747582D03*
Y736582D03*
X830499Y1119550D03*
Y1130550D03*
X838833Y1152392D03*
Y1141392D03*
X833827Y1523796D03*
Y1534796D03*
X841500Y1556300D03*
Y1545300D03*
X832499Y1930050D03*
X840400Y1954000D03*
X832499Y1941050D03*
X840400Y1965000D03*
X846999Y135550D03*
Y124550D03*
X850999Y301550D03*
Y312550D03*
X849500Y346800D03*
Y335800D03*
X858200Y346800D03*
Y335800D03*
X848696Y702882D03*
Y713882D03*
X847496Y747582D03*
Y736582D03*
X856196Y747582D03*
Y736582D03*
X848413Y1107613D03*
Y1118613D03*
X847533Y1152392D03*
Y1141392D03*
X856233Y1152392D03*
Y1141392D03*
X850827Y1512296D03*
Y1523296D03*
X850200Y1556300D03*
Y1545300D03*
X858900Y1556300D03*
Y1545300D03*
X850314Y1929113D03*
Y1918113D03*
X849100Y1954000D03*
X857800D03*
X849100Y1965000D03*
X857800D03*
X896999Y136550D03*
Y125550D03*
G54D29*
X30499Y1592060D03*
X31999Y1922250D03*
X23999Y1968250D03*
X27999D03*
X46800Y412300D03*
X42900Y604800D03*
X103999Y1472000D03*
X119499Y1109750D03*
X109499Y1201813D03*
X105499D03*
X106999Y1227313D03*
X111999D03*
X111499Y1472000D03*
X115599Y1471950D03*
X141499Y443813D03*
X146499D03*
X136000Y532200D03*
X135999Y1706750D03*
X131999D03*
X159199Y520550D03*
X167199D03*
X166499Y812313D03*
X167499Y836813D03*
X152600Y1684600D03*
X174999Y74750D03*
X185499Y120750D03*
X174199Y520550D03*
X170499Y812313D03*
X172499Y836813D03*
X184600Y1376500D03*
X180500D03*
X201499Y101250D03*
X209499D03*
X192800Y1654500D03*
X217499Y101250D03*
X223436Y1897065D03*
X644049Y1807334D03*
Y1796334D03*
X710549Y1801334D03*
X708549Y1812034D03*
X754978Y339124D03*
X753196Y738582D03*
X755499Y1143750D03*
X756327Y1546496D03*
X753314Y1951913D03*
X816499Y162750D03*
X814999Y1783750D03*
X823999Y162750D03*
X831499D03*
X826100Y670100D03*
X833499Y1783750D03*
X824499D03*
X828000Y1884700D03*
X900499Y88250D03*
X903499Y131750D03*
X924499Y111750D03*
X916499D03*
X932499D03*
X944499D03*
X940499D03*
X952499D03*
G54D92*
X997608Y1452322D03*
Y1492322D03*
Y1532322D03*
Y1572322D03*
G54D65*
X144099Y1247113D03*
X170899D03*
X179100Y461000D03*
X205900D03*
X203099Y859613D03*
X229899D03*
G54D56*
X117999Y1143550D03*
Y1162050D03*
G54D74*
X185799Y95050D03*
X884201Y1693850D03*
X906299Y115050D03*
X896200Y1716200D03*
X971000Y1660500D03*
Y1665500D03*
G54D39*
X43999Y1964750D03*
X103499Y1297813D03*
X104999Y1702063D03*
X123999Y1734813D03*
X138999Y517313D03*
X142667Y1306460D03*
X132999Y1306813D03*
X137504Y1735523D03*
X161999Y915813D03*
X182499Y71250D03*
X194500Y499200D03*
X215900Y896900D03*
X292999Y86313D03*
X295500Y329200D03*
X298000Y735700D03*
X297000Y1549800D03*
X296858Y1944028D03*
X369300Y72300D03*
X389500Y72200D03*
X693549Y1813334D03*
X870201Y1709850D03*
X907999Y84750D03*
G54D48*
X67999Y774150D03*
Y798950D03*
X133521Y107677D03*
Y132477D03*
X154521Y107677D03*
Y132477D03*
X861999Y114650D03*
Y139450D03*
X882499Y114650D03*
Y139450D03*
G54D66*
X139600Y1281825D03*
X232500Y1128175D03*
X245800Y299775D03*
X246300Y706675D03*
X244800Y1516175D03*
X247300Y1911175D03*
G54D93*
X997607Y1602322D03*
G54D84*
X666399Y1806699D03*
Y1808664D03*
Y1810634D03*
Y1812604D03*
Y1814569D03*
X682699Y1806699D03*
Y1814569D03*
Y1812604D03*
Y1810634D03*
Y1808664D03*
G54D75*
X210676Y72528D03*
X928499Y85550D03*
G54D57*
X105749Y1255113D03*
X124249D03*
X105749Y1288613D03*
X124249D03*
X106749Y1659613D03*
X125249D03*
X107249Y1693113D03*
X125749D03*
X140749Y474550D03*
X140999Y508113D03*
X159249Y474550D03*
X159499Y508113D03*
X164249Y873113D03*
Y906613D03*
X182749Y873113D03*
Y906613D03*
X219248Y296614D03*
Y329614D03*
X219749Y703050D03*
X219249Y737050D03*
X219250Y1103100D03*
X218050Y1513400D03*
X219249Y1546050D03*
X219684Y1906687D03*
X218184Y1942987D03*
X237748Y296614D03*
Y329614D03*
X238249Y703050D03*
X237749Y737050D03*
X237750Y1103100D03*
X236550Y1513400D03*
X237749Y1546050D03*
X238184Y1906687D03*
X236684Y1942987D03*
X295249Y43613D03*
Y77113D03*
X313749Y43613D03*
Y77113D03*
X837978Y290124D03*
X841478Y323924D03*
X836196Y691182D03*
X839249Y724550D03*
X836333Y1096692D03*
X839749Y1129550D03*
X838077Y1501596D03*
X842577Y1534296D03*
X838314Y1907313D03*
X841249Y1940550D03*
X856478Y290124D03*
X859978Y323924D03*
X854696Y691182D03*
X857749Y724550D03*
X854833Y1096692D03*
X858249Y1129550D03*
X856577Y1501596D03*
X861077Y1534296D03*
X856814Y1907313D03*
X859749Y1940550D03*
G54D67*
X139600Y1287788D03*
X232500Y1122212D03*
X245800Y293812D03*
X246300Y700712D03*
X244800Y1510212D03*
X247300Y1905212D03*
G54D58*
X120418Y1275613D03*
X121418Y1680113D03*
X131580Y1275613D03*
X132580Y1680113D03*
X155158Y495113D03*
X166320D03*
X178418Y893613D03*
X189580D03*
X233917Y309614D03*
X245079D03*
X234418Y716550D03*
X245580D03*
X233918Y1526050D03*
X245080D03*
X235843Y1920987D03*
X247005D03*
X309918Y64113D03*
X321080D03*
X842119Y303424D03*
X830957D03*
X840037Y704382D03*
X828875D03*
X840174Y1109892D03*
X829012D03*
X841708Y1514296D03*
X830546D03*
X841655Y1920613D03*
X830493D03*
G54D49*
X84999Y1121050D03*
Y1126050D03*
Y1131050D03*
Y1136050D03*
X104999Y1131050D03*
Y1126050D03*
Y1121050D03*
Y1136050D03*
X138499Y1216113D03*
Y1221113D03*
Y1226113D03*
Y1231113D03*
X158499Y1216113D03*
Y1231113D03*
Y1226113D03*
Y1221113D03*
X168499Y1625613D03*
Y1630613D03*
Y1635613D03*
Y1640613D03*
X173999Y430050D03*
Y435050D03*
Y440050D03*
Y445050D03*
X188499Y1635613D03*
Y1630613D03*
Y1625613D03*
Y1640613D03*
X193999Y430050D03*
Y445050D03*
Y440050D03*
Y435050D03*
X198499Y828613D03*
Y833613D03*
Y838613D03*
Y843613D03*
X218499Y833613D03*
Y828613D03*
Y843613D03*
Y838613D03*
X253998Y295114D03*
Y300114D03*
Y305114D03*
Y310114D03*
X254499Y701550D03*
Y706550D03*
Y711550D03*
Y716550D03*
X252999Y1513050D03*
Y1518050D03*
Y1523050D03*
Y1528050D03*
X273998Y305114D03*
Y300114D03*
Y295114D03*
Y310114D03*
X274499Y706550D03*
Y701550D03*
Y716550D03*
Y711550D03*
X272999Y1528050D03*
Y1523050D03*
Y1518050D03*
Y1513050D03*
X255777Y1917191D03*
Y1922191D03*
Y1927191D03*
Y1932191D03*
X279999Y351050D03*
Y356050D03*
Y361050D03*
Y366050D03*
X280999Y757550D03*
Y762550D03*
Y767550D03*
Y772550D03*
X279999Y1568550D03*
Y1573550D03*
Y1578550D03*
Y1583550D03*
X275777Y1932191D03*
Y1927191D03*
Y1922191D03*
Y1917191D03*
X279777Y1961191D03*
Y1966191D03*
Y1971191D03*
Y1976191D03*
X299999Y366050D03*
Y361050D03*
Y356050D03*
Y351050D03*
X300999Y767550D03*
Y762550D03*
Y757550D03*
Y772550D03*
X299999Y1573550D03*
Y1568550D03*
Y1583550D03*
Y1578550D03*
X299777Y1976191D03*
Y1971191D03*
Y1966191D03*
Y1961191D03*
X356499Y21550D03*
Y26550D03*
Y31550D03*
Y36550D03*
X376499Y31550D03*
Y26550D03*
Y21550D03*
Y36550D03*
X777978Y341924D03*
Y346924D03*
Y351924D03*
Y356924D03*
X776696Y742382D03*
Y747382D03*
Y752382D03*
Y757382D03*
X776833Y1143892D03*
Y1148892D03*
Y1153892D03*
Y1158892D03*
X779327Y1548796D03*
Y1553796D03*
Y1558796D03*
Y1563796D03*
X776814Y1954713D03*
Y1959713D03*
Y1964713D03*
Y1969713D03*
X802873Y292471D03*
Y297471D03*
Y302471D03*
Y307471D03*
X797978Y346924D03*
Y341924D03*
Y356924D03*
Y351924D03*
X800831Y696853D03*
Y701853D03*
Y706853D03*
Y711853D03*
X796696Y747382D03*
Y742382D03*
Y757382D03*
Y752382D03*
X800841Y1101216D03*
Y1106216D03*
Y1111216D03*
Y1116216D03*
X796833Y1148892D03*
Y1143892D03*
Y1158892D03*
Y1153892D03*
X802245Y1503722D03*
Y1508722D03*
Y1513722D03*
Y1518722D03*
X799327Y1553796D03*
Y1548796D03*
Y1563796D03*
Y1558796D03*
X801436Y1910365D03*
Y1915365D03*
Y1920365D03*
Y1925365D03*
X796814Y1954713D03*
Y1969713D03*
Y1964713D03*
Y1959713D03*
X822873Y302471D03*
Y297471D03*
Y292471D03*
Y307471D03*
X820831Y706853D03*
Y701853D03*
Y696853D03*
Y711853D03*
X820841Y1106216D03*
Y1101216D03*
Y1116216D03*
Y1111216D03*
X822245Y1508722D03*
Y1503722D03*
Y1518722D03*
Y1513722D03*
X821436Y1910365D03*
Y1925365D03*
Y1920365D03*
Y1915365D03*
G54D76*
X201033Y62685D03*
Y64654D03*
Y66622D03*
Y68591D03*
Y70559D03*
Y72528D03*
Y74497D03*
Y76465D03*
Y78434D03*
Y80402D03*
Y82371D03*
X220319Y72528D03*
Y70559D03*
Y68591D03*
Y66622D03*
Y64654D03*
Y62685D03*
Y82371D03*
Y80402D03*
Y78434D03*
Y76465D03*
Y74497D03*
X918856Y75707D03*
Y77676D03*
Y79644D03*
Y81613D03*
Y83581D03*
Y85550D03*
Y87519D03*
Y89487D03*
Y91456D03*
Y93424D03*
Y95393D03*
X938142Y93424D03*
Y91456D03*
Y89487D03*
Y87519D03*
Y85550D03*
Y83581D03*
Y81613D03*
Y79644D03*
Y77676D03*
Y75707D03*
Y95393D03*
G54D85*
X753949Y1801294D03*
Y1803854D03*
Y1806414D03*
Y1808974D03*
X776149Y1806414D03*
Y1803854D03*
Y1801294D03*
Y1808974D03*
G54D94*
X1005807Y1636102D03*
Y1631102D03*
Y1626102D03*
Y1621102D03*
Y1661102D03*
Y1656102D03*
Y1651102D03*
Y1646102D03*
Y1641102D03*
Y1676102D03*
Y1671102D03*
Y1666102D03*
G54D95*
G01X-87137Y-139897D02*
Y-107897D01*
G01X-75137Y-123897D02*
G02I-12000J0D01*
G01X-80287D02*
G02I-6850J0D01*
G01X-71137D02*
X-103137D01*
G01X-71137Y-139897D02*
Y-219897D01*
G01D02*
X1129963D01*
G01X-71137Y-175397D02*
X1129963D01*
G01X-71137Y-139897D02*
X1129963D01*
G01X23499Y381831D02*
X21589Y379921D01*
X12575D01*
X12569Y379915D01*
G01X23399Y389679D02*
X21346Y391732D01*
X12575D01*
X12569Y391726D01*
G01X23499Y397579D02*
X21589Y395669D01*
X12575D01*
X12569Y395663D01*
G01Y407474D02*
X12575Y407480D01*
X22003D01*
G01X23399Y429051D02*
X21346Y431104D01*
X12575D01*
X12569Y431098D01*
G01X23499Y436951D02*
X21589Y435041D01*
X12575D01*
X12569Y435035D01*
G01X23399Y444799D02*
X21346Y446852D01*
X12575D01*
X12569Y446846D01*
G01X23499Y452699D02*
X21589Y450789D01*
X12575D01*
X12569Y450783D01*
G01X23399Y460547D02*
X21346Y462600D01*
X12575D01*
X12569Y462594D01*
G01X23499Y468447D02*
X21589Y466537D01*
X12575D01*
X12569Y466531D01*
G01X23399Y492043D02*
X21346Y494096D01*
X12575D01*
X12569Y494090D01*
G01X23399Y476295D02*
X21346Y478348D01*
X12575D01*
X12569Y478342D01*
G01X23499Y484195D02*
X21589Y482285D01*
X12575D01*
X12569Y482279D01*
G01X23499Y499943D02*
X21589Y498033D01*
X12575D01*
X12569Y498027D01*
G01X23399Y507791D02*
X21346Y509844D01*
X12575D01*
X12569Y509838D01*
G01X23499Y515691D02*
X21589Y513781D01*
X12575D01*
X12569Y513775D01*
G01X23399Y523539D02*
X21346Y525592D01*
X12575D01*
X12569Y525586D01*
G01X23499Y531439D02*
X21589Y529529D01*
X12575D01*
X12569Y529523D01*
G01X22800Y539600D02*
X21060Y541340D01*
X12575D01*
X12569Y541334D01*
G01X22999Y565550D02*
X22411Y564962D01*
X12575D01*
X12569Y564956D01*
G01X22699Y577950D02*
X21522Y576773D01*
X12575D01*
X12569Y576767D01*
G01X23499Y618053D02*
X21589Y616143D01*
X12575D01*
X12569Y616137D01*
G01X23799Y625950D02*
X21795Y627954D01*
X12575D01*
X12569Y627948D01*
G01X23499Y633801D02*
X21589Y631891D01*
X12575D01*
X12569Y631885D01*
G01X23399Y641649D02*
X21346Y643702D01*
X12575D01*
X12569Y643696D01*
G01X23499Y649549D02*
X21589Y647639D01*
X12575D01*
X12569Y647633D01*
G01X23725Y657471D02*
X21746Y659450D01*
X12575D01*
X12569Y659444D01*
G01X23499Y665297D02*
X21589Y663387D01*
X12575D01*
X12569Y663381D01*
G01X23699Y673150D02*
X21651Y675198D01*
X12575D01*
X12569Y675192D01*
G01X23499Y681045D02*
X21589Y679135D01*
X12575D01*
X12569Y679129D01*
G01X25986Y694883D02*
X22049Y698820D01*
X12575D01*
X12569Y698814D01*
G01X25986Y694883D02*
X12575D01*
X12569Y694877D01*
G01X23999Y689050D02*
X22103Y690946D01*
X12575D01*
X12569Y690940D01*
G01X22500Y853700D02*
X21168Y852368D01*
X12573D01*
X12560Y852381D01*
G01X22999Y1366050D02*
X21122Y1364173D01*
X12575D01*
X12569Y1364167D01*
G01X22851Y1374169D02*
X21036Y1375984D01*
X12575D01*
X12569Y1375978D01*
G01X23499Y1381550D02*
Y1381199D01*
X22221Y1379921D01*
X12575D01*
X12569Y1379915D01*
G01X24499Y1389663D02*
X22430Y1391732D01*
X12575D01*
X12569Y1391726D01*
G01X23999Y1413550D02*
X22193Y1415356D01*
X12575D01*
X12569Y1415350D01*
G01X23499Y1421550D02*
Y1420999D01*
X21793Y1419293D01*
X12575D01*
X12569Y1419287D01*
G01X23999Y1429050D02*
X21945Y1431104D01*
X12575D01*
X12569Y1431098D01*
G01X22999Y1437050D02*
X20990Y1435041D01*
X12575D01*
X12569Y1435035D01*
G01X23499Y1445050D02*
X21697Y1446852D01*
X12575D01*
X12569Y1446846D01*
G01X22999Y1453050D02*
Y1452799D01*
X20989Y1450789D01*
X12575D01*
X12569Y1450783D01*
G01X23499Y1460550D02*
X21350Y1462699D01*
X21251Y1462600D01*
X12575D01*
X12569Y1462594D01*
G01X23028Y1468579D02*
X20986Y1466537D01*
X12575D01*
X12569Y1466531D01*
G01X23599Y1476350D02*
X21601Y1478348D01*
X12575D01*
X12569Y1478342D01*
G01X23277Y1484050D02*
X21512Y1482285D01*
X12575D01*
X12569Y1482279D01*
G01X24499Y1492050D02*
X22453Y1494096D01*
X12575D01*
X12569Y1494090D01*
G01X22999Y1500050D02*
X20982Y1498033D01*
X12575D01*
X12569Y1498027D01*
G01X23799Y1508050D02*
X22005Y1509844D01*
X12575D01*
X12569Y1509838D01*
G01X22999Y1515550D02*
X21230Y1513781D01*
X12575D01*
X12569Y1513775D01*
G01X24423Y1527123D02*
X23600Y1526300D01*
X23121D01*
X22413Y1525592D01*
X12575D01*
X12569Y1525586D01*
G01X25247Y1546912D02*
X22945Y1549214D01*
X12575D01*
X12569Y1549208D01*
G01X24323Y1559950D02*
X23248Y1561025D01*
X12575D01*
X12569Y1561019D01*
G01X23499Y1602050D02*
X21844Y1600395D01*
X12575D01*
X12569Y1600389D01*
G01X23499Y1610050D02*
X21244Y1612305D01*
X21145Y1612206D01*
X12575D01*
X12569Y1612200D01*
G01X23499Y1618050D02*
X21592Y1616143D01*
X12575D01*
X12569Y1616137D01*
G01X22999Y1626050D02*
X21095Y1627954D01*
X12575D01*
X12569Y1627948D01*
G01X23499Y1634050D02*
Y1633399D01*
X21991Y1631891D01*
X12575D01*
X12569Y1631885D01*
G01X23415Y1641634D02*
X21347Y1643702D01*
X12575D01*
X12569Y1643696D01*
G01X23999Y1649550D02*
X22088Y1647639D01*
X12575D01*
X12569Y1647633D01*
G01X23499Y1657050D02*
X21099Y1659450D01*
X12575D01*
X12569Y1659444D01*
G01X22999Y1665550D02*
X20836Y1663387D01*
X12575D01*
X12569Y1663381D01*
G01X22864Y1673550D02*
X21216Y1675198D01*
X12575D01*
X12569Y1675192D01*
G01X24244Y1681868D02*
X21511Y1679135D01*
X12575D01*
X12569Y1679129D01*
G01X24244Y1681868D02*
X23040Y1683072D01*
X12575D01*
X12569Y1683066D01*
G01X22099Y1836609D02*
X22088Y1836620D01*
X12573D01*
X12560Y1836633D01*
G01X18249Y1940050D02*
X14999D01*
G01X18249Y1944050D02*
X15099D01*
G01X18249Y1936050D02*
X14999D01*
G01X5303Y1947050D02*
X11999D01*
X12999Y1948050D01*
X18249D01*
G01X5303Y1947050D02*
Y1960429D01*
X17724Y1972850D01*
X20799D01*
G01X18249Y1956050D02*
X18549Y1956350D01*
Y1957377D01*
X20422Y1959250D01*
X23076D01*
X23576Y1958750D01*
X23621D01*
X24499Y1957872D01*
Y1957827D01*
X24949Y1957377D01*
Y1956600D01*
X25499Y1956050D01*
G01X18249Y1952050D02*
X11807D01*
X11703Y1951946D01*
G01X19999Y1968300D02*
X19249D01*
X17299Y1966350D01*
Y1961250D01*
X17499Y1961050D01*
G01X22003Y407480D02*
X23799Y405684D01*
G01X34749Y611550D02*
X37999D01*
G01X34749Y616050D02*
Y619023D01*
X34976Y619250D01*
G01X25986Y694883D02*
X25999Y694870D01*
G01X34599Y1592100D02*
Y1594950D01*
X34999Y1595350D01*
G01X30499Y1592110D02*
Y1594750D01*
X31099Y1595350D01*
G01X23030Y1925188D02*
Y1922038D01*
G01Y1928688D02*
X27030D01*
G01X31999Y1922300D02*
X32749Y1921550D01*
X36249D01*
G01X27030Y1925188D02*
Y1922835D01*
X26999Y1922804D01*
Y1922179D01*
X26765Y1921945D01*
G01X21749Y1940050D02*
X25499D01*
X26999Y1941550D01*
G01X21749Y1944050D02*
Y1940050D01*
G01Y1952050D02*
Y1948050D01*
G01Y1956050D02*
Y1952050D01*
G01X31999Y1975800D02*
Y1978850D01*
X31799Y1979050D01*
G01X37999Y1968750D02*
Y1970050D01*
X40299Y1972350D01*
X40411D01*
X40661Y1972600D01*
X41371D01*
X43657Y1974886D01*
X44624D01*
G01X31999Y1968300D02*
Y1972300D01*
G01D02*
X28249D01*
X26999Y1973550D01*
G01X27999Y1968300D02*
X23999D01*
G01X20799Y1972850D02*
X22450D01*
X23999Y1971301D01*
Y1968300D01*
G01X59249Y203550D02*
Y201050D01*
X60749Y199550D01*
G01X46800Y408850D02*
Y406200D01*
X45800Y405200D01*
G01X56999Y656487D02*
X55936Y657550D01*
X43499D01*
G01X53999Y786350D02*
Y791000D01*
G01X67000Y1011500D02*
X65549D01*
X59999Y1017050D01*
X59749D01*
G01X60449Y1838725D02*
Y1842550D01*
G01X49499Y1901800D02*
X43249D01*
X42499Y1902550D01*
G01X53749Y1901550D02*
X53499Y1901800D01*
X49499D01*
G01X52249Y1897050D02*
X48499D01*
G01X43999Y1968300D02*
Y1968550D01*
X45999Y1970550D01*
Y1971450D01*
G01X49999Y1972050D02*
X47999Y1974050D01*
X47926D01*
X47090Y1974886D01*
X44624D01*
G01X81249Y204550D02*
X95350D01*
G01X81249Y208550D02*
X89800D01*
G01X77499Y469550D02*
X79589Y471640D01*
X85617D01*
X85630Y471653D01*
G01X77999Y493050D02*
X79409Y491640D01*
X85617D01*
X85630Y491653D01*
G01X77499Y502550D02*
X78409Y501640D01*
X85617D01*
X85630Y501653D01*
G01X81251Y611450D02*
Y607249D01*
G01Y615450D02*
Y619251D01*
G01X78499Y654050D02*
X76774Y655775D01*
X74049D01*
G01X67999Y798950D02*
Y790400D01*
G01X77499Y921550D02*
X77166Y921883D01*
Y925236D01*
G01X77499Y962152D02*
X85617D01*
X85630Y962165D01*
G01X83849Y1004450D02*
X80699D01*
G01X83849Y1000450D02*
X80699D01*
G01X79250Y1013000D02*
X76239D01*
X75500Y1012261D01*
G01X74500Y1097550D02*
X84700D01*
X84750Y1097500D01*
G01X74399Y1111550D02*
X84700D01*
X84750Y1111500D01*
G01X78499Y1273550D02*
X79385Y1272664D01*
X85617D01*
X85630Y1272677D01*
G01X78613Y1282664D02*
X85617D01*
X85630Y1282677D01*
G01X78779Y1312664D02*
X85617D01*
X85630Y1312677D01*
G01X78779Y1302664D02*
X85617D01*
X85630Y1302677D01*
G01X86165Y1339050D02*
X83999D01*
X82865Y1340184D01*
X77179D01*
X77166Y1340197D01*
G01X77165Y1327335D02*
X77166Y1327336D01*
Y1330748D01*
G01Y1349646D02*
Y1353400D01*
G01X85630Y1688189D02*
X78100D01*
G01X77165Y1759550D02*
X77166Y1759549D01*
Y1755158D01*
G01X78529Y1788113D02*
X78605Y1788189D01*
X85630D01*
G01X77249Y1837550D02*
X79999D01*
X80999Y1836550D01*
G01X92900Y66128D02*
X85643D01*
X85630Y66141D01*
G01X93999Y58550D02*
X91577Y56128D01*
X85643D01*
X85630Y56141D01*
G01X92999Y86128D02*
X85643D01*
X85630Y86141D01*
G01X92999Y96128D02*
X85643D01*
X85630Y96141D01*
G01X95814Y136065D02*
X95738Y136141D01*
X85630D01*
G01X96184Y151065D02*
X96108Y151141D01*
X85630D01*
G01X96184Y166065D02*
X96108Y166141D01*
X85630D01*
G01X92499Y876550D02*
X91897Y877152D01*
X85643D01*
X85630Y877165D01*
G01X92999Y868550D02*
X91601Y867152D01*
X85629D01*
X85630Y867153D01*
Y867165D01*
G01X93499Y897152D02*
X85643D01*
X85630Y897165D01*
G01X93000Y907165D02*
X85630D01*
G01X84750Y1008500D02*
X88000D01*
G01X97849Y1081700D02*
Y1077400D01*
G01D02*
Y1076200D01*
X101499Y1072550D01*
G01X102999Y1182550D02*
Y1188050D01*
G01X102900Y1196050D02*
X103186D01*
X105499Y1198363D01*
G01X106999Y1223863D02*
X103686D01*
G01X106939Y1216863D02*
X103999D01*
G01X103499Y1301363D02*
Y1305050D01*
G01X93316Y1351000D02*
X91652Y1352664D01*
X85643D01*
X85630Y1352677D01*
G01X96000Y1369000D02*
X95500D01*
X94200Y1367700D01*
X85653D01*
X85630Y1367677D01*
G01X103999Y1468550D02*
X103199D01*
X100699Y1471050D01*
G01X98599Y1491350D02*
X100299Y1493050D01*
X119199D01*
X122799Y1489450D01*
Y1485300D01*
G01X100499Y1476050D02*
Y1479650D01*
G01X92900Y1678176D02*
X85643D01*
X85630Y1678189D01*
G01X92479Y1718176D02*
X85643D01*
X85630Y1718189D01*
G01X92873Y1708176D02*
X85643D01*
X85630Y1708189D01*
G01X93499Y1759550D02*
X92138Y1758189D01*
X85630D01*
G01X94336Y1773113D02*
X94260Y1773189D01*
X85630D01*
G01X85999Y1828613D02*
X89287D01*
X90000Y1827900D01*
G01X93500D02*
X93201Y1828199D01*
Y1830099D01*
X90800Y1832500D01*
G01D02*
X86112D01*
X85999Y1832613D01*
G01X122499Y427900D02*
Y432349D01*
X123750Y433600D01*
G01X109000Y967901D02*
Y964400D01*
X108200Y963600D01*
G01X109000Y967901D02*
X108949Y967850D01*
G01X109000Y972000D02*
Y967901D01*
G01X109439Y1085800D02*
X105999D01*
G01X114559Y1079300D02*
X117499D01*
G01X116249Y1099110D02*
Y1102550D01*
G01X112999Y1103740D02*
Y1104050D01*
X113499Y1104550D01*
Y1106640D01*
G01X109499Y1198363D02*
Y1197050D01*
X106999Y1194550D01*
G01X111999Y1182550D02*
Y1188050D01*
G01X120999Y1182550D02*
Y1188050D01*
G01X112059Y1210363D02*
X114999D01*
G01X118999Y1219050D02*
X122922D01*
X123299Y1218673D01*
G01X114939Y1311800D02*
X111499D01*
G01X116499Y1324863D02*
Y1328013D01*
G01X120507Y1324946D02*
Y1328096D01*
G01X123500Y1360300D02*
X121700D01*
X119749Y1358349D01*
Y1356050D01*
G01X128250Y1365000D02*
X127250Y1366000D01*
X125100D01*
G01X111499Y1468550D02*
X115549D01*
X115599Y1468500D01*
G01D02*
Y1463050D01*
X106999Y1454450D01*
G01X107999Y1476050D02*
Y1462050D01*
X105099Y1459150D01*
G01X122799Y1485300D02*
X118549D01*
G01X117499Y1702613D02*
Y1706050D01*
G01X105749Y1720613D02*
Y1716613D01*
G01X104999Y1705613D02*
Y1708963D01*
G01X143110Y203861D02*
X143186Y203937D01*
X150591D01*
G01X142688Y218861D02*
X142764Y218937D01*
X150591D01*
G01X138999Y520863D02*
Y524213D01*
G01X141500Y711000D02*
X143064Y709436D01*
X150578D01*
X150591Y709449D01*
G01X140864Y1044885D02*
X140927Y1044948D01*
X150578D01*
X150591Y1044961D01*
G01X141234Y1029885D02*
X141297Y1029948D01*
X150578D01*
X150591Y1029961D01*
G01X128230Y1098482D02*
X130067D01*
X132499Y1096050D01*
Y1094550D01*
G01X128230Y1094482D02*
Y1093730D01*
X125900Y1091400D01*
Y1091282D01*
G01X130699Y1213553D02*
Y1210653D01*
G01X125999Y1311613D02*
Y1315550D01*
G01X132999Y1319550D02*
Y1310363D01*
G01X142667Y1319218D02*
Y1310010D01*
G01X142150Y1335800D02*
X143700Y1334250D01*
Y1332500D01*
G01X133475Y1326750D02*
Y1331200D01*
G01X129000Y1356500D02*
X129500D01*
X131750Y1358750D01*
Y1361000D01*
G01X140799Y1435460D02*
X150578D01*
X150591Y1435473D01*
G01X133999Y1670613D02*
X126562D01*
G01X135999Y1703300D02*
Y1702725D01*
X133233Y1699959D01*
X133090D01*
G01X131999Y1703300D02*
X128749D01*
G01X143490Y1855972D02*
X150578D01*
X150591Y1855985D01*
G01X142499Y1905972D02*
X150578D01*
X150591Y1905985D01*
G01X141499Y1895972D02*
X150578D01*
X150591Y1895985D01*
G01X154200Y168500D02*
Y165599D01*
X154749Y165050D01*
G01X149400Y166400D02*
Y163100D01*
X151450Y161050D01*
X154749D01*
G01X158999Y259800D02*
Y255922D01*
X159055Y255866D01*
G01X157440Y283924D02*
X150604D01*
X150591Y283937D01*
G01X157740Y273924D02*
X150604D01*
X150591Y273937D01*
G01X157440Y303924D02*
X150604D01*
X150591Y303937D01*
G01X157440Y313924D02*
X150604D01*
X150591Y313937D01*
G01X165699Y433053D02*
Y428050D01*
G01X154101Y445550D02*
X158299Y441352D01*
Y438173D01*
G01X151749Y517613D02*
Y520249D01*
X152000Y520500D01*
Y520813D01*
G01X167199Y517100D02*
X163549D01*
G01D02*
X159199D01*
G01X163449Y524850D02*
Y521650D01*
G01X155949Y524850D02*
Y527386D01*
X154099Y529236D01*
G01X147250Y545000D02*
X150500D01*
G01X154249Y570050D02*
Y571149D01*
X156951Y573851D01*
X157000D01*
G01X154249Y566050D02*
X153722D01*
X151049Y568723D01*
Y572475D01*
X155625Y577051D01*
X160500D01*
X160551Y577000D01*
X160824D01*
G01X159054Y665400D02*
X159055Y665399D01*
Y661378D01*
G01X158885Y679436D02*
X150604D01*
X150591Y679449D01*
G01X158885Y689436D02*
X150604D01*
X150591Y689449D01*
G01X158385Y719436D02*
X150604D01*
X150591Y719449D01*
G01X159500Y818250D02*
Y814700D01*
G01X161999Y919363D02*
Y921250D01*
X160399Y922850D01*
G01X154749Y975550D02*
Y979149D01*
G01Y971550D02*
Y968249D01*
G01X158300Y1015000D02*
X158248Y1014948D01*
X150604D01*
X150591Y1014961D01*
G01X159499Y1044579D02*
X159055Y1045023D01*
Y1047992D01*
G01Y1066890D02*
Y1070400D01*
G01X165600Y1057428D02*
X159068D01*
X159055Y1057441D01*
G01X149562Y1311550D02*
Y1315987D01*
G01X157915Y1420460D02*
X150604D01*
X150591Y1420473D01*
G01X150338Y1453958D02*
X150590Y1453706D01*
Y1450474D01*
X150591Y1450473D01*
G01X165575Y1682050D02*
Y1676975D01*
G01X151499Y1660887D02*
Y1673550D01*
G01X154721Y1786909D02*
Y1787897D01*
X157024Y1790200D01*
X165600D01*
X165900Y1790500D01*
G01X161900Y1793400D02*
X155698D01*
X151521Y1789223D01*
Y1784579D01*
X153191Y1782909D01*
X154721D01*
G01X157999Y1840972D02*
X150604D01*
X150591Y1840985D01*
G01X159054Y1855050D02*
X158900Y1855204D01*
Y1858861D01*
X159055Y1859016D01*
G01X159421Y1925972D02*
X150604D01*
X150591Y1925985D01*
G01X159173Y1935972D02*
X150604D01*
X150591Y1935985D01*
G01X179376Y82428D02*
X175999D01*
G01X174999Y74800D02*
Y79050D01*
G01X182922Y90572D02*
Y86572D01*
G01X169999Y90550D02*
X170021Y90572D01*
G01D02*
X179422D01*
G01Y86572D02*
X175499D01*
G01X178999Y74800D02*
Y79050D01*
G01X179999Y95050D02*
X179821Y94872D01*
X176399D01*
G01X182499Y74800D02*
X185589D01*
X187024Y76235D01*
G01X182876Y82428D02*
X185299Y80005D01*
Y78431D01*
X187024Y76706D01*
Y76235D01*
G01X183249Y99050D02*
X186999D01*
G01X185499Y120800D02*
X188999D01*
G01X173500Y166315D02*
X173715Y166100D01*
X175949D01*
X176749Y165300D01*
Y165050D01*
G01X171722Y513827D02*
X171864D01*
X172999Y514962D01*
Y515900D01*
X174199Y517100D01*
G01D02*
X175137D01*
X178449Y520412D01*
Y524850D01*
G01D02*
Y529000D01*
X174099Y533350D01*
G01X170949Y524850D02*
Y525453D01*
X168453Y527949D01*
G01X172500Y919294D02*
X174749Y917045D01*
Y916113D01*
G01X180350Y931600D02*
X172000D01*
G01X181000Y1365500D02*
X184600Y1369100D01*
Y1373050D01*
G01X180500D02*
Y1369900D01*
G01X174250Y1691200D02*
Y1694500D01*
G01X177314Y1786613D02*
Y1787865D01*
X186499Y1797050D01*
X297499D01*
G01X201499Y101300D02*
Y104550D01*
G01X197499Y97800D02*
X196472D01*
X194299Y99973D01*
Y111126D01*
X199436Y116263D01*
X236786D01*
X248699Y104350D01*
Y98850D01*
X245399Y95550D01*
X241749D01*
G01X205499Y101300D02*
Y105550D01*
G01X233749Y110800D02*
X231486Y113063D01*
X200762D01*
X197499Y109800D01*
Y101300D01*
G01X209499D02*
Y108050D01*
X207999Y109550D01*
G01X193549Y165075D02*
X197899D01*
G01X193549Y572275D02*
Y575875D01*
G01X191499Y884113D02*
X198499D01*
G01X209999Y901763D02*
X205999D01*
G01X193549Y975975D02*
X198924D01*
G01X208049Y1380675D02*
Y1385550D01*
G01X194700Y1385700D02*
X194200D01*
X191249Y1382749D01*
Y1381050D01*
G01X194049Y1786375D02*
Y1792600D01*
G01X213499Y101300D02*
Y104650D01*
G01X217499Y101300D02*
X219249D01*
X223499Y105550D01*
Y108150D01*
G01X216998Y283864D02*
X213499D01*
G01X242000Y287114D02*
X229748D01*
G01X218998Y318114D02*
X214063D01*
G01X225900Y318400D02*
X225914Y318414D01*
X231800D01*
G01X216999Y690300D02*
Y686550D01*
G01X227025Y683750D02*
Y678176D01*
X226399Y677550D01*
G01X241400Y693550D02*
X236452D01*
X236450Y693552D01*
X232550D01*
X232548Y693550D01*
X229749D01*
G01X218499Y725050D02*
X213999D01*
G01X225499Y726050D02*
X230849D01*
G01X221299Y760550D02*
Y762250D01*
X218224Y765325D01*
G01X209999Y901763D02*
X210871D01*
X212599Y900035D01*
Y899401D01*
X215050Y896950D01*
G01D02*
X215900D01*
G01X222900Y1086550D02*
Y1085900D01*
X221300Y1084300D01*
Y1083238D01*
G01X226800Y1090050D02*
Y1093400D01*
G01X224750Y1480100D02*
Y1483950D01*
G01X225499Y1502800D02*
X249400D01*
X251000Y1504400D01*
G01X228825Y1493450D02*
X232650D01*
G01X223436Y1893615D02*
Y1890465D01*
G01X231000Y1883950D02*
Y1886300D01*
X231800Y1887100D01*
G01X218814Y1926113D02*
X213562D01*
G01X225814Y1931113D02*
X220062D01*
G01X235499Y81300D02*
X240049D01*
X240999Y82250D01*
G01X246499Y80550D02*
X242699D01*
X240999Y82250D01*
G01X246499Y86050D02*
X242699Y82250D01*
X240999D01*
G01X242499Y76550D02*
X247614D01*
X250114Y79050D01*
Y88435D01*
X248699Y89850D01*
X240999D01*
G01X233749Y105050D02*
Y110800D01*
G01X237399Y102050D02*
Y106550D01*
X237899Y107050D01*
G01X233749Y97050D02*
Y101050D01*
G01D02*
X236399D01*
X237399Y102050D01*
G01X244050Y269700D02*
X247800D01*
G01X327499Y320050D02*
Y304550D01*
X310063Y287114D01*
X242000D01*
G01X246498Y319114D02*
X252935D01*
G01X243450Y677100D02*
X246800D01*
G01X238500Y680800D02*
X238800D01*
X240500Y682500D01*
X241440D01*
G01X324999Y727550D02*
Y712050D01*
X306499Y693550D01*
X241400D01*
G01X246499Y726050D02*
X252499D01*
G01X247500Y1082000D02*
Y1085500D01*
G01X325499Y1538550D02*
Y1511300D01*
X317499Y1503300D01*
X267100D01*
X263500Y1506900D01*
X253500D01*
X251000Y1504400D01*
G01X232314Y1893863D02*
Y1890513D01*
G01X236225Y1887950D02*
Y1883125D01*
G01X246314Y1934113D02*
X240964D01*
G01X260200Y1527000D02*
Y1532600D01*
X258800Y1534000D01*
G01X287664Y328715D02*
Y343885D01*
X286249Y345300D01*
X284999D01*
G01X280499D02*
X284999D01*
G01X288999Y733550D02*
X289799Y734350D01*
G01D02*
Y750750D01*
X288749Y751800D01*
X285499D01*
G01X279939Y740300D02*
X277039D01*
G01X281499Y751800D02*
X285499D01*
G01X286799Y1546350D02*
Y1561750D01*
X285749Y1562800D01*
X282499D01*
G01X278499D02*
X282499D01*
G01X292999Y1945550D02*
X291886Y1946663D01*
Y1953663D01*
X290471Y1955078D01*
X288358D01*
G01X284358D02*
X288358D01*
G01X305749Y86613D02*
X306621D01*
X307058Y87050D01*
X308999D01*
G01X295500Y332750D02*
X295750Y333000D01*
X298800D01*
G01X308999Y716450D02*
Y724800D01*
G01X298000Y739250D02*
Y743500D01*
G01X334999Y1797050D02*
X297499D01*
G01X313499Y1924550D02*
Y1919050D01*
G01X296858Y1956228D02*
Y1947578D01*
G01X352999Y70050D02*
X336377D01*
X334249Y67922D01*
Y67050D01*
G01Y63050D02*
Y67050D01*
G01X319650Y105200D02*
X323400D01*
G01X328999Y321550D02*
X327499Y320050D01*
G01X316999Y317050D02*
Y312576D01*
G01X325499Y728050D02*
X324999Y727550D01*
G01X315999Y722550D02*
Y718950D01*
G01X334749Y737800D02*
Y741050D01*
G01D02*
Y745050D01*
G01X323249Y746110D02*
Y749010D01*
G01X322059Y766750D02*
X324959D01*
G01X331249Y1553550D02*
Y1557550D01*
G01Y1553550D02*
Y1549300D01*
G01D02*
X328999Y1547050D01*
X327999D01*
G01X321059Y1577250D02*
X323999D01*
G01X710549Y1797884D02*
Y1785449D01*
X705500Y1780400D01*
X535864D01*
X521494Y1766030D01*
X326301D01*
G01X320640Y1927272D02*
X325221D01*
G01X342463Y-139897D02*
Y-219897D01*
G01X339471Y1947409D02*
X342999D01*
G01X339471Y1943409D02*
X342621D01*
G01X375249Y53050D02*
Y57050D01*
G01X479963Y-139897D02*
Y-219897D01*
G01X544300Y1784638D02*
X639799D01*
X644049Y1788888D01*
Y1792884D01*
G01X594963Y-139897D02*
Y-219897D01*
G01X651799Y1803634D02*
X655299D01*
X655549Y1803884D01*
G01X651799Y1796134D02*
X655299D01*
X655549Y1796384D01*
G01X644049Y1803884D02*
X640049D01*
G01X648299Y1803634D02*
X648049Y1803884D01*
X644049D01*
G01X640049D02*
X638799D01*
X637965Y1803050D01*
X634999D01*
G01X644049Y1796384D02*
X640049D01*
G01X648299Y1796134D02*
X644299D01*
X644049Y1796384D01*
G01X640049D02*
X634850D01*
X633931Y1795465D01*
G01X640049Y1807384D02*
X633837D01*
G01X649049Y1814384D02*
X646799D01*
X646049Y1815134D01*
X645549D01*
G01X647799Y1818634D02*
X647296Y1819137D01*
X644360D01*
G01X660519Y1806887D02*
X659949Y1806317D01*
Y1803670D01*
G01X655549Y1803884D02*
X655763Y1803670D01*
X659949D01*
G01X669001Y1801888D02*
X664549Y1797436D01*
G01X655549Y1796384D02*
X663497D01*
X664549Y1797436D01*
G01X655549Y1815384D02*
X659549D01*
G01X682549Y1803634D02*
Y1802134D01*
X685549Y1799134D01*
G01X697299Y1801634D02*
X697049Y1801884D01*
X693549D01*
G01D02*
X693249Y1801584D01*
X692222D01*
X689772Y1799134D01*
X685549D01*
G01X693549Y1809384D02*
X690451D01*
X689731Y1808664D01*
G01X693549Y1813384D02*
X689299D01*
X688499Y1812584D01*
X688473D01*
X687536Y1811647D01*
G01X697799Y1813134D02*
X697549Y1813384D01*
X693549D01*
G01X697299Y1808634D02*
X696549Y1809384D01*
X693549D01*
G01X708549Y1808584D02*
X712549D01*
G01X700799Y1808634D02*
X708499D01*
X708549Y1808584D01*
G01X712549D02*
X720000D01*
X720300Y1808884D01*
G01X710549Y1801384D02*
X713799D01*
X715549Y1799634D01*
G01X706549Y1801384D02*
X710549D01*
G01X700799Y1801634D02*
X706299D01*
X706549Y1801384D01*
G01X717564Y1804045D02*
X716676Y1804933D01*
X699973D01*
X697299Y1807607D01*
Y1808634D01*
G01X707600Y1815600D02*
X705000D01*
X704400Y1816200D01*
X699300D01*
X697799Y1814699D01*
Y1813134D01*
G01X717000Y1812384D02*
X716700Y1812084D01*
X712549D01*
G01X736299Y1806634D02*
X732549D01*
G01X736299Y1798634D02*
X733149D01*
G01X736299Y1814134D02*
X733049D01*
G01X751499Y679148D02*
X754401Y682050D01*
X820600D01*
G01X757499Y1079550D02*
X811623D01*
X814073Y1082000D01*
X814600D01*
X816000Y1083400D01*
G01X822100Y1490900D02*
X809400D01*
X802550Y1484050D01*
X757999D01*
G01X753949Y1801294D02*
Y1798194D01*
G01X744049Y1802884D02*
X740799D01*
X740549Y1802634D01*
G01X744049Y1810384D02*
X740549D01*
G01X758499Y1893550D02*
X759949Y1895000D01*
X817386D01*
G01X762463Y-139897D02*
Y-219897D01*
G01X760778Y341984D02*
Y345050D01*
G01X768178Y336864D02*
Y333964D01*
G01D02*
X767728Y333514D01*
Y328984D01*
G01X783049Y1813634D02*
X779149D01*
X776149Y1810634D01*
Y1808974D01*
G01X792999Y315550D02*
X796499D01*
X800749Y319800D01*
Y332050D01*
G01Y336050D02*
Y332050D01*
G01X795499Y719050D02*
X799249Y722800D01*
Y732050D01*
G01Y736050D02*
Y732050D01*
G01X792999Y1116050D02*
Y1124550D01*
X799249Y1130800D01*
Y1133050D01*
G01D02*
Y1137050D01*
G01X793499Y1525050D02*
X796931D01*
X801931Y1530050D01*
Y1538893D01*
G01D02*
Y1542893D01*
G01X787693Y1535628D02*
X784577D01*
G01X800431Y1948393D02*
Y1949482D01*
X802499Y1951550D01*
G01X800431Y1944393D02*
Y1941193D01*
G01X844446Y681882D02*
X844278Y682050D01*
X820600D01*
G01X844083Y1087392D02*
X819992D01*
X816000Y1083400D01*
G01X815400Y1078800D02*
Y1078400D01*
X812900Y1075900D01*
Y1075460D01*
G01X846077Y1492296D02*
X844681Y1490900D01*
X822100D01*
G01X821249Y1788050D02*
Y1791250D01*
G01X846564Y1898113D02*
X845551Y1897100D01*
X819486D01*
X817386Y1895000D01*
G01X835999Y160050D02*
X835749Y160300D01*
G01D02*
Y167550D01*
G01X839249D02*
Y164050D01*
G01X845728Y280924D02*
X842499D01*
G01X827500Y270950D02*
Y274500D01*
G01X826100Y666650D02*
X829800D01*
G01X825700Y1079250D02*
Y1083100D01*
G01X827700Y1484150D02*
Y1487600D01*
G01X833025Y1486550D02*
X835775D01*
X836625Y1487400D01*
G01X837499Y1780050D02*
Y1785773D01*
X836249Y1787023D01*
Y1788050D01*
G01X828749D02*
X827999Y1788800D01*
Y1791550D01*
G01X828500Y1877800D02*
Y1880750D01*
X828000Y1881250D01*
G01X862500Y1736700D02*
X867200Y1741400D01*
X890800D01*
X899500Y1732700D01*
Y1720700D01*
G01X871478Y163924D02*
X867500D01*
G01X871478Y159924D02*
X867576D01*
G01X871786Y218924D02*
X878924D01*
X878937Y218937D01*
G01X883249Y570550D02*
X879750D01*
G01X883249Y565050D02*
X879950D01*
G01X870773Y624705D02*
X871029Y624449D01*
X878937D01*
G01X870719Y609705D02*
X870975Y609449D01*
X878937D01*
G01X883083Y975892D02*
Y979183D01*
G01Y971892D02*
X879708D01*
G01X870468Y1030227D02*
X870747Y1029948D01*
X878924D01*
X878937Y1029961D01*
G01X872086Y1084948D02*
X878924D01*
X878937Y1084961D01*
G01X871999Y1094948D02*
X878924D01*
X878937Y1094961D01*
G01X873249Y1359550D02*
Y1356800D01*
X873499Y1356550D01*
Y1356050D01*
G01X870077Y1379796D02*
X866700D01*
G01X870077Y1375796D02*
X866596D01*
G01X871836Y1420460D02*
X878924D01*
X878937Y1420473D01*
G01X871836Y1435460D02*
X878924D01*
X878937Y1435473D01*
G01X871836Y1450460D02*
X878924D01*
X878937Y1450473D01*
G01X886913Y1449010D02*
X887400Y1449497D01*
Y1453453D01*
X887401Y1453454D01*
Y1453504D01*
G01X872086Y1490460D02*
X878924D01*
X878937Y1490473D01*
G01X871999Y1500460D02*
X878924D01*
X878937Y1500473D01*
G01X872086Y1530460D02*
X878924D01*
X878937Y1530473D01*
G01X871999Y1520460D02*
X878924D01*
X878937Y1520473D01*
G01X871100Y1690300D02*
Y1692100D01*
X876000Y1697000D01*
Y1703899D01*
G01X885851Y1720950D02*
Y1718188D01*
X886439Y1717600D01*
G01X885851Y1720950D02*
X881851D01*
G01X886439Y1717600D02*
Y1715638D01*
X885300Y1714499D01*
X883500D01*
G01X876000Y1703899D02*
X873201D01*
X870201Y1706899D01*
Y1709900D01*
G01X879700Y1786300D02*
X882850D01*
G01X882814Y1782213D02*
X879664D01*
G01X871836Y1840972D02*
X871849Y1840985D01*
X878937D01*
G01X900499Y88300D02*
X899749D01*
X897555Y90494D01*
G01X902249Y103050D02*
X894999D01*
G01X902249Y107050D02*
X902499Y107300D01*
Y110550D01*
G01X900499Y115050D02*
X898999Y113550D01*
Y110550D01*
G01X905749Y107050D02*
Y103050D01*
G01X903499Y131800D02*
X907499D01*
G01X907249Y124550D02*
X910999D01*
G01X905196Y570882D02*
Y572156D01*
X903999Y573353D01*
Y574378D01*
G01X905083Y974392D02*
Y974966D01*
X900999Y979050D01*
G01X894800Y1710000D02*
X895800Y1711000D01*
Y1715600D01*
X896400Y1716200D01*
G01D02*
X899500Y1719300D01*
Y1720700D01*
G01X889800Y1711500D02*
Y1715600D01*
X890400Y1716200D01*
G01X889700Y1708150D02*
X889800Y1708250D01*
Y1711500D01*
G01X904814Y1785613D02*
Y1789113D01*
G01X916499Y111800D02*
Y115050D01*
G01X912499Y111800D02*
Y115550D01*
X922499Y125550D01*
X934499D01*
X937999Y122050D01*
G01X920499Y111800D02*
Y118050D01*
X924499Y122050D01*
X926999D01*
G01X916499Y108300D02*
X920499D01*
G01D02*
Y103550D01*
X920999Y103050D01*
G01X934499Y118750D02*
X926199D01*
X923999Y116550D01*
Y112300D01*
X924499Y111800D01*
G01X932499Y108300D02*
X928499D01*
G01D02*
X924499D01*
G01X928499Y111800D02*
Y113550D01*
X926999Y115050D01*
G01X916499Y172550D02*
X922249D01*
G01X922049Y570775D02*
Y574375D01*
G01X921549Y1784875D02*
Y1788475D01*
G01X932463Y-139897D02*
Y-219897D01*
G01X932499Y111800D02*
Y113524D01*
X932298Y113725D01*
Y114772D01*
X931520Y115550D01*
X930999D01*
G01X936499Y111800D02*
Y114550D01*
X937499Y115550D01*
X938499D01*
G01X948499Y111800D02*
X952499D01*
G01X946999Y115450D02*
X944377D01*
X941077Y118750D01*
X934499D01*
G01X940499Y111800D02*
X944499D01*
G01D02*
Y112950D01*
X946999Y115450D01*
G01Y119650D02*
X946899Y119750D01*
Y122550D01*
G01X939549Y171575D02*
Y175175D01*
G01X952499Y111800D02*
X954499Y113800D01*
Y116550D01*
G01X990425Y1633898D02*
Y1633575D01*
X992898Y1631102D01*
X1005807D01*
G01X987029Y1634075D02*
X987000Y1634046D01*
Y1630900D01*
X991798Y1626102D01*
X1005807D01*
G01X989502Y1646000D02*
X992000D01*
X992102Y1646102D01*
X1005807D01*
G01X987200Y1675600D02*
X992300D01*
X992802Y1676102D01*
X1005807D01*
G01X1129963Y-139897D02*
Y-219897D01*
G01X1157963Y-123897D02*
G02I-12000J0D01*
G01X1152813D02*
G02I-6850J0D01*
G01X1161963D02*
X1129963D01*
G01X1145963Y-139897D02*
Y-107897D01*
G54D77*
X231500Y269350D03*
X227625Y276850D03*
X230900Y676250D03*
X227025Y683750D03*
X228825Y1493450D03*
X235375Y276850D03*
X234775Y683750D03*
X232700Y1485950D03*
X236575Y1493450D03*
X240100Y1880450D03*
X243975Y1887950D03*
X236225D03*
X836700Y267450D03*
X840575Y274950D03*
X832825D03*
X835300Y670150D03*
X839175Y677650D03*
X831425D03*
X835000Y1075750D03*
X838875Y1083250D03*
X831125D03*
X836900Y1479050D03*
X840775Y1486550D03*
X833025D03*
X837499Y1884800D03*
X841374Y1892300D03*
X833624D03*
G54D68*
X128099Y1598150D03*
X135699D03*
X232199Y33550D03*
Y42550D03*
Y51550D03*
Y69550D03*
Y60550D03*
X239799Y33550D03*
Y42550D03*
Y51550D03*
Y69550D03*
Y60550D03*
X951199Y46050D03*
Y55050D03*
Y64050D03*
Y73050D03*
Y82050D03*
X949199Y101550D03*
X958799Y46050D03*
Y55050D03*
Y64050D03*
Y73050D03*
Y82050D03*
X956799Y101550D03*
G54D86*
X825300Y1726200D03*
X836300D03*
X888200Y1727300D03*
X877200D03*
X940400Y1486900D03*
X951400D03*
X940500Y1477500D03*
X951500D03*
G54D59*
X125725Y1326750D03*
X145000Y539050D03*
X141125Y531550D03*
X129600Y1334250D03*
X133475Y1326750D03*
X148875Y531550D03*
X157825Y1682050D03*
X165575D03*
X161700Y1689550D03*
X180025Y918250D03*
X187775D03*
X183900Y925750D03*
X307000Y105150D03*
X303125Y97650D03*
X310875D03*
G54D96*
G01X105749Y1716613D02*
Y1712749D01*
G01X832825Y274950D02*
X836500D01*
G01X1005807Y1621102D02*
X955098D01*
X950100Y1626100D01*
G54D87*
X854101Y1710351D03*
Y1733149D03*
G54D69*
X133912Y1694600D03*
X160312Y485500D03*
X190912Y910700D03*
X322212Y79500D03*
X829788Y285000D03*
X827988Y688200D03*
X828188Y1093700D03*
X829988Y1496200D03*
X829112Y1734500D03*
X830188Y1902900D03*
G54D78*
X242299Y76550D03*
X958299Y89550D03*
G54D97*
G01X31999Y1918800D02*
X29059D01*
X28799Y1919060D01*
G01X174099Y533350D02*
X174024Y533275D01*
G01X666399Y1808664D02*
X662296D01*
X660519Y1806887D01*
G01X666399Y1806699D02*
X669984D01*
X671050Y1805633D01*
Y1803937D01*
X669001Y1801888D01*
G01X666399Y1810634D02*
X659549D01*
G01X682699Y1806699D02*
Y1803784D01*
X682549Y1803634D01*
G01X689731Y1808664D02*
X682699D01*
G01X687536Y1811647D02*
X686523Y1810634D01*
X682699D01*
G54D88*
X876000Y1703899D03*
X879750D03*
X883500D03*
Y1714499D03*
X879750D03*
X876000D03*
G54D79*
X236699Y76550D03*
X952699Y89550D03*
G54D98*
G01X60749Y199550D02*
X97499D01*
X97999Y199050D01*
G01X800890Y1780148D02*
X804076Y1783334D01*
Y1808873D01*
X799315Y1813634D01*
X788049D01*
G01D02*
X783049D01*
G54D89*
X878200Y1734200D03*
G54D99*
G01X118549Y1485300D02*
X118217Y1484968D01*
X116058D01*
X116045Y1484981D01*
G01X163877Y549468D02*
X160932D01*
G01X174024Y533275D02*
X171570D01*
X171557Y533288D01*
G01X241599Y102050D02*
X243999D01*
X245499Y100550D01*
G01X822499Y1815164D02*
X822512Y1815177D01*
X825333D01*
G01X833013Y1798997D02*
X833012Y1798996D01*
Y1792587D01*
X836249Y1789350D01*
Y1788050D01*
M02*
